G04 ================== begin FILE IDENTIFICATION RECORD ==================*
G04 Layout Name:  13130-1b.brd*
G04 Film Name:    BSMD*
G04 File Format:  Gerber RS274X*
G04 File Origin:  Cadence Allegro 16.5-S037*
G04 Origin Date:  Thu Nov 13 17:26:15 2014*
G04 *
G04 Layer:  VIA CLASS/PASTEMASK_BOTTOM*
G04 Layer:  PIN/PASTEMASK_BOTTOM*
G04 Layer:  PACKAGE GEOMETRY/PASTEMASK_BOTTOM*
G04 Layer:  DRAWING FORMAT/LAYER_PCB_STORY*
G04 Layer:  DRAWING FORMAT/LAYER_PAST_B*
G04 Layer:  BOARD GEOMETRY/PANEL_OUTLINE*
G04 *
G04 Offset:    (0.00 0.00)*
G04 Mirror:    No*
G04 Mode:      Positive*
G04 Rotation:  0*
G04 FullContactRelief:  No*
G04 UndefLineWidth:     6.00*
G04 ================== end FILE IDENTIFICATION RECORD ====================*
%FSLAX35Y35*MOIN*%
%IR0*IPPOS*OFA0.00000B0.00000*MIA0B0*SFA1.00000B1.00000*%
%AMMACRO27*
4,1,40,.008,.009,
-.008,.009,
-.008347,.00897,
-.008684,.008879,
-.009,.008732,
-.009286,.008532,
-.009532,.008286,
-.009732,.008,
-.009879,.007684,
-.00997,.007347,
-.01,.007,
-.01,-.007,
-.00997,-.007347,
-.009879,-.007684,
-.009732,-.008,
-.009532,-.008286,
-.009286,-.008532,
-.009,-.008732,
-.008684,-.008879,
-.008347,-.00897,
-.008,-.009,
.008,-.009,
.008347,-.00897,
.008684,-.008879,
.009,-.008732,
.009286,-.008532,
.009532,-.008286,
.009732,-.008,
.009879,-.007684,
.00997,-.007347,
.01,-.007,
.01,.007,
.00997,.007347,
.009879,.007684,
.009732,.008,
.009532,.008286,
.009286,.008532,
.009,.008732,
.008684,.008879,
.008347,.00897,
.008,.009,
0.0*
%
%ADD27MACRO27*%
%AMMACRO50*
4,1,3,-.025,.0125,
0.0,-.0125,
.025,.0125,
-.025,.0125,
0.0*
%
%ADD50MACRO50*%
%AMMACRO63*
4,1,3,.0125,0.0,
-.0125,.025,
-.0125,-.025,
.0125,0.0,
0.0*
%
%ADD63MACRO63*%
%AMMACRO17*
4,1,40,-.009,.01,
.009,.01,
.009347,.00997,
.009684,.009879,
.01,.009732,
.010286,.009532,
.010532,.009286,
.010732,.009,
.010879,.008684,
.01097,.008347,
.011,.008,
.011,-.008,
.01097,-.008347,
.010879,-.008684,
.010732,-.009,
.010532,-.009286,
.010286,-.009532,
.01,-.009732,
.009684,-.009879,
.009347,-.00997,
.009,-.01,
-.009,-.01,
-.009347,-.00997,
-.009684,-.009879,
-.01,-.009732,
-.010286,-.009532,
-.010532,-.009286,
-.010732,-.009,
-.010879,-.008684,
-.01097,-.008347,
-.011,-.008,
-.011,.008,
-.01097,.008347,
-.010879,.008684,
-.010732,.009,
-.010532,.009286,
-.010286,.009532,
-.01,.009732,
-.009684,.009879,
-.009347,.00997,
-.009,.01,
0.0*
%
%ADD17MACRO17*%
%ADD11C,.04*%
%ADD46R,.126X.091*%
%AMMACRO18*
4,1,40,.01,.009,
.01,-.009,
.00997,-.009347,
.009879,-.009684,
.009732,-.01,
.009532,-.010286,
.009286,-.010532,
.009,-.010732,
.008684,-.010879,
.008347,-.01097,
.008,-.011,
-.008,-.011,
-.008347,-.01097,
-.008684,-.010879,
-.009,-.010732,
-.009286,-.010532,
-.009532,-.010286,
-.009732,-.01,
-.009879,-.009684,
-.00997,-.009347,
-.01,-.009,
-.01,.009,
-.00997,.009347,
-.009879,.009684,
-.009732,.01,
-.009532,.010286,
-.009286,.010532,
-.009,.010732,
-.008684,.010879,
-.008347,.01097,
-.008,.011,
.008,.011,
.008347,.01097,
.008684,.010879,
.009,.010732,
.009286,.010532,
.009532,.010286,
.009732,.01,
.009879,.009684,
.00997,.009347,
.01,.009,
0.0*
%
%ADD18MACRO18*%
%ADD84R,.047X.108*%
%ADD22R,.108X.047*%
%ADD41R,.008X.035*%
%ADD39R,.035X.008*%
%ADD40R,.008X.027*%
%ADD38R,.027X.008*%
%AMMACRO30*
4,1,40,-.0155,-.016,
-.0155,.016,
-.015439,.016695,
-.015259,.017368,
-.014964,.018,
-.014564,.018571,
-.014071,.019064,
-.0135,.019464,
-.012868,.019759,
-.012195,.019939,
-.0115,.02,
.0115,.02,
.012195,.019939,
.012868,.019759,
.0135,.019464,
.014071,.019064,
.014564,.018571,
.014964,.018,
.015259,.017368,
.015439,.016695,
.0155,.016,
.0155,-.016,
.015439,-.016695,
.015259,-.017368,
.014964,-.018,
.014564,-.018571,
.014071,-.019064,
.0135,-.019464,
.012868,-.019759,
.012195,-.019939,
.0115,-.02,
-.0115,-.02,
-.012195,-.019939,
-.012868,-.019759,
-.0135,-.019464,
-.014071,-.019064,
-.014564,-.018571,
-.014964,-.018,
-.015259,-.017368,
-.015439,-.016695,
-.0155,-.016,
0.0*
%
%ADD30MACRO30*%
%AMMACRO29*
4,1,40,-.016,.0155,
.016,.0155,
.016695,.015439,
.017368,.015259,
.018,.014964,
.018571,.014564,
.019064,.014071,
.019464,.0135,
.019759,.012868,
.019939,.012195,
.02,.0115,
.02,-.0115,
.019939,-.012195,
.019759,-.012868,
.019464,-.0135,
.019064,-.014071,
.018571,-.014564,
.018,-.014964,
.017368,-.015259,
.016695,-.015439,
.016,-.0155,
-.016,-.0155,
-.016695,-.015439,
-.017368,-.015259,
-.018,-.014964,
-.018571,-.014564,
-.019064,-.014071,
-.019464,-.0135,
-.019759,-.012868,
-.019939,-.012195,
-.02,-.0115,
-.02,.0115,
-.019939,.012195,
-.019759,.012868,
-.019464,.0135,
-.019064,.014071,
-.018571,.014564,
-.018,.014964,
-.017368,.015259,
-.016695,.015439,
-.016,.0155,
0.0*
%
%ADD29MACRO29*%
%ADD58C,.028*%
%AMMACRO55*
4,1,40,.002,-.016,
.003389,-.015878,
.004736,-.015518,
.006,-.014928,
.007142,-.014128,
.008128,-.013142,
.008928,-.012,
.009518,-.010736,
.009878,-.009389,
.01,-.008,
.01,.008,
.009878,.009389,
.009518,.010736,
.008928,.012,
.008128,.013142,
.007142,.014128,
.006,.014928,
.004736,.015518,
.003389,.015878,
.002,.016,
-.002,.016,
-.003389,.015878,
-.004736,.015518,
-.006,.014928,
-.007142,.014128,
-.008128,.013142,
-.008928,.012,
-.009518,.010736,
-.009878,.009389,
-.01,.008,
-.01,-.008,
-.009878,-.009389,
-.009518,-.010736,
-.008928,-.012,
-.008128,-.013142,
-.007142,-.014128,
-.006,-.014928,
-.004736,-.015518,
-.003389,-.015878,
-.002,-.016,
.002,-.016,
0.0*
%
%ADD55MACRO55*%
%AMMACRO83*
4,1,40,.0155,.016,
.0155,-.016,
.015439,-.016695,
.015259,-.017368,
.014964,-.018,
.014564,-.018571,
.014071,-.019064,
.0135,-.019464,
.012868,-.019759,
.012195,-.019939,
.0115,-.02,
-.0115,-.02,
-.012195,-.019939,
-.012868,-.019759,
-.0135,-.019464,
-.014071,-.019064,
-.014564,-.018571,
-.014964,-.018,
-.015259,-.017368,
-.015439,-.016695,
-.0155,-.016,
-.0155,.016,
-.015439,.016695,
-.015259,.017368,
-.014964,.018,
-.014564,.018571,
-.014071,.019064,
-.0135,.019464,
-.012868,.019759,
-.012195,.019939,
-.0115,.02,
.0115,.02,
.012195,.019939,
.012868,.019759,
.0135,.019464,
.014071,.019064,
.014564,.018571,
.014964,.018,
.015259,.017368,
.015439,.016695,
.0155,.016,
0.0*
%
%ADD83MACRO83*%
%AMMACRO31*
4,1,40,-.008,-.009,
.008,-.009,
.008347,-.00897,
.008684,-.008879,
.009,-.008732,
.009286,-.008532,
.009532,-.008286,
.009732,-.008,
.009879,-.007684,
.00997,-.007347,
.01,-.007,
.01,.007,
.00997,.007347,
.009879,.007684,
.009732,.008,
.009532,.008286,
.009286,.008532,
.009,.008732,
.008684,.008879,
.008347,.00897,
.008,.009,
-.008,.009,
-.008347,.00897,
-.008684,.008879,
-.009,.008732,
-.009286,.008532,
-.009532,.008286,
-.009732,.008,
-.009879,.007684,
-.00997,.007347,
-.01,.007,
-.01,-.007,
-.00997,-.007347,
-.009879,-.007684,
-.009732,-.008,
-.009532,-.008286,
-.009286,-.008532,
-.009,-.008732,
-.008684,-.008879,
-.008347,-.00897,
-.008,-.009,
0.0*
%
%ADD31MACRO31*%
%AMMACRO23*
4,1,40,.009,-.008,
.009,.008,
.00897,.008347,
.008879,.008684,
.008732,.009,
.008532,.009286,
.008286,.009532,
.008,.009732,
.007684,.009879,
.007347,.00997,
.007,.01,
-.007,.01,
-.007347,.00997,
-.007684,.009879,
-.008,.009732,
-.008286,.009532,
-.008532,.009286,
-.008732,.009,
-.008879,.008684,
-.00897,.008347,
-.009,.008,
-.009,-.008,
-.00897,-.008347,
-.008879,-.008684,
-.008732,-.009,
-.008532,-.009286,
-.008286,-.009532,
-.008,-.009732,
-.007684,-.009879,
-.007347,-.00997,
-.007,-.01,
.007,-.01,
.007347,-.00997,
.007684,-.009879,
.008,-.009732,
.008286,-.009532,
.008532,-.009286,
.008732,-.009,
.008879,-.008684,
.00897,-.008347,
.009,-.008,
0.0*
%
%ADD23MACRO23*%
%AMMACRO28*
4,1,40,.0055,-.0145,
.006889,-.014378,
.008236,-.014018,
.0095,-.013428,
.010642,-.012628,
.011628,-.011642,
.012428,-.0105,
.013018,-.009236,
.013378,-.007889,
.0135,-.0065,
.0135,.0065,
.013378,.007889,
.013018,.009236,
.012428,.0105,
.011628,.011642,
.010642,.012628,
.0095,.013428,
.008236,.014018,
.006889,.014378,
.0055,.0145,
-.0055,.0145,
-.006889,.014378,
-.008236,.014018,
-.0095,.013428,
-.010642,.012628,
-.011628,.011642,
-.012428,.0105,
-.013018,.009236,
-.013378,.007889,
-.0135,.0065,
-.0135,-.0065,
-.013378,-.007889,
-.013018,-.009236,
-.012428,-.0105,
-.011628,-.011642,
-.010642,-.012628,
-.0095,-.013428,
-.008236,-.014018,
-.006889,-.014378,
-.0055,-.0145,
.0055,-.0145,
0.0*
%
%ADD28MACRO28*%
%AMMACRO82*
4,1,40,.0155,.016,
.0155,-.016,
.015439,-.016695,
.015259,-.017368,
.014964,-.018,
.014564,-.018571,
.014071,-.019064,
.0135,-.019464,
.012868,-.019759,
.012195,-.019939,
.0115,-.02,
-.0115,-.02,
-.012195,-.019939,
-.012868,-.019759,
-.0135,-.019464,
-.014071,-.019064,
-.014564,-.018571,
-.014964,-.018,
-.015259,-.017368,
-.015439,-.016695,
-.0155,-.016,
-.0155,.016,
-.015439,.016695,
-.015259,.017368,
-.014964,.018,
-.014564,.018571,
-.014071,.019064,
-.0135,.019464,
-.012868,.019759,
-.012195,.019939,
-.0115,.02,
.0115,.02,
.012195,.019939,
.012868,.019759,
.0135,.019464,
.014071,.019064,
.014564,.018571,
.014964,.018,
.015259,.017368,
.015439,.016695,
.0155,.016,
0.0*
%
%ADD82MACRO82*%
%AMMACRO32*
4,1,40,-.008,-.009,
.008,-.009,
.008347,-.00897,
.008684,-.008879,
.009,-.008732,
.009286,-.008532,
.009532,-.008286,
.009732,-.008,
.009879,-.007684,
.00997,-.007347,
.01,-.007,
.01,.007,
.00997,.007347,
.009879,.007684,
.009732,.008,
.009532,.008286,
.009286,.008532,
.009,.008732,
.008684,.008879,
.008347,.00897,
.008,.009,
-.008,.009,
-.008347,.00897,
-.008684,.008879,
-.009,.008732,
-.009286,.008532,
-.009532,.008286,
-.009732,.008,
-.009879,.007684,
-.00997,.007347,
-.01,.007,
-.01,-.007,
-.00997,-.007347,
-.009879,-.007684,
-.009732,-.008,
-.009532,-.008286,
-.009286,-.008532,
-.009,-.008732,
-.008684,-.008879,
-.008347,-.00897,
-.008,-.009,
0.0*
%
%ADD32MACRO32*%
%AMMACRO15*
4,1,40,.009,-.008,
.009,.008,
.00897,.008347,
.008879,.008684,
.008732,.009,
.008532,.009286,
.008286,.009532,
.008,.009732,
.007684,.009879,
.007347,.00997,
.007,.01,
-.007,.01,
-.007347,.00997,
-.007684,.009879,
-.008,.009732,
-.008286,.009532,
-.008532,.009286,
-.008732,.009,
-.008879,.008684,
-.00897,.008347,
-.009,.008,
-.009,-.008,
-.00897,-.008347,
-.008879,-.008684,
-.008732,-.009,
-.008532,-.009286,
-.008286,-.009532,
-.008,-.009732,
-.007684,-.009879,
-.007347,-.00997,
-.007,-.01,
.007,-.01,
.007347,-.00997,
.007684,-.009879,
.008,-.009732,
.008286,-.009532,
.008532,-.009286,
.008732,-.009,
.008879,-.008684,
.00897,-.008347,
.009,-.008,
0.0*
%
%ADD15MACRO15*%
%AMMACRO64*
4,1,3,.0125,.025,
-.0125,0.0,
.0125,-.025,
.0125,.025,
0.0*
%
%ADD64MACRO64*%
%ADD51R,.03X.014*%
%ADD45R,.014X.03*%
%ADD79R,.022X.032*%
%AMMACRO49*
4,1,3,0.0,.0125,
-.025,-.0125,
.025,-.0125,
0.0,.0125,
0.0*
%
%ADD49MACRO49*%
%ADD34R,.014X.032*%
%ADD33R,.032X.014*%
%ADD21R,.061X.012*%
%ADD81R,.032X.042*%
%ADD59R,.025X.012*%
%ADD54R,.014X.032*%
%ADD53R,.032X.014*%
%ADD48R,.034X.012*%
%ADD47R,.012X.034*%
%ADD61R,.012X.026*%
%ADD60R,.026X.012*%
%ADD13R,.042X.032*%
%ADD67R,.061X.024*%
%AMMACRO16*
4,1,40,.009,-.01,
-.009,-.01,
-.009347,-.00997,
-.009684,-.009879,
-.01,-.009732,
-.010286,-.009532,
-.010532,-.009286,
-.010732,-.009,
-.010879,-.008684,
-.01097,-.008347,
-.011,-.008,
-.011,.008,
-.01097,.008347,
-.010879,.008684,
-.010732,.009,
-.010532,.009286,
-.010286,.009532,
-.01,.009732,
-.009684,.009879,
-.009347,.00997,
-.009,.01,
.009,.01,
.009347,.00997,
.009684,.009879,
.01,.009732,
.010286,.009532,
.010532,.009286,
.010732,.009,
.010879,.008684,
.01097,.008347,
.011,.008,
.011,-.008,
.01097,-.008347,
.010879,-.008684,
.010732,-.009,
.010532,-.009286,
.010286,-.009532,
.01,-.009732,
.009684,-.009879,
.009347,-.00997,
.009,-.01,
0.0*
%
%ADD16MACRO16*%
%AMMACRO14*
4,1,40,-.01,-.009,
-.01,.009,
-.00997,.009347,
-.009879,.009684,
-.009732,.01,
-.009532,.010286,
-.009286,.010532,
-.009,.010732,
-.008684,.010879,
-.008347,.01097,
-.008,.011,
.008,.011,
.008347,.01097,
.008684,.010879,
.009,.010732,
.009286,.010532,
.009532,.010286,
.009732,.01,
.009879,.009684,
.00997,.009347,
.01,.009,
.01,-.009,
.00997,-.009347,
.009879,-.009684,
.009732,-.01,
.009532,-.010286,
.009286,-.010532,
.009,-.010732,
.008684,-.010879,
.008347,-.01097,
.008,-.011,
-.008,-.011,
-.008347,-.01097,
-.008684,-.010879,
-.009,-.010732,
-.009286,-.010532,
-.009532,-.010286,
-.009732,-.01,
-.009879,-.009684,
-.00997,-.009347,
-.01,-.009,
0.0*
%
%ADD14MACRO14*%
%ADD56R,.04X.073*%
%ADD37R,.012X.055*%
%ADD10C,.14*%
%ADD57R,.073X.04*%
%AMMACRO43*
4,1,40,.0155,.016,
.0155,-.016,
.015439,-.016695,
.015259,-.017368,
.014964,-.018,
.014564,-.018571,
.014071,-.019064,
.0135,-.019464,
.012868,-.019759,
.012195,-.019939,
.0115,-.02,
-.0115,-.02,
-.012195,-.019939,
-.012868,-.019759,
-.0135,-.019464,
-.014071,-.019064,
-.014564,-.018571,
-.014964,-.018,
-.015259,-.017368,
-.015439,-.016695,
-.0155,-.016,
-.0155,.016,
-.015439,.016695,
-.015259,.017368,
-.014964,.018,
-.014564,.018571,
-.014071,.019064,
-.0135,.019464,
-.012868,.019759,
-.012195,.019939,
-.0115,.02,
.0115,.02,
.012195,.019939,
.012868,.019759,
.0135,.019464,
.014071,.019064,
.014564,.018571,
.014964,.018,
.015259,.017368,
.015439,.016695,
.0155,.016,
0.0*
%
%ADD43MACRO43*%
%AMMACRO25*
4,1,40,.016,-.0155,
-.016,-.0155,
-.016695,-.015439,
-.017368,-.015259,
-.018,-.014964,
-.018571,-.014564,
-.019064,-.014071,
-.019464,-.0135,
-.019759,-.012868,
-.019939,-.012195,
-.02,-.0115,
-.02,.0115,
-.019939,.012195,
-.019759,.012868,
-.019464,.0135,
-.019064,.014071,
-.018571,.014564,
-.018,.014964,
-.017368,.015259,
-.016695,.015439,
-.016,.0155,
.016,.0155,
.016695,.015439,
.017368,.015259,
.018,.014964,
.018571,.014564,
.019064,.014071,
.019464,.0135,
.019759,.012868,
.019939,.012195,
.02,.0115,
.02,-.0115,
.019939,-.012195,
.019759,-.012868,
.019464,-.0135,
.019064,-.014071,
.018571,-.014564,
.018,-.014964,
.017368,-.015259,
.016695,-.015439,
.016,-.0155,
0.0*
%
%ADD25MACRO25*%
%ADD12R,.037X.061*%
%ADD69R,.138X.181*%
%ADD24R,.061X.037*%
%ADD65R,.071X.047*%
%AMMACRO78*
4,1,40,-.002,.016,
-.003389,.015878,
-.004736,.015518,
-.006,.014928,
-.007142,.014128,
-.008128,.013142,
-.008928,.012,
-.009518,.010736,
-.009878,.009389,
-.01,.008,
-.01,-.008,
-.009878,-.009389,
-.009518,-.010736,
-.008928,-.012,
-.008128,-.013142,
-.007142,-.014128,
-.006,-.014928,
-.004736,-.015518,
-.003389,-.015878,
-.002,-.016,
.002,-.016,
.003389,-.015878,
.004736,-.015518,
.006,-.014928,
.007142,-.014128,
.008128,-.013142,
.008928,-.012,
.009518,-.010736,
.009878,-.009389,
.01,-.008,
.01,.008,
.009878,.009389,
.009518,.010736,
.008928,.012,
.008128,.013142,
.007142,.014128,
.006,.014928,
.004736,.015518,
.003389,.015878,
.002,.016,
-.002,.016,
0.0*
%
%ADD78MACRO78*%
%AMMACRO52*
4,1,40,-.016,-.002,
-.015878,-.003389,
-.015518,-.004736,
-.014928,-.006,
-.014128,-.007142,
-.013142,-.008128,
-.012,-.008928,
-.010736,-.009518,
-.009389,-.009878,
-.008,-.01,
.008,-.01,
.009389,-.009878,
.010736,-.009518,
.012,-.008928,
.013142,-.008128,
.014128,-.007142,
.014928,-.006,
.015518,-.004736,
.015878,-.003389,
.016,-.002,
.016,.002,
.015878,.003389,
.015518,.004736,
.014928,.006,
.014128,.007142,
.013142,.008128,
.012,.008928,
.010736,.009518,
.009389,.009878,
.008,.01,
-.008,.01,
-.009389,.009878,
-.010736,.009518,
-.012,.008928,
-.013142,.008128,
-.014128,.007142,
-.014928,.006,
-.015518,.004736,
-.015878,.003389,
-.016,.002,
-.016,-.002,
0.0*
%
%ADD52MACRO52*%
%ADD44R,.079X.022*%
%ADD68R,.177X.181*%
%ADD35R,.124X.124*%
%ADD66R,.075X.095*%
%ADD62R,.098X.072*%
%ADD42R,.165X.165*%
%ADD36R,.089X.076*%
%AMMACRO80*
4,1,40,-.0145,-.0055,
-.014378,-.006889,
-.014018,-.008236,
-.013428,-.0095,
-.012628,-.010642,
-.011642,-.011628,
-.0105,-.012428,
-.009236,-.013018,
-.007889,-.013378,
-.0065,-.0135,
.0065,-.0135,
.007889,-.013378,
.009236,-.013018,
.0105,-.012428,
.011642,-.011628,
.012628,-.010642,
.013428,-.0095,
.014018,-.008236,
.014378,-.006889,
.0145,-.0055,
.0145,.0055,
.014378,.006889,
.014018,.008236,
.013428,.0095,
.012628,.010642,
.011642,.011628,
.0105,.012428,
.009236,.013018,
.007889,.013378,
.0065,.0135,
-.0065,.0135,
-.007889,.013378,
-.009236,.013018,
-.0105,.012428,
-.011642,.011628,
-.012628,.010642,
-.013428,.0095,
-.014018,.008236,
-.014378,.006889,
-.0145,.0055,
-.0145,-.0055,
0.0*
%
%ADD80MACRO80*%
%AMMACRO19*
4,1,40,-.009,.008,
-.009,-.008,
-.00897,-.008347,
-.008879,-.008684,
-.008732,-.009,
-.008532,-.009286,
-.008286,-.009532,
-.008,-.009732,
-.007684,-.009879,
-.007347,-.00997,
-.007,-.01,
.007,-.01,
.007347,-.00997,
.007684,-.009879,
.008,-.009732,
.008286,-.009532,
.008532,-.009286,
.008732,-.009,
.008879,-.008684,
.00897,-.008347,
.009,-.008,
.009,.008,
.00897,.008347,
.008879,.008684,
.008732,.009,
.008532,.009286,
.008286,.009532,
.008,.009732,
.007684,.009879,
.007347,.00997,
.007,.01,
-.007,.01,
-.007347,.00997,
-.007684,.009879,
-.008,.009732,
-.008286,.009532,
-.008532,.009286,
-.008732,.009,
-.008879,.008684,
-.00897,.008347,
-.009,.008,
0.0*
%
%ADD19MACRO19*%
%AMMACRO26*
4,1,40,.008,.009,
-.008,.009,
-.008347,.00897,
-.008684,.008879,
-.009,.008732,
-.009286,.008532,
-.009532,.008286,
-.009732,.008,
-.009879,.007684,
-.00997,.007347,
-.01,.007,
-.01,-.007,
-.00997,-.007347,
-.009879,-.007684,
-.009732,-.008,
-.009532,-.008286,
-.009286,-.008532,
-.009,-.008732,
-.008684,-.008879,
-.008347,-.00897,
-.008,-.009,
.008,-.009,
.008347,-.00897,
.008684,-.008879,
.009,-.008732,
.009286,-.008532,
.009532,-.008286,
.009732,-.008,
.009879,-.007684,
.00997,-.007347,
.01,-.007,
.01,.007,
.00997,.007347,
.009879,.007684,
.009732,.008,
.009532,.008286,
.009286,.008532,
.009,.008732,
.008684,.008879,
.008347,.00897,
.008,.009,
0.0*
%
%ADD26MACRO26*%
%AMMACRO20*
4,1,40,-.009,.008,
-.009,-.008,
-.00897,-.008347,
-.008879,-.008684,
-.008732,-.009,
-.008532,-.009286,
-.008286,-.009532,
-.008,-.009732,
-.007684,-.009879,
-.007347,-.00997,
-.007,-.01,
.007,-.01,
.007347,-.00997,
.007684,-.009879,
.008,-.009732,
.008286,-.009532,
.008532,-.009286,
.008732,-.009,
.008879,-.008684,
.00897,-.008347,
.009,-.008,
.009,.008,
.00897,.008347,
.008879,.008684,
.008732,.009,
.008532,.009286,
.008286,.009532,
.008,.009732,
.007684,.009879,
.007347,.00997,
.007,.01,
-.007,.01,
-.007347,.00997,
-.007684,.009879,
-.008,.009732,
-.008286,.009532,
-.008532,.009286,
-.008732,.009,
-.008879,.008684,
-.00897,.008347,
-.009,.008,
0.0*
%
%ADD20MACRO20*%
%ADD85C,.02*%
%ADD86C,.006*%
G75*
%LPD*%
G75*
G54D10*
X-19686Y15748D03*
Y573228D03*
X846455Y15748D03*
Y573228D03*
G54D20*
X26000Y138500D03*
X64000Y251500D03*
Y254500D03*
Y261700D03*
Y264800D03*
X75100Y241700D03*
X125500Y175000D03*
X132000Y172000D03*
X153500Y168000D03*
X260800Y76200D03*
X272000Y126300D03*
X283000Y138500D03*
X281400Y153200D03*
X318500Y88300D03*
X329000Y85000D03*
X356650Y131700D03*
Y134700D03*
X370000Y103000D03*
Y100000D03*
Y106000D03*
X365100Y121500D03*
X366500Y118500D03*
X361400Y151900D03*
X379500Y77500D03*
X383500Y139500D03*
X374000Y146000D03*
X386500Y152500D03*
X376280Y184610D03*
X403000Y131063D03*
X408000Y134063D03*
X408012Y140238D03*
X408000Y137063D03*
X408200Y176063D03*
Y173063D03*
X404542Y169124D03*
X414000Y208000D03*
X444000Y114563D03*
Y111563D03*
X437000Y188500D03*
X437500Y200063D03*
X466500Y24000D03*
X513000Y50507D03*
X515000Y126000D03*
Y122500D03*
X528000Y125500D03*
X546000Y96000D03*
Y93000D03*
X544500Y179000D03*
X570000Y92500D03*
X599000Y142000D03*
X591000Y179000D03*
X644500Y285000D03*
X722000Y116500D03*
X736200Y111900D03*
X736300Y108700D03*
X737900Y130900D03*
X737800Y137100D03*
X805000Y121500D03*
Y125000D03*
X805200Y155300D03*
X805900Y166700D03*
G54D11*
X-11600Y33200D03*
X18400Y76200D03*
X22000Y168500D03*
X24000Y280000D03*
X130000Y72000D03*
X165000Y211500D03*
X394100Y57700D03*
X799500Y10500D03*
X833100Y564800D03*
X842500Y35000D03*
G54D12*
X18500Y111500D03*
X25100D03*
X25600Y149700D03*
X19000D03*
X25600Y156800D03*
X19000D03*
X103300Y174000D03*
X96700D03*
X103300Y181500D03*
X96700D03*
X275600Y60900D03*
X273100Y68000D03*
X279700D03*
X282200Y60900D03*
X305800Y64400D03*
X299200D03*
X305800Y71600D03*
X299200D03*
X365300Y247000D03*
X358700D03*
X365300Y254500D03*
X358700D03*
X426700Y85000D03*
X433300D03*
X431200Y205500D03*
X437800D03*
X787200Y101000D03*
Y108500D03*
X781700Y230600D03*
X775100D03*
X781700Y238000D03*
X775100D03*
X793800Y101000D03*
Y108500D03*
X797800Y229400D03*
X804400D03*
X797800Y222300D03*
X804400D03*
X797800Y239000D03*
X804400D03*
X797800Y246200D03*
X804400D03*
X803300Y279500D03*
X796700D03*
G54D21*
X21949Y194685D03*
Y196653D03*
Y198622D03*
Y200590D03*
Y202559D03*
Y212401D03*
Y214370D03*
Y216338D03*
Y218307D03*
Y220275D03*
Y222244D03*
Y224212D03*
Y226181D03*
Y228149D03*
Y230118D03*
Y232086D03*
Y234055D03*
Y236023D03*
Y237992D03*
Y239960D03*
Y241929D03*
Y243897D03*
Y249803D03*
Y251771D03*
Y253740D03*
Y255708D03*
Y245866D03*
Y247834D03*
Y257677D03*
Y259645D03*
Y261614D03*
Y263582D03*
Y265551D03*
Y267519D03*
X51674Y195669D03*
Y197637D03*
Y199606D03*
Y201574D03*
Y211417D03*
Y213385D03*
Y215354D03*
Y217322D03*
Y219291D03*
Y221259D03*
Y223228D03*
Y225196D03*
Y227165D03*
Y229133D03*
Y231102D03*
Y233071D03*
Y235039D03*
Y237008D03*
Y238976D03*
Y240945D03*
Y242913D03*
Y250787D03*
Y252756D03*
Y254724D03*
Y256693D03*
Y244882D03*
Y246850D03*
Y248819D03*
Y258661D03*
Y260630D03*
Y262598D03*
Y264567D03*
Y266535D03*
G54D30*
X94900Y193000D03*
X100100D03*
X120900Y121000D03*
X126100D03*
X154900Y157500D03*
X142900Y190500D03*
X148100D03*
X160100Y157500D03*
X192900Y115200D03*
X198100D03*
X262400Y65500D03*
X261400Y83000D03*
X267600Y65500D03*
X266600Y83000D03*
X300400Y77700D03*
X305600D03*
X334400Y131000D03*
X339600D03*
X338360Y150400D03*
X343560D03*
X370396Y68063D03*
X370400Y73200D03*
X368400Y175650D03*
X375596Y68063D03*
X375600Y73200D03*
X373600Y175650D03*
X508900Y46507D03*
X514100D03*
X725900Y59000D03*
Y54000D03*
X731100Y59000D03*
Y54000D03*
X775900Y6500D03*
X781100D03*
X775900Y11700D03*
X781100D03*
X799400Y252300D03*
Y257300D03*
Y262500D03*
X804600Y252300D03*
Y257300D03*
Y262500D03*
G54D13*
X19000Y174931D03*
Y180069D03*
X265500Y87931D03*
Y93069D03*
G54D31*
X81500Y234500D03*
X127000Y209500D03*
X154000Y118500D03*
X150500Y177000D03*
X160000Y165000D03*
X161000Y203000D03*
X212500Y169500D03*
X259000Y52000D03*
X262000D03*
X353000Y146500D03*
X356000Y158600D03*
Y180000D03*
X352500Y174000D03*
X359000Y145800D03*
X370742Y139924D03*
X361300Y162200D03*
X364300Y159850D03*
X359000Y168000D03*
Y180000D03*
X371500Y187600D03*
X376390Y187650D03*
X385500Y200700D03*
X389500Y150463D03*
X401866Y162000D03*
X396142Y165024D03*
X400500Y201063D03*
X395000Y267500D03*
X406500Y68500D03*
X411500Y130000D03*
X403500Y201063D03*
X406500D03*
X409500D03*
X424500Y160000D03*
X420000Y206000D03*
X423000Y206063D03*
X517000Y56507D03*
X626500Y47507D03*
X633300D03*
X636600D03*
X661500Y48107D03*
X658500D03*
X664500D03*
X735000Y66500D03*
X739300Y109000D03*
G54D40*
X171885Y181048D03*
Y203970D03*
X189207Y181048D03*
Y203970D03*
G54D22*
X25000Y190354D03*
Y271850D03*
G54D14*
X32500Y90700D03*
Y87300D03*
X35500Y90700D03*
Y87300D03*
X61000Y135300D03*
Y138700D03*
X64500Y87700D03*
Y84300D03*
X78000Y242200D03*
Y238800D03*
X87800Y211800D03*
Y215200D03*
X92800Y224700D03*
Y221300D03*
X88200Y242200D03*
Y238800D03*
X88000Y256700D03*
Y253300D03*
X121000Y212700D03*
Y209300D03*
X127500Y101200D03*
Y97800D03*
X143500Y82200D03*
Y78800D03*
Y96200D03*
Y92800D03*
X164900Y110100D03*
Y106700D03*
X167900Y110100D03*
Y106700D03*
X175600Y113200D03*
Y109800D03*
X184600Y113200D03*
Y109800D03*
X189000Y112700D03*
Y109300D03*
X195000Y172700D03*
Y169300D03*
X209000Y51700D03*
Y48300D03*
X212000Y51700D03*
Y48300D03*
X207400Y94500D03*
Y91100D03*
X218100Y198400D03*
Y195000D03*
X236500Y54200D03*
Y50800D03*
X239500Y54200D03*
Y50800D03*
X261300Y90200D03*
Y93600D03*
X264100Y151400D03*
Y154800D03*
X278500Y104100D03*
Y107500D03*
X278600Y149300D03*
Y145900D03*
X274000Y182800D03*
X277400Y181200D03*
Y177800D03*
X274000Y186200D03*
X293200Y151000D03*
Y154400D03*
X280500Y212200D03*
Y208800D03*
X304500Y85200D03*
Y81800D03*
X308700Y104500D03*
Y101100D03*
X297500Y146200D03*
Y142800D03*
X325100Y109900D03*
Y106500D03*
X322500Y250700D03*
Y247300D03*
X319000Y250700D03*
Y247300D03*
X315500Y250700D03*
Y247300D03*
X328100Y115500D03*
Y112100D03*
X336000Y110700D03*
Y107300D03*
X344500Y135900D03*
Y139300D03*
X353000Y156200D03*
Y152800D03*
X351000Y180300D03*
X349500Y175200D03*
Y171800D03*
X356000Y172000D03*
Y168600D03*
X351000Y183700D03*
X398300Y177500D03*
Y174100D03*
X396000Y203700D03*
Y200300D03*
Y210700D03*
Y207300D03*
X388500Y204200D03*
Y200800D03*
X395000Y253200D03*
Y249800D03*
X410000Y126763D03*
Y123363D03*
X433500Y24200D03*
Y20800D03*
X433000Y120363D03*
Y123763D03*
X472000Y258200D03*
Y254800D03*
X468500Y258200D03*
Y254800D03*
X509000Y101200D03*
Y97800D03*
X525000Y237700D03*
Y234300D03*
X538500Y238700D03*
Y235300D03*
X573500Y178700D03*
Y175300D03*
X576500Y178700D03*
Y175300D03*
X698000Y165800D03*
Y169200D03*
X725200Y119900D03*
Y116500D03*
X738300Y126600D03*
Y123200D03*
X742500Y111700D03*
Y108300D03*
X745500Y111700D03*
Y108300D03*
X749500Y126200D03*
Y122800D03*
X778000Y20100D03*
Y16700D03*
X775000Y20100D03*
Y16700D03*
G54D32*
X81500Y237500D03*
X127000Y212500D03*
X154000Y121500D03*
X150500Y180000D03*
X160000Y168000D03*
X161000Y206000D03*
X212500Y172500D03*
X259000Y55000D03*
X262000D03*
X353000Y149500D03*
X356000Y161600D03*
Y183000D03*
X352500Y177000D03*
X359000Y148800D03*
X370742Y142924D03*
X361300Y165200D03*
X364300Y162850D03*
X359000Y171000D03*
Y183000D03*
X371500Y190600D03*
X376390Y190650D03*
X385500Y203700D03*
X401866Y165000D03*
X389500Y153463D03*
X396142Y168024D03*
X400500Y204063D03*
X395000Y270500D03*
X406500Y71500D03*
X411500Y133000D03*
X403500Y204063D03*
X406500D03*
X409500D03*
X424500Y163000D03*
X420000Y209000D03*
X423000Y209063D03*
X517000Y59507D03*
X626500Y50507D03*
X633300D03*
X636600D03*
X661500Y51107D03*
X658500D03*
X664500D03*
X735000Y69500D03*
X739300Y112000D03*
G54D23*
X35000Y99000D03*
X75500Y91500D03*
X67500Y132500D03*
X71000Y222000D03*
X88500Y110000D03*
X136000Y201000D03*
X147000Y106000D03*
X212000Y74000D03*
Y68000D03*
Y71000D03*
Y77000D03*
X266000Y108500D03*
Y111500D03*
Y120200D03*
Y117200D03*
X310500Y88300D03*
X311000Y144200D03*
X340500Y78500D03*
X347500Y88500D03*
X352500Y103500D03*
Y100500D03*
X350000Y97500D03*
Y94500D03*
X347500Y91500D03*
X352500Y106500D03*
X362450Y134700D03*
X366500Y182700D03*
Y179700D03*
X395496Y131063D03*
X396342Y143124D03*
X391000Y210500D03*
X437000Y17500D03*
X434500Y170000D03*
X471500Y242500D03*
X528000Y122500D03*
Y148500D03*
Y151500D03*
X530500Y179000D03*
Y176000D03*
X550500Y179000D03*
X563500D03*
X605000Y142000D03*
X610000Y211000D03*
G54D41*
X173459Y181448D03*
X175034D03*
X176609D03*
X178184D03*
X179759D03*
X181333D03*
X182908D03*
X184483D03*
X186058D03*
Y203570D03*
X184483D03*
X182908D03*
X181333D03*
X179759D03*
X178184D03*
X176609D03*
X175034D03*
X173459D03*
X187633Y181448D03*
Y203570D03*
G54D50*
X270000Y100350D03*
G54D42*
X180546Y192509D03*
G54D24*
X60500Y120200D03*
Y126800D03*
X109500Y166200D03*
Y172800D03*
X117000Y166200D03*
Y172800D03*
X292700Y75100D03*
Y81700D03*
X339500Y56200D03*
Y62800D03*
X347000Y56200D03*
Y62800D03*
X357000Y271300D03*
Y264700D03*
X369500Y52200D03*
Y58800D03*
X377000Y52200D03*
Y58800D03*
X439900Y175700D03*
Y182300D03*
X447000Y175700D03*
Y182300D03*
X449500Y269800D03*
Y263200D03*
X589500Y230200D03*
X582000D03*
X589500Y236800D03*
X582000D03*
X615900Y47207D03*
Y53807D03*
X608800Y47207D03*
Y53807D03*
X634500Y230200D03*
Y236800D03*
X642000Y230200D03*
Y236800D03*
X676700Y47407D03*
Y54007D03*
X669600Y47407D03*
Y54007D03*
X767500Y122200D03*
Y128800D03*
X803200Y179500D03*
Y172900D03*
G54D60*
X372426Y258500D03*
Y256531D03*
Y254563D03*
Y252594D03*
Y250626D03*
Y248657D03*
Y268343D03*
Y266374D03*
Y264406D03*
Y262437D03*
Y260469D03*
X387574Y248657D03*
Y250626D03*
Y252594D03*
Y254563D03*
Y256531D03*
Y258500D03*
Y260469D03*
Y262437D03*
Y264406D03*
Y266374D03*
Y268343D03*
G54D33*
X110517Y196537D03*
Y193978D03*
Y191419D03*
Y188860D03*
Y186301D03*
X129003D03*
Y188860D03*
Y191419D03*
Y193978D03*
Y196537D03*
G54D51*
X268520Y132540D03*
X275880D03*
Y135100D03*
Y137660D03*
X268520D03*
X402820Y59440D03*
Y64560D03*
Y62000D03*
X410180Y59440D03*
Y64560D03*
X461520Y20060D03*
Y14940D03*
X468880Y20060D03*
Y14940D03*
Y17500D03*
G54D15*
X32000Y99000D03*
X72500Y91500D03*
X64500Y132500D03*
X68000Y222000D03*
X85500Y110000D03*
X133000Y201000D03*
X144000Y106000D03*
X209000Y74000D03*
Y68000D03*
Y71000D03*
Y77000D03*
X263000Y108500D03*
Y111500D03*
Y120200D03*
Y117200D03*
X307500Y88300D03*
X308000Y144200D03*
X337500Y78500D03*
X344500Y88500D03*
X349500Y103500D03*
Y100500D03*
X347000Y97500D03*
Y94500D03*
X344500Y91500D03*
X349500Y106500D03*
X359450Y134700D03*
X363500Y182700D03*
Y179700D03*
X392496Y131063D03*
X393342Y143124D03*
X388000Y210500D03*
X434000Y17500D03*
X431500Y170000D03*
X468500Y242500D03*
X525000Y122500D03*
Y148500D03*
Y151500D03*
X527500Y179000D03*
Y176000D03*
X547500Y179000D03*
X560500D03*
X602000Y142000D03*
X607000Y211000D03*
G54D52*
X286900Y208000D03*
Y204000D03*
X292100Y206000D03*
G54D25*
X63000Y198900D03*
Y204100D03*
X68000Y198900D03*
Y204100D03*
X88800Y218900D03*
Y224100D03*
X109000Y124900D03*
Y130100D03*
X103500Y124900D03*
Y130100D03*
X123500Y164900D03*
Y170100D03*
X157000Y201900D03*
Y207100D03*
X343000Y115900D03*
Y121100D03*
X380500Y68463D03*
Y73663D03*
X376500Y202900D03*
Y208100D03*
X381500Y202900D03*
Y208100D03*
X512500Y56407D03*
Y61607D03*
X517500Y219400D03*
Y224600D03*
X512500Y219400D03*
Y224600D03*
X522500Y219400D03*
Y224600D03*
X622000Y46907D03*
Y52107D03*
X650500Y46907D03*
Y52107D03*
X645300Y49507D03*
Y54707D03*
X747500Y61900D03*
Y67100D03*
X762000Y144400D03*
Y149600D03*
X797000Y173400D03*
Y178600D03*
G54D43*
X198100Y110200D03*
X192900D03*
X198100Y120200D03*
X192900D03*
X276700Y92200D03*
X271500D03*
X290900Y86600D03*
X296100D03*
X364196Y203763D03*
X358996D03*
X387900Y178300D03*
X393100D03*
X426600Y78500D03*
X421400D03*
X472600Y238500D03*
X467400D03*
X472600Y233000D03*
X467400D03*
X780000Y244300D03*
X774800D03*
X780000Y254300D03*
X774800D03*
X780000Y249300D03*
X774800D03*
G54D16*
X31800Y96000D03*
X35200D03*
X60800Y91000D03*
X64200D03*
X60800Y218000D03*
X64200D03*
X72800Y88000D03*
X76200D03*
X72800Y84500D03*
X76200D03*
X72300Y97500D03*
X75700D03*
X72300Y94500D03*
X75700D03*
X105800Y255000D03*
X109200D03*
X128800Y175000D03*
X132200D03*
X139300Y201000D03*
X153300Y57500D03*
X156700D03*
X146800Y89500D03*
X150200D03*
X146800Y92500D03*
X150200D03*
X143800Y109000D03*
X147200D03*
X150800Y162000D03*
X154200D03*
X150800Y171500D03*
X154200D03*
X151800Y192000D03*
X155200D03*
X142700Y201000D03*
X167300Y61300D03*
X170700D03*
X161400Y113200D03*
X164800D03*
X162300Y257000D03*
X165700D03*
X182800Y57500D03*
X186200D03*
X178300Y213000D03*
X181700D03*
X195300Y230500D03*
X198700D03*
X211800Y206500D03*
X215200D03*
X226800Y60000D03*
X230200D03*
X279800Y135500D03*
X271500Y141400D03*
X274900D03*
X278700Y244400D03*
X283000Y132500D03*
X286400D03*
X283200Y135500D03*
X289800Y141500D03*
X293200D03*
X290300Y157500D03*
X293700D03*
X283700Y168000D03*
X287100D03*
X293300Y199500D03*
X286300D03*
X289700D03*
X282100Y244400D03*
X297300Y157500D03*
X300700D03*
X296700Y199500D03*
X295800Y228000D03*
X299200D03*
X295800Y231000D03*
X299200D03*
X313300Y103500D03*
X316700D03*
X313300Y148000D03*
X316700D03*
X337300Y81500D03*
X340700D03*
X349400Y159400D03*
X352800D03*
X369900Y128100D03*
X361396Y199563D03*
X364796D03*
X373300Y128100D03*
X387800Y207500D03*
X393170Y197103D03*
X396570D03*
X391200Y207500D03*
X406800Y55500D03*
X410200D03*
X404300Y208000D03*
X407700D03*
X409200Y262800D03*
X412600D03*
X440300Y36000D03*
X443700D03*
X522800Y93000D03*
X526200D03*
X520800Y110500D03*
X524200D03*
X520800Y107500D03*
X524200D03*
X545800Y119500D03*
X549200D03*
X551300Y187500D03*
X554700D03*
X566800Y179000D03*
X570200D03*
X566800Y176000D03*
X570200D03*
X560300Y187000D03*
X563700D03*
X566900Y190000D03*
X570300D03*
X573300Y92500D03*
X576700D03*
X718682Y119685D03*
X722082D03*
X741500Y46507D03*
X734800D03*
X738200D03*
X732800Y102500D03*
X736200D03*
X744900Y46507D03*
X775800Y133000D03*
X779200D03*
X775800Y129500D03*
X779200D03*
X775800Y126000D03*
X779200D03*
X775800Y122500D03*
X779200D03*
X777800Y162000D03*
X781200D03*
X777800Y165000D03*
X781200D03*
X777800Y168000D03*
X781200D03*
X777800Y171000D03*
X781200D03*
G54D61*
X375079Y245020D03*
X384921D03*
X377047D03*
X379016D03*
X380984D03*
X382953D03*
X375079Y271980D03*
X384921D03*
X382953D03*
X380984D03*
X379016D03*
X377047D03*
G54D34*
X114642Y182176D03*
X117201D03*
X119760D03*
X122319D03*
X124878D03*
Y200662D03*
X122319D03*
X119760D03*
X117201D03*
X114642D03*
G36*
G01X508858Y3106D02*
X508983Y3116D01*
X509108Y3156D01*
X509218Y3216D01*
X509318Y3296D01*
X509398Y3396D01*
X509458Y3506D01*
X509498Y3631D01*
X509508Y3756D01*
Y6186D01*
X509538Y6216D01*
X509638Y6356D01*
X509658Y6396D01*
X509673Y6431D01*
X509693Y6471D01*
X509708Y6511D01*
X509718Y6551D01*
X509733Y6596D01*
X509738Y6636D01*
X509748Y6676D01*
X509753Y6721D01*
Y6761D01*
X509758Y6806D01*
X509753Y6851D01*
Y6891D01*
X509748Y6936D01*
X509738Y6976D01*
X509733Y7016D01*
X509718Y7061D01*
X509708Y7101D01*
X509693Y7141D01*
X509673Y7181D01*
X509658Y7216D01*
X509638Y7256D01*
X509538Y7396D01*
X509508Y7426D01*
Y9556D01*
X509498Y9681D01*
X509458Y9806D01*
X509398Y9916D01*
X509318Y10016D01*
X509218Y10096D01*
X509108Y10156D01*
X508983Y10196D01*
X508858Y10206D01*
X508733Y10196D01*
X508608Y10156D01*
X508498Y10096D01*
X508398Y10016D01*
X508318Y9916D01*
X508258Y9806D01*
X508218Y9681D01*
X508208Y9556D01*
Y7431D01*
X508178Y7401D01*
X508153Y7366D01*
X508123Y7331D01*
X508103Y7296D01*
X508078Y7261D01*
X508038Y7181D01*
X507993Y7061D01*
X507983Y7021D01*
X507973Y6976D01*
X507968Y6936D01*
X507958Y6891D01*
Y6721D01*
X507968Y6676D01*
X507973Y6636D01*
X507983Y6591D01*
X507993Y6551D01*
X508038Y6431D01*
X508078Y6351D01*
X508103Y6316D01*
X508123Y6281D01*
X508153Y6246D01*
X508178Y6211D01*
X508208Y6181D01*
Y3756D01*
X508218Y3631D01*
X508258Y3506D01*
X508318Y3396D01*
X508398Y3296D01*
X508498Y3216D01*
X508608Y3156D01*
X508733Y3116D01*
X508858Y3106D01*
G37*
G36*
G01X523031D02*
X523156Y3116D01*
X523281Y3156D01*
X523391Y3216D01*
X523491Y3296D01*
X523571Y3396D01*
X523631Y3506D01*
X523671Y3631D01*
X523681Y3756D01*
Y6186D01*
X523711Y6216D01*
X523811Y6356D01*
X523831Y6396D01*
X523846Y6431D01*
X523866Y6471D01*
X523881Y6511D01*
X523891Y6551D01*
X523906Y6596D01*
X523911Y6636D01*
X523921Y6676D01*
X523926Y6721D01*
Y6761D01*
X523931Y6806D01*
X523926Y6851D01*
Y6891D01*
X523921Y6936D01*
X523911Y6976D01*
X523906Y7016D01*
X523891Y7061D01*
X523881Y7101D01*
X523866Y7141D01*
X523846Y7181D01*
X523831Y7216D01*
X523811Y7256D01*
X523711Y7396D01*
X523681Y7426D01*
Y9556D01*
X523671Y9681D01*
X523631Y9806D01*
X523571Y9916D01*
X523491Y10016D01*
X523391Y10096D01*
X523281Y10156D01*
X523156Y10196D01*
X523031Y10206D01*
X522906Y10196D01*
X522781Y10156D01*
X522671Y10096D01*
X522571Y10016D01*
X522491Y9916D01*
X522431Y9806D01*
X522391Y9681D01*
X522381Y9556D01*
Y7431D01*
X522351Y7401D01*
X522326Y7366D01*
X522296Y7331D01*
X522276Y7296D01*
X522251Y7261D01*
X522211Y7181D01*
X522166Y7061D01*
X522156Y7021D01*
X522146Y6976D01*
X522141Y6936D01*
X522131Y6891D01*
Y6721D01*
X522141Y6676D01*
X522146Y6636D01*
X522156Y6591D01*
X522166Y6551D01*
X522211Y6431D01*
X522251Y6351D01*
X522276Y6316D01*
X522296Y6281D01*
X522326Y6246D01*
X522351Y6211D01*
X522381Y6181D01*
Y3756D01*
X522391Y3631D01*
X522431Y3506D01*
X522491Y3396D01*
X522571Y3296D01*
X522671Y3216D01*
X522781Y3156D01*
X522906Y3116D01*
X523031Y3106D01*
G37*
G36*
G01X518307D02*
X518432Y3116D01*
X518557Y3156D01*
X518667Y3216D01*
X518767Y3296D01*
X518847Y3396D01*
X518907Y3506D01*
X518947Y3631D01*
X518957Y3756D01*
Y6186D01*
X518987Y6216D01*
X519087Y6356D01*
X519107Y6396D01*
X519122Y6431D01*
X519142Y6471D01*
X519157Y6511D01*
X519167Y6551D01*
X519182Y6596D01*
X519187Y6636D01*
X519197Y6676D01*
X519202Y6721D01*
Y6761D01*
X519207Y6806D01*
X519202Y6851D01*
Y6891D01*
X519197Y6936D01*
X519187Y6976D01*
X519182Y7016D01*
X519167Y7061D01*
X519157Y7101D01*
X519142Y7141D01*
X519122Y7181D01*
X519107Y7216D01*
X519087Y7256D01*
X518987Y7396D01*
X518957Y7426D01*
Y9556D01*
X518947Y9681D01*
X518907Y9806D01*
X518847Y9916D01*
X518767Y10016D01*
X518667Y10096D01*
X518557Y10156D01*
X518432Y10196D01*
X518307Y10206D01*
X518182Y10196D01*
X518057Y10156D01*
X517947Y10096D01*
X517847Y10016D01*
X517767Y9916D01*
X517707Y9806D01*
X517667Y9681D01*
X517657Y9556D01*
Y7431D01*
X517627Y7401D01*
X517602Y7366D01*
X517572Y7331D01*
X517552Y7296D01*
X517527Y7261D01*
X517487Y7181D01*
X517442Y7061D01*
X517432Y7021D01*
X517422Y6976D01*
X517417Y6936D01*
X517407Y6891D01*
Y6721D01*
X517417Y6676D01*
X517422Y6636D01*
X517432Y6591D01*
X517442Y6551D01*
X517487Y6431D01*
X517527Y6351D01*
X517552Y6316D01*
X517572Y6281D01*
X517602Y6246D01*
X517627Y6211D01*
X517657Y6181D01*
Y3756D01*
X517667Y3631D01*
X517707Y3506D01*
X517767Y3396D01*
X517847Y3296D01*
X517947Y3216D01*
X518057Y3156D01*
X518182Y3116D01*
X518307Y3106D01*
G37*
G36*
G01X513582D02*
X513707Y3116D01*
X513832Y3156D01*
X513942Y3216D01*
X514042Y3296D01*
X514122Y3396D01*
X514182Y3506D01*
X514222Y3631D01*
X514232Y3756D01*
Y6186D01*
X514262Y6216D01*
X514362Y6356D01*
X514382Y6396D01*
X514397Y6431D01*
X514417Y6471D01*
X514432Y6511D01*
X514442Y6551D01*
X514457Y6596D01*
X514462Y6636D01*
X514472Y6676D01*
X514477Y6721D01*
Y6761D01*
X514482Y6806D01*
X514477Y6851D01*
Y6891D01*
X514472Y6936D01*
X514462Y6976D01*
X514457Y7016D01*
X514442Y7061D01*
X514432Y7101D01*
X514417Y7141D01*
X514397Y7181D01*
X514382Y7216D01*
X514362Y7256D01*
X514262Y7396D01*
X514232Y7426D01*
Y9556D01*
X514222Y9681D01*
X514182Y9806D01*
X514122Y9916D01*
X514042Y10016D01*
X513942Y10096D01*
X513832Y10156D01*
X513707Y10196D01*
X513582Y10206D01*
X513457Y10196D01*
X513332Y10156D01*
X513222Y10096D01*
X513122Y10016D01*
X513042Y9916D01*
X512982Y9806D01*
X512942Y9681D01*
X512932Y9556D01*
Y7431D01*
X512902Y7401D01*
X512877Y7366D01*
X512847Y7331D01*
X512827Y7296D01*
X512802Y7261D01*
X512762Y7181D01*
X512717Y7061D01*
X512707Y7021D01*
X512697Y6976D01*
X512692Y6936D01*
X512682Y6891D01*
Y6721D01*
X512692Y6676D01*
X512697Y6636D01*
X512707Y6591D01*
X512717Y6551D01*
X512762Y6431D01*
X512802Y6351D01*
X512827Y6316D01*
X512847Y6281D01*
X512877Y6246D01*
X512902Y6211D01*
X512932Y6181D01*
Y3756D01*
X512942Y3631D01*
X512982Y3506D01*
X513042Y3396D01*
X513122Y3296D01*
X513222Y3216D01*
X513332Y3156D01*
X513457Y3116D01*
X513582Y3106D01*
G37*
G36*
G01X541929D02*
X542054Y3116D01*
X542179Y3156D01*
X542289Y3216D01*
X542389Y3296D01*
X542469Y3396D01*
X542529Y3506D01*
X542569Y3631D01*
X542579Y3756D01*
Y6186D01*
X542609Y6216D01*
X542709Y6356D01*
X542729Y6396D01*
X542744Y6431D01*
X542764Y6471D01*
X542779Y6511D01*
X542789Y6551D01*
X542804Y6596D01*
X542809Y6636D01*
X542819Y6676D01*
X542824Y6721D01*
Y6761D01*
X542829Y6806D01*
X542824Y6851D01*
Y6891D01*
X542819Y6936D01*
X542809Y6976D01*
X542804Y7016D01*
X542789Y7061D01*
X542779Y7101D01*
X542764Y7141D01*
X542744Y7181D01*
X542729Y7216D01*
X542709Y7256D01*
X542609Y7396D01*
X542579Y7426D01*
Y9556D01*
X542569Y9681D01*
X542529Y9806D01*
X542469Y9916D01*
X542389Y10016D01*
X542289Y10096D01*
X542179Y10156D01*
X542054Y10196D01*
X541929Y10206D01*
X541804Y10196D01*
X541679Y10156D01*
X541569Y10096D01*
X541469Y10016D01*
X541389Y9916D01*
X541329Y9806D01*
X541289Y9681D01*
X541279Y9556D01*
Y7431D01*
X541249Y7401D01*
X541224Y7366D01*
X541194Y7331D01*
X541174Y7296D01*
X541149Y7261D01*
X541109Y7181D01*
X541064Y7061D01*
X541054Y7021D01*
X541044Y6976D01*
X541039Y6936D01*
X541029Y6891D01*
Y6721D01*
X541039Y6676D01*
X541044Y6636D01*
X541054Y6591D01*
X541064Y6551D01*
X541109Y6431D01*
X541149Y6351D01*
X541174Y6316D01*
X541194Y6281D01*
X541224Y6246D01*
X541249Y6211D01*
X541279Y6181D01*
Y3756D01*
X541289Y3631D01*
X541329Y3506D01*
X541389Y3396D01*
X541469Y3296D01*
X541569Y3216D01*
X541679Y3156D01*
X541804Y3116D01*
X541929Y3106D01*
G37*
G36*
G01X537204D02*
X537329Y3116D01*
X537454Y3156D01*
X537564Y3216D01*
X537664Y3296D01*
X537744Y3396D01*
X537804Y3506D01*
X537844Y3631D01*
X537854Y3756D01*
Y6186D01*
X537884Y6216D01*
X537984Y6356D01*
X538004Y6396D01*
X538019Y6431D01*
X538039Y6471D01*
X538054Y6511D01*
X538064Y6551D01*
X538079Y6596D01*
X538084Y6636D01*
X538094Y6676D01*
X538099Y6721D01*
Y6761D01*
X538104Y6806D01*
X538099Y6851D01*
Y6891D01*
X538094Y6936D01*
X538084Y6976D01*
X538079Y7016D01*
X538064Y7061D01*
X538054Y7101D01*
X538039Y7141D01*
X538019Y7181D01*
X538004Y7216D01*
X537984Y7256D01*
X537884Y7396D01*
X537854Y7426D01*
Y9556D01*
X537844Y9681D01*
X537804Y9806D01*
X537744Y9916D01*
X537664Y10016D01*
X537564Y10096D01*
X537454Y10156D01*
X537329Y10196D01*
X537204Y10206D01*
X537079Y10196D01*
X536954Y10156D01*
X536844Y10096D01*
X536744Y10016D01*
X536664Y9916D01*
X536604Y9806D01*
X536564Y9681D01*
X536554Y9556D01*
Y7431D01*
X536524Y7401D01*
X536499Y7366D01*
X536469Y7331D01*
X536449Y7296D01*
X536424Y7261D01*
X536384Y7181D01*
X536339Y7061D01*
X536329Y7021D01*
X536319Y6976D01*
X536314Y6936D01*
X536304Y6891D01*
Y6721D01*
X536314Y6676D01*
X536319Y6636D01*
X536329Y6591D01*
X536339Y6551D01*
X536384Y6431D01*
X536424Y6351D01*
X536449Y6316D01*
X536469Y6281D01*
X536499Y6246D01*
X536524Y6211D01*
X536554Y6181D01*
Y3756D01*
X536564Y3631D01*
X536604Y3506D01*
X536664Y3396D01*
X536744Y3296D01*
X536844Y3216D01*
X536954Y3156D01*
X537079Y3116D01*
X537204Y3106D01*
G37*
G36*
G01X532480D02*
X532605Y3116D01*
X532730Y3156D01*
X532840Y3216D01*
X532940Y3296D01*
X533020Y3396D01*
X533080Y3506D01*
X533120Y3631D01*
X533130Y3756D01*
Y6186D01*
X533160Y6216D01*
X533260Y6356D01*
X533280Y6396D01*
X533295Y6431D01*
X533315Y6471D01*
X533330Y6511D01*
X533340Y6551D01*
X533355Y6596D01*
X533360Y6636D01*
X533370Y6676D01*
X533375Y6721D01*
Y6761D01*
X533380Y6806D01*
X533375Y6851D01*
Y6891D01*
X533370Y6936D01*
X533360Y6976D01*
X533355Y7016D01*
X533340Y7061D01*
X533330Y7101D01*
X533315Y7141D01*
X533295Y7181D01*
X533280Y7216D01*
X533260Y7256D01*
X533160Y7396D01*
X533130Y7426D01*
Y9556D01*
X533120Y9681D01*
X533080Y9806D01*
X533020Y9916D01*
X532940Y10016D01*
X532840Y10096D01*
X532730Y10156D01*
X532605Y10196D01*
X532480Y10206D01*
X532355Y10196D01*
X532230Y10156D01*
X532120Y10096D01*
X532020Y10016D01*
X531940Y9916D01*
X531880Y9806D01*
X531840Y9681D01*
X531830Y9556D01*
Y7431D01*
X531800Y7401D01*
X531775Y7366D01*
X531745Y7331D01*
X531725Y7296D01*
X531700Y7261D01*
X531660Y7181D01*
X531615Y7061D01*
X531605Y7021D01*
X531595Y6976D01*
X531590Y6936D01*
X531580Y6891D01*
Y6721D01*
X531590Y6676D01*
X531595Y6636D01*
X531605Y6591D01*
X531615Y6551D01*
X531660Y6431D01*
X531700Y6351D01*
X531725Y6316D01*
X531745Y6281D01*
X531775Y6246D01*
X531800Y6211D01*
X531830Y6181D01*
Y3756D01*
X531840Y3631D01*
X531880Y3506D01*
X531940Y3396D01*
X532020Y3296D01*
X532120Y3216D01*
X532230Y3156D01*
X532355Y3116D01*
X532480Y3106D01*
G37*
G36*
G01X527756D02*
X527881Y3116D01*
X528006Y3156D01*
X528116Y3216D01*
X528216Y3296D01*
X528296Y3396D01*
X528356Y3506D01*
X528396Y3631D01*
X528406Y3756D01*
Y6186D01*
X528436Y6216D01*
X528536Y6356D01*
X528556Y6396D01*
X528571Y6431D01*
X528591Y6471D01*
X528606Y6511D01*
X528616Y6551D01*
X528631Y6596D01*
X528636Y6636D01*
X528646Y6676D01*
X528651Y6721D01*
Y6761D01*
X528656Y6806D01*
X528651Y6851D01*
Y6891D01*
X528646Y6936D01*
X528636Y6976D01*
X528631Y7016D01*
X528616Y7061D01*
X528606Y7101D01*
X528591Y7141D01*
X528571Y7181D01*
X528556Y7216D01*
X528536Y7256D01*
X528436Y7396D01*
X528406Y7426D01*
Y9556D01*
X528396Y9681D01*
X528356Y9806D01*
X528296Y9916D01*
X528216Y10016D01*
X528116Y10096D01*
X528006Y10156D01*
X527881Y10196D01*
X527756Y10206D01*
X527631Y10196D01*
X527506Y10156D01*
X527396Y10096D01*
X527296Y10016D01*
X527216Y9916D01*
X527156Y9806D01*
X527116Y9681D01*
X527106Y9556D01*
Y7431D01*
X527076Y7401D01*
X527051Y7366D01*
X527021Y7331D01*
X527001Y7296D01*
X526976Y7261D01*
X526936Y7181D01*
X526891Y7061D01*
X526881Y7021D01*
X526871Y6976D01*
X526866Y6936D01*
X526856Y6891D01*
Y6721D01*
X526866Y6676D01*
X526871Y6636D01*
X526881Y6591D01*
X526891Y6551D01*
X526936Y6431D01*
X526976Y6351D01*
X527001Y6316D01*
X527021Y6281D01*
X527051Y6246D01*
X527076Y6211D01*
X527106Y6181D01*
Y3756D01*
X527116Y3631D01*
X527156Y3506D01*
X527216Y3396D01*
X527296Y3296D01*
X527396Y3216D01*
X527506Y3156D01*
X527631Y3116D01*
X527756Y3106D01*
G37*
G36*
G01X556102D02*
X556227Y3116D01*
X556352Y3156D01*
X556462Y3216D01*
X556562Y3296D01*
X556642Y3396D01*
X556702Y3506D01*
X556742Y3631D01*
X556752Y3756D01*
Y6186D01*
X556782Y6216D01*
X556882Y6356D01*
X556902Y6396D01*
X556917Y6431D01*
X556937Y6471D01*
X556952Y6511D01*
X556962Y6551D01*
X556977Y6596D01*
X556982Y6636D01*
X556992Y6676D01*
X556997Y6721D01*
Y6761D01*
X557002Y6806D01*
X556997Y6851D01*
Y6891D01*
X556992Y6936D01*
X556982Y6976D01*
X556977Y7016D01*
X556962Y7061D01*
X556952Y7101D01*
X556937Y7141D01*
X556917Y7181D01*
X556902Y7216D01*
X556882Y7256D01*
X556782Y7396D01*
X556752Y7426D01*
Y9556D01*
X556742Y9681D01*
X556702Y9806D01*
X556642Y9916D01*
X556562Y10016D01*
X556462Y10096D01*
X556352Y10156D01*
X556227Y10196D01*
X556102Y10206D01*
X555977Y10196D01*
X555852Y10156D01*
X555742Y10096D01*
X555642Y10016D01*
X555562Y9916D01*
X555502Y9806D01*
X555462Y9681D01*
X555452Y9556D01*
Y7431D01*
X555422Y7401D01*
X555397Y7366D01*
X555367Y7331D01*
X555347Y7296D01*
X555322Y7261D01*
X555282Y7181D01*
X555237Y7061D01*
X555227Y7021D01*
X555217Y6976D01*
X555212Y6936D01*
X555202Y6891D01*
Y6721D01*
X555212Y6676D01*
X555217Y6636D01*
X555227Y6591D01*
X555237Y6551D01*
X555282Y6431D01*
X555322Y6351D01*
X555347Y6316D01*
X555367Y6281D01*
X555397Y6246D01*
X555422Y6211D01*
X555452Y6181D01*
Y3756D01*
X555462Y3631D01*
X555502Y3506D01*
X555562Y3396D01*
X555642Y3296D01*
X555742Y3216D01*
X555852Y3156D01*
X555977Y3116D01*
X556102Y3106D01*
G37*
G36*
G01X551378D02*
X551503Y3116D01*
X551628Y3156D01*
X551738Y3216D01*
X551838Y3296D01*
X551918Y3396D01*
X551978Y3506D01*
X552018Y3631D01*
X552028Y3756D01*
Y6186D01*
X552058Y6216D01*
X552158Y6356D01*
X552178Y6396D01*
X552193Y6431D01*
X552213Y6471D01*
X552228Y6511D01*
X552238Y6551D01*
X552253Y6596D01*
X552258Y6636D01*
X552268Y6676D01*
X552273Y6721D01*
Y6761D01*
X552278Y6806D01*
X552273Y6851D01*
Y6891D01*
X552268Y6936D01*
X552258Y6976D01*
X552253Y7016D01*
X552238Y7061D01*
X552228Y7101D01*
X552213Y7141D01*
X552193Y7181D01*
X552178Y7216D01*
X552158Y7256D01*
X552058Y7396D01*
X552028Y7426D01*
Y9556D01*
X552018Y9681D01*
X551978Y9806D01*
X551918Y9916D01*
X551838Y10016D01*
X551738Y10096D01*
X551628Y10156D01*
X551503Y10196D01*
X551378Y10206D01*
X551253Y10196D01*
X551128Y10156D01*
X551018Y10096D01*
X550918Y10016D01*
X550838Y9916D01*
X550778Y9806D01*
X550738Y9681D01*
X550728Y9556D01*
Y7431D01*
X550698Y7401D01*
X550673Y7366D01*
X550643Y7331D01*
X550623Y7296D01*
X550598Y7261D01*
X550558Y7181D01*
X550513Y7061D01*
X550503Y7021D01*
X550493Y6976D01*
X550488Y6936D01*
X550478Y6891D01*
Y6721D01*
X550488Y6676D01*
X550493Y6636D01*
X550503Y6591D01*
X550513Y6551D01*
X550558Y6431D01*
X550598Y6351D01*
X550623Y6316D01*
X550643Y6281D01*
X550673Y6246D01*
X550698Y6211D01*
X550728Y6181D01*
Y3756D01*
X550738Y3631D01*
X550778Y3506D01*
X550838Y3396D01*
X550918Y3296D01*
X551018Y3216D01*
X551128Y3156D01*
X551253Y3116D01*
X551378Y3106D01*
G37*
G36*
G01X546653D02*
X546778Y3116D01*
X546903Y3156D01*
X547013Y3216D01*
X547113Y3296D01*
X547193Y3396D01*
X547253Y3506D01*
X547293Y3631D01*
X547303Y3756D01*
Y6186D01*
X547333Y6216D01*
X547433Y6356D01*
X547453Y6396D01*
X547468Y6431D01*
X547488Y6471D01*
X547503Y6511D01*
X547513Y6551D01*
X547528Y6596D01*
X547533Y6636D01*
X547543Y6676D01*
X547548Y6721D01*
Y6761D01*
X547553Y6806D01*
X547548Y6851D01*
Y6891D01*
X547543Y6936D01*
X547533Y6976D01*
X547528Y7016D01*
X547513Y7061D01*
X547503Y7101D01*
X547488Y7141D01*
X547468Y7181D01*
X547453Y7216D01*
X547433Y7256D01*
X547333Y7396D01*
X547303Y7426D01*
Y9556D01*
X547293Y9681D01*
X547253Y9806D01*
X547193Y9916D01*
X547113Y10016D01*
X547013Y10096D01*
X546903Y10156D01*
X546778Y10196D01*
X546653Y10206D01*
X546528Y10196D01*
X546403Y10156D01*
X546293Y10096D01*
X546193Y10016D01*
X546113Y9916D01*
X546053Y9806D01*
X546013Y9681D01*
X546003Y9556D01*
Y7431D01*
X545973Y7401D01*
X545948Y7366D01*
X545918Y7331D01*
X545898Y7296D01*
X545873Y7261D01*
X545833Y7181D01*
X545788Y7061D01*
X545778Y7021D01*
X545768Y6976D01*
X545763Y6936D01*
X545753Y6891D01*
Y6721D01*
X545763Y6676D01*
X545768Y6636D01*
X545778Y6591D01*
X545788Y6551D01*
X545833Y6431D01*
X545873Y6351D01*
X545898Y6316D01*
X545918Y6281D01*
X545948Y6246D01*
X545973Y6211D01*
X546003Y6181D01*
Y3756D01*
X546013Y3631D01*
X546053Y3506D01*
X546113Y3396D01*
X546193Y3296D01*
X546293Y3216D01*
X546403Y3156D01*
X546528Y3116D01*
X546653Y3106D01*
G37*
G36*
G01X570275D02*
X570400Y3116D01*
X570525Y3156D01*
X570635Y3216D01*
X570735Y3296D01*
X570815Y3396D01*
X570875Y3506D01*
X570915Y3631D01*
X570925Y3756D01*
Y6186D01*
X570955Y6216D01*
X571055Y6356D01*
X571075Y6396D01*
X571090Y6431D01*
X571110Y6471D01*
X571125Y6511D01*
X571135Y6551D01*
X571150Y6596D01*
X571155Y6636D01*
X571165Y6676D01*
X571170Y6721D01*
Y6761D01*
X571175Y6806D01*
X571170Y6851D01*
Y6891D01*
X571165Y6936D01*
X571155Y6976D01*
X571150Y7016D01*
X571135Y7061D01*
X571125Y7101D01*
X571110Y7141D01*
X571090Y7181D01*
X571075Y7216D01*
X571055Y7256D01*
X570955Y7396D01*
X570925Y7426D01*
Y9556D01*
X570915Y9681D01*
X570875Y9806D01*
X570815Y9916D01*
X570735Y10016D01*
X570635Y10096D01*
X570525Y10156D01*
X570400Y10196D01*
X570275Y10206D01*
X570150Y10196D01*
X570025Y10156D01*
X569915Y10096D01*
X569815Y10016D01*
X569735Y9916D01*
X569675Y9806D01*
X569635Y9681D01*
X569625Y9556D01*
Y7431D01*
X569595Y7401D01*
X569570Y7366D01*
X569540Y7331D01*
X569520Y7296D01*
X569495Y7261D01*
X569455Y7181D01*
X569410Y7061D01*
X569400Y7021D01*
X569390Y6976D01*
X569385Y6936D01*
X569375Y6891D01*
Y6721D01*
X569385Y6676D01*
X569390Y6636D01*
X569400Y6591D01*
X569410Y6551D01*
X569455Y6431D01*
X569495Y6351D01*
X569520Y6316D01*
X569540Y6281D01*
X569570Y6246D01*
X569595Y6211D01*
X569625Y6181D01*
Y3756D01*
X569635Y3631D01*
X569675Y3506D01*
X569735Y3396D01*
X569815Y3296D01*
X569915Y3216D01*
X570025Y3156D01*
X570150Y3116D01*
X570275Y3106D01*
G37*
G36*
G01X565551D02*
X565676Y3116D01*
X565801Y3156D01*
X565911Y3216D01*
X566011Y3296D01*
X566091Y3396D01*
X566151Y3506D01*
X566191Y3631D01*
X566201Y3756D01*
Y6186D01*
X566231Y6216D01*
X566331Y6356D01*
X566351Y6396D01*
X566366Y6431D01*
X566386Y6471D01*
X566401Y6511D01*
X566411Y6551D01*
X566426Y6596D01*
X566431Y6636D01*
X566441Y6676D01*
X566446Y6721D01*
Y6761D01*
X566451Y6806D01*
X566446Y6851D01*
Y6891D01*
X566441Y6936D01*
X566431Y6976D01*
X566426Y7016D01*
X566411Y7061D01*
X566401Y7101D01*
X566386Y7141D01*
X566366Y7181D01*
X566351Y7216D01*
X566331Y7256D01*
X566231Y7396D01*
X566201Y7426D01*
Y9556D01*
X566191Y9681D01*
X566151Y9806D01*
X566091Y9916D01*
X566011Y10016D01*
X565911Y10096D01*
X565801Y10156D01*
X565676Y10196D01*
X565551Y10206D01*
X565426Y10196D01*
X565301Y10156D01*
X565191Y10096D01*
X565091Y10016D01*
X565011Y9916D01*
X564951Y9806D01*
X564911Y9681D01*
X564901Y9556D01*
Y7431D01*
X564871Y7401D01*
X564846Y7366D01*
X564816Y7331D01*
X564796Y7296D01*
X564771Y7261D01*
X564731Y7181D01*
X564686Y7061D01*
X564676Y7021D01*
X564666Y6976D01*
X564661Y6936D01*
X564651Y6891D01*
Y6721D01*
X564661Y6676D01*
X564666Y6636D01*
X564676Y6591D01*
X564686Y6551D01*
X564731Y6431D01*
X564771Y6351D01*
X564796Y6316D01*
X564816Y6281D01*
X564846Y6246D01*
X564871Y6211D01*
X564901Y6181D01*
Y3756D01*
X564911Y3631D01*
X564951Y3506D01*
X565011Y3396D01*
X565091Y3296D01*
X565191Y3216D01*
X565301Y3156D01*
X565426Y3116D01*
X565551Y3106D01*
G37*
G36*
G01X560827D02*
X560952Y3116D01*
X561077Y3156D01*
X561187Y3216D01*
X561287Y3296D01*
X561367Y3396D01*
X561427Y3506D01*
X561467Y3631D01*
X561477Y3756D01*
Y6186D01*
X561507Y6216D01*
X561607Y6356D01*
X561627Y6396D01*
X561642Y6431D01*
X561662Y6471D01*
X561677Y6511D01*
X561687Y6551D01*
X561702Y6596D01*
X561707Y6636D01*
X561717Y6676D01*
X561722Y6721D01*
Y6761D01*
X561727Y6806D01*
X561722Y6851D01*
Y6891D01*
X561717Y6936D01*
X561707Y6976D01*
X561702Y7016D01*
X561687Y7061D01*
X561677Y7101D01*
X561662Y7141D01*
X561642Y7181D01*
X561627Y7216D01*
X561607Y7256D01*
X561507Y7396D01*
X561477Y7426D01*
Y9556D01*
X561467Y9681D01*
X561427Y9806D01*
X561367Y9916D01*
X561287Y10016D01*
X561187Y10096D01*
X561077Y10156D01*
X560952Y10196D01*
X560827Y10206D01*
X560702Y10196D01*
X560577Y10156D01*
X560467Y10096D01*
X560367Y10016D01*
X560287Y9916D01*
X560227Y9806D01*
X560187Y9681D01*
X560177Y9556D01*
Y7431D01*
X560147Y7401D01*
X560122Y7366D01*
X560092Y7331D01*
X560072Y7296D01*
X560047Y7261D01*
X560007Y7181D01*
X559962Y7061D01*
X559952Y7021D01*
X559942Y6976D01*
X559937Y6936D01*
X559927Y6891D01*
Y6721D01*
X559937Y6676D01*
X559942Y6636D01*
X559952Y6591D01*
X559962Y6551D01*
X560007Y6431D01*
X560047Y6351D01*
X560072Y6316D01*
X560092Y6281D01*
X560122Y6246D01*
X560147Y6211D01*
X560177Y6181D01*
Y3756D01*
X560187Y3631D01*
X560227Y3506D01*
X560287Y3396D01*
X560367Y3296D01*
X560467Y3216D01*
X560577Y3156D01*
X560702Y3116D01*
X560827Y3106D01*
G37*
G36*
G01X584449D02*
X584574Y3116D01*
X584699Y3156D01*
X584809Y3216D01*
X584909Y3296D01*
X584989Y3396D01*
X585049Y3506D01*
X585089Y3631D01*
X585099Y3756D01*
Y6186D01*
X585129Y6216D01*
X585229Y6356D01*
X585249Y6396D01*
X585264Y6431D01*
X585284Y6471D01*
X585299Y6511D01*
X585309Y6551D01*
X585324Y6596D01*
X585329Y6636D01*
X585339Y6676D01*
X585344Y6721D01*
Y6761D01*
X585349Y6806D01*
X585344Y6851D01*
Y6891D01*
X585339Y6936D01*
X585329Y6976D01*
X585324Y7016D01*
X585309Y7061D01*
X585299Y7101D01*
X585284Y7141D01*
X585264Y7181D01*
X585249Y7216D01*
X585229Y7256D01*
X585129Y7396D01*
X585099Y7426D01*
Y9556D01*
X585089Y9681D01*
X585049Y9806D01*
X584989Y9916D01*
X584909Y10016D01*
X584809Y10096D01*
X584699Y10156D01*
X584574Y10196D01*
X584449Y10206D01*
X584324Y10196D01*
X584199Y10156D01*
X584089Y10096D01*
X583989Y10016D01*
X583909Y9916D01*
X583849Y9806D01*
X583809Y9681D01*
X583799Y9556D01*
Y7431D01*
X583769Y7401D01*
X583744Y7366D01*
X583714Y7331D01*
X583694Y7296D01*
X583669Y7261D01*
X583629Y7181D01*
X583584Y7061D01*
X583574Y7021D01*
X583564Y6976D01*
X583559Y6936D01*
X583549Y6891D01*
Y6721D01*
X583559Y6676D01*
X583564Y6636D01*
X583574Y6591D01*
X583584Y6551D01*
X583629Y6431D01*
X583669Y6351D01*
X583694Y6316D01*
X583714Y6281D01*
X583744Y6246D01*
X583769Y6211D01*
X583799Y6181D01*
Y3756D01*
X583809Y3631D01*
X583849Y3506D01*
X583909Y3396D01*
X583989Y3296D01*
X584089Y3216D01*
X584199Y3156D01*
X584324Y3116D01*
X584449Y3106D01*
G37*
G36*
G01X579724D02*
X579849Y3116D01*
X579974Y3156D01*
X580084Y3216D01*
X580184Y3296D01*
X580264Y3396D01*
X580324Y3506D01*
X580364Y3631D01*
X580374Y3756D01*
Y6186D01*
X580404Y6216D01*
X580504Y6356D01*
X580524Y6396D01*
X580539Y6431D01*
X580559Y6471D01*
X580574Y6511D01*
X580584Y6551D01*
X580599Y6596D01*
X580604Y6636D01*
X580614Y6676D01*
X580619Y6721D01*
Y6761D01*
X580624Y6806D01*
X580619Y6851D01*
Y6891D01*
X580614Y6936D01*
X580604Y6976D01*
X580599Y7016D01*
X580584Y7061D01*
X580574Y7101D01*
X580559Y7141D01*
X580539Y7181D01*
X580524Y7216D01*
X580504Y7256D01*
X580404Y7396D01*
X580374Y7426D01*
Y9556D01*
X580364Y9681D01*
X580324Y9806D01*
X580264Y9916D01*
X580184Y10016D01*
X580084Y10096D01*
X579974Y10156D01*
X579849Y10196D01*
X579724Y10206D01*
X579599Y10196D01*
X579474Y10156D01*
X579364Y10096D01*
X579264Y10016D01*
X579184Y9916D01*
X579124Y9806D01*
X579084Y9681D01*
X579074Y9556D01*
Y7431D01*
X579044Y7401D01*
X579019Y7366D01*
X578989Y7331D01*
X578969Y7296D01*
X578944Y7261D01*
X578904Y7181D01*
X578859Y7061D01*
X578849Y7021D01*
X578839Y6976D01*
X578834Y6936D01*
X578824Y6891D01*
Y6721D01*
X578834Y6676D01*
X578839Y6636D01*
X578849Y6591D01*
X578859Y6551D01*
X578904Y6431D01*
X578944Y6351D01*
X578969Y6316D01*
X578989Y6281D01*
X579019Y6246D01*
X579044Y6211D01*
X579074Y6181D01*
Y3756D01*
X579084Y3631D01*
X579124Y3506D01*
X579184Y3396D01*
X579264Y3296D01*
X579364Y3216D01*
X579474Y3156D01*
X579599Y3116D01*
X579724Y3106D01*
G37*
G36*
G01X575000D02*
X575125Y3116D01*
X575250Y3156D01*
X575360Y3216D01*
X575460Y3296D01*
X575540Y3396D01*
X575600Y3506D01*
X575640Y3631D01*
X575650Y3756D01*
Y6186D01*
X575680Y6216D01*
X575780Y6356D01*
X575800Y6396D01*
X575815Y6431D01*
X575835Y6471D01*
X575850Y6511D01*
X575860Y6551D01*
X575875Y6596D01*
X575880Y6636D01*
X575890Y6676D01*
X575895Y6721D01*
Y6761D01*
X575900Y6806D01*
X575895Y6851D01*
Y6891D01*
X575890Y6936D01*
X575880Y6976D01*
X575875Y7016D01*
X575860Y7061D01*
X575850Y7101D01*
X575835Y7141D01*
X575815Y7181D01*
X575800Y7216D01*
X575780Y7256D01*
X575680Y7396D01*
X575650Y7426D01*
Y9556D01*
X575640Y9681D01*
X575600Y9806D01*
X575540Y9916D01*
X575460Y10016D01*
X575360Y10096D01*
X575250Y10156D01*
X575125Y10196D01*
X575000Y10206D01*
X574875Y10196D01*
X574750Y10156D01*
X574640Y10096D01*
X574540Y10016D01*
X574460Y9916D01*
X574400Y9806D01*
X574360Y9681D01*
X574350Y9556D01*
Y7431D01*
X574320Y7401D01*
X574295Y7366D01*
X574265Y7331D01*
X574245Y7296D01*
X574220Y7261D01*
X574180Y7181D01*
X574135Y7061D01*
X574125Y7021D01*
X574115Y6976D01*
X574110Y6936D01*
X574100Y6891D01*
Y6721D01*
X574110Y6676D01*
X574115Y6636D01*
X574125Y6591D01*
X574135Y6551D01*
X574180Y6431D01*
X574220Y6351D01*
X574245Y6316D01*
X574265Y6281D01*
X574295Y6246D01*
X574320Y6211D01*
X574350Y6181D01*
Y3756D01*
X574360Y3631D01*
X574400Y3506D01*
X574460Y3396D01*
X574540Y3296D01*
X574640Y3216D01*
X574750Y3156D01*
X574875Y3116D01*
X575000Y3106D01*
G37*
G36*
G01X603346D02*
X603471Y3116D01*
X603596Y3156D01*
X603706Y3216D01*
X603806Y3296D01*
X603886Y3396D01*
X603946Y3506D01*
X603986Y3631D01*
X603996Y3756D01*
Y6186D01*
X604026Y6216D01*
X604126Y6356D01*
X604146Y6396D01*
X604161Y6431D01*
X604181Y6471D01*
X604196Y6511D01*
X604206Y6551D01*
X604221Y6596D01*
X604226Y6636D01*
X604236Y6676D01*
X604241Y6721D01*
Y6761D01*
X604246Y6806D01*
X604241Y6851D01*
Y6891D01*
X604236Y6936D01*
X604226Y6976D01*
X604221Y7016D01*
X604206Y7061D01*
X604196Y7101D01*
X604181Y7141D01*
X604161Y7181D01*
X604146Y7216D01*
X604126Y7256D01*
X604026Y7396D01*
X603996Y7426D01*
Y9556D01*
X603986Y9681D01*
X603946Y9806D01*
X603886Y9916D01*
X603806Y10016D01*
X603706Y10096D01*
X603596Y10156D01*
X603471Y10196D01*
X603346Y10206D01*
X603221Y10196D01*
X603096Y10156D01*
X602986Y10096D01*
X602886Y10016D01*
X602806Y9916D01*
X602746Y9806D01*
X602706Y9681D01*
X602696Y9556D01*
Y7431D01*
X602666Y7401D01*
X602641Y7366D01*
X602611Y7331D01*
X602591Y7296D01*
X602566Y7261D01*
X602526Y7181D01*
X602481Y7061D01*
X602471Y7021D01*
X602461Y6976D01*
X602456Y6936D01*
X602446Y6891D01*
Y6721D01*
X602456Y6676D01*
X602461Y6636D01*
X602471Y6591D01*
X602481Y6551D01*
X602526Y6431D01*
X602566Y6351D01*
X602591Y6316D01*
X602611Y6281D01*
X602641Y6246D01*
X602666Y6211D01*
X602696Y6181D01*
Y3756D01*
X602706Y3631D01*
X602746Y3506D01*
X602806Y3396D01*
X602886Y3296D01*
X602986Y3216D01*
X603096Y3156D01*
X603221Y3116D01*
X603346Y3106D01*
G37*
G36*
G01X589173D02*
X589298Y3116D01*
X589423Y3156D01*
X589533Y3216D01*
X589633Y3296D01*
X589713Y3396D01*
X589773Y3506D01*
X589813Y3631D01*
X589823Y3756D01*
Y6186D01*
X589853Y6216D01*
X589953Y6356D01*
X589973Y6396D01*
X589988Y6431D01*
X590008Y6471D01*
X590023Y6511D01*
X590033Y6551D01*
X590048Y6596D01*
X590053Y6636D01*
X590063Y6676D01*
X590068Y6721D01*
Y6761D01*
X590073Y6806D01*
X590068Y6851D01*
Y6891D01*
X590063Y6936D01*
X590053Y6976D01*
X590048Y7016D01*
X590033Y7061D01*
X590023Y7101D01*
X590008Y7141D01*
X589988Y7181D01*
X589973Y7216D01*
X589953Y7256D01*
X589853Y7396D01*
X589823Y7426D01*
Y9556D01*
X589813Y9681D01*
X589773Y9806D01*
X589713Y9916D01*
X589633Y10016D01*
X589533Y10096D01*
X589423Y10156D01*
X589298Y10196D01*
X589173Y10206D01*
X589048Y10196D01*
X588923Y10156D01*
X588813Y10096D01*
X588713Y10016D01*
X588633Y9916D01*
X588573Y9806D01*
X588533Y9681D01*
X588523Y9556D01*
Y7431D01*
X588493Y7401D01*
X588468Y7366D01*
X588438Y7331D01*
X588418Y7296D01*
X588393Y7261D01*
X588353Y7181D01*
X588308Y7061D01*
X588298Y7021D01*
X588288Y6976D01*
X588283Y6936D01*
X588273Y6891D01*
Y6721D01*
X588283Y6676D01*
X588288Y6636D01*
X588298Y6591D01*
X588308Y6551D01*
X588353Y6431D01*
X588393Y6351D01*
X588418Y6316D01*
X588438Y6281D01*
X588468Y6246D01*
X588493Y6211D01*
X588523Y6181D01*
Y3756D01*
X588533Y3631D01*
X588573Y3506D01*
X588633Y3396D01*
X588713Y3296D01*
X588813Y3216D01*
X588923Y3156D01*
X589048Y3116D01*
X589173Y3106D01*
G37*
G36*
G01X617519D02*
X617644Y3116D01*
X617769Y3156D01*
X617879Y3216D01*
X617979Y3296D01*
X618059Y3396D01*
X618119Y3506D01*
X618159Y3631D01*
X618169Y3756D01*
Y6186D01*
X618199Y6216D01*
X618299Y6356D01*
X618319Y6396D01*
X618334Y6431D01*
X618354Y6471D01*
X618369Y6511D01*
X618379Y6551D01*
X618394Y6596D01*
X618399Y6636D01*
X618409Y6676D01*
X618414Y6721D01*
Y6761D01*
X618419Y6806D01*
X618414Y6851D01*
Y6891D01*
X618409Y6936D01*
X618399Y6976D01*
X618394Y7016D01*
X618379Y7061D01*
X618369Y7101D01*
X618354Y7141D01*
X618334Y7181D01*
X618319Y7216D01*
X618299Y7256D01*
X618199Y7396D01*
X618169Y7426D01*
Y9556D01*
X618159Y9681D01*
X618119Y9806D01*
X618059Y9916D01*
X617979Y10016D01*
X617879Y10096D01*
X617769Y10156D01*
X617644Y10196D01*
X617519Y10206D01*
X617394Y10196D01*
X617269Y10156D01*
X617159Y10096D01*
X617059Y10016D01*
X616979Y9916D01*
X616919Y9806D01*
X616879Y9681D01*
X616869Y9556D01*
Y7431D01*
X616839Y7401D01*
X616814Y7366D01*
X616784Y7331D01*
X616764Y7296D01*
X616739Y7261D01*
X616699Y7181D01*
X616654Y7061D01*
X616644Y7021D01*
X616634Y6976D01*
X616629Y6936D01*
X616619Y6891D01*
Y6721D01*
X616629Y6676D01*
X616634Y6636D01*
X616644Y6591D01*
X616654Y6551D01*
X616699Y6431D01*
X616739Y6351D01*
X616764Y6316D01*
X616784Y6281D01*
X616814Y6246D01*
X616839Y6211D01*
X616869Y6181D01*
Y3756D01*
X616879Y3631D01*
X616919Y3506D01*
X616979Y3396D01*
X617059Y3296D01*
X617159Y3216D01*
X617269Y3156D01*
X617394Y3116D01*
X617519Y3106D01*
G37*
G36*
G01X612795D02*
X612920Y3116D01*
X613045Y3156D01*
X613155Y3216D01*
X613255Y3296D01*
X613335Y3396D01*
X613395Y3506D01*
X613435Y3631D01*
X613445Y3756D01*
Y6186D01*
X613475Y6216D01*
X613575Y6356D01*
X613595Y6396D01*
X613610Y6431D01*
X613630Y6471D01*
X613645Y6511D01*
X613655Y6551D01*
X613670Y6596D01*
X613675Y6636D01*
X613685Y6676D01*
X613690Y6721D01*
Y6761D01*
X613695Y6806D01*
X613690Y6851D01*
Y6891D01*
X613685Y6936D01*
X613675Y6976D01*
X613670Y7016D01*
X613655Y7061D01*
X613645Y7101D01*
X613630Y7141D01*
X613610Y7181D01*
X613595Y7216D01*
X613575Y7256D01*
X613475Y7396D01*
X613445Y7426D01*
Y9556D01*
X613435Y9681D01*
X613395Y9806D01*
X613335Y9916D01*
X613255Y10016D01*
X613155Y10096D01*
X613045Y10156D01*
X612920Y10196D01*
X612795Y10206D01*
X612670Y10196D01*
X612545Y10156D01*
X612435Y10096D01*
X612335Y10016D01*
X612255Y9916D01*
X612195Y9806D01*
X612155Y9681D01*
X612145Y9556D01*
Y7431D01*
X612115Y7401D01*
X612090Y7366D01*
X612060Y7331D01*
X612040Y7296D01*
X612015Y7261D01*
X611975Y7181D01*
X611930Y7061D01*
X611920Y7021D01*
X611910Y6976D01*
X611905Y6936D01*
X611895Y6891D01*
Y6721D01*
X611905Y6676D01*
X611910Y6636D01*
X611920Y6591D01*
X611930Y6551D01*
X611975Y6431D01*
X612015Y6351D01*
X612040Y6316D01*
X612060Y6281D01*
X612090Y6246D01*
X612115Y6211D01*
X612145Y6181D01*
Y3756D01*
X612155Y3631D01*
X612195Y3506D01*
X612255Y3396D01*
X612335Y3296D01*
X612435Y3216D01*
X612545Y3156D01*
X612670Y3116D01*
X612795Y3106D01*
G37*
G36*
G01X608071D02*
X608196Y3116D01*
X608321Y3156D01*
X608431Y3216D01*
X608531Y3296D01*
X608611Y3396D01*
X608671Y3506D01*
X608711Y3631D01*
X608721Y3756D01*
Y6186D01*
X608751Y6216D01*
X608851Y6356D01*
X608871Y6396D01*
X608886Y6431D01*
X608906Y6471D01*
X608921Y6511D01*
X608931Y6551D01*
X608946Y6596D01*
X608951Y6636D01*
X608961Y6676D01*
X608966Y6721D01*
Y6761D01*
X608971Y6806D01*
X608966Y6851D01*
Y6891D01*
X608961Y6936D01*
X608951Y6976D01*
X608946Y7016D01*
X608931Y7061D01*
X608921Y7101D01*
X608906Y7141D01*
X608886Y7181D01*
X608871Y7216D01*
X608851Y7256D01*
X608751Y7396D01*
X608721Y7426D01*
Y9556D01*
X608711Y9681D01*
X608671Y9806D01*
X608611Y9916D01*
X608531Y10016D01*
X608431Y10096D01*
X608321Y10156D01*
X608196Y10196D01*
X608071Y10206D01*
X607946Y10196D01*
X607821Y10156D01*
X607711Y10096D01*
X607611Y10016D01*
X607531Y9916D01*
X607471Y9806D01*
X607431Y9681D01*
X607421Y9556D01*
Y7431D01*
X607391Y7401D01*
X607366Y7366D01*
X607336Y7331D01*
X607316Y7296D01*
X607291Y7261D01*
X607251Y7181D01*
X607206Y7061D01*
X607196Y7021D01*
X607186Y6976D01*
X607181Y6936D01*
X607171Y6891D01*
Y6721D01*
X607181Y6676D01*
X607186Y6636D01*
X607196Y6591D01*
X607206Y6551D01*
X607251Y6431D01*
X607291Y6351D01*
X607316Y6316D01*
X607336Y6281D01*
X607366Y6246D01*
X607391Y6211D01*
X607421Y6181D01*
Y3756D01*
X607431Y3631D01*
X607471Y3506D01*
X607531Y3396D01*
X607611Y3296D01*
X607711Y3216D01*
X607821Y3156D01*
X607946Y3116D01*
X608071Y3106D01*
G37*
G36*
G01X631693D02*
X631818Y3116D01*
X631943Y3156D01*
X632053Y3216D01*
X632153Y3296D01*
X632233Y3396D01*
X632293Y3506D01*
X632333Y3631D01*
X632343Y3756D01*
Y6186D01*
X632373Y6216D01*
X632473Y6356D01*
X632493Y6396D01*
X632508Y6431D01*
X632528Y6471D01*
X632543Y6511D01*
X632553Y6551D01*
X632568Y6596D01*
X632573Y6636D01*
X632583Y6676D01*
X632588Y6721D01*
Y6761D01*
X632593Y6806D01*
X632588Y6851D01*
Y6891D01*
X632583Y6936D01*
X632573Y6976D01*
X632568Y7016D01*
X632553Y7061D01*
X632543Y7101D01*
X632528Y7141D01*
X632508Y7181D01*
X632493Y7216D01*
X632473Y7256D01*
X632373Y7396D01*
X632343Y7426D01*
Y9556D01*
X632333Y9681D01*
X632293Y9806D01*
X632233Y9916D01*
X632153Y10016D01*
X632053Y10096D01*
X631943Y10156D01*
X631818Y10196D01*
X631693Y10206D01*
X631568Y10196D01*
X631443Y10156D01*
X631333Y10096D01*
X631233Y10016D01*
X631153Y9916D01*
X631093Y9806D01*
X631053Y9681D01*
X631043Y9556D01*
Y7431D01*
X631013Y7401D01*
X630988Y7366D01*
X630958Y7331D01*
X630938Y7296D01*
X630913Y7261D01*
X630873Y7181D01*
X630828Y7061D01*
X630818Y7021D01*
X630808Y6976D01*
X630803Y6936D01*
X630793Y6891D01*
Y6721D01*
X630803Y6676D01*
X630808Y6636D01*
X630818Y6591D01*
X630828Y6551D01*
X630873Y6431D01*
X630913Y6351D01*
X630938Y6316D01*
X630958Y6281D01*
X630988Y6246D01*
X631013Y6211D01*
X631043Y6181D01*
Y3756D01*
X631053Y3631D01*
X631093Y3506D01*
X631153Y3396D01*
X631233Y3296D01*
X631333Y3216D01*
X631443Y3156D01*
X631568Y3116D01*
X631693Y3106D01*
G37*
G36*
G01X626968D02*
X627093Y3116D01*
X627218Y3156D01*
X627328Y3216D01*
X627428Y3296D01*
X627508Y3396D01*
X627568Y3506D01*
X627608Y3631D01*
X627618Y3756D01*
Y6186D01*
X627648Y6216D01*
X627748Y6356D01*
X627768Y6396D01*
X627783Y6431D01*
X627803Y6471D01*
X627818Y6511D01*
X627828Y6551D01*
X627843Y6596D01*
X627848Y6636D01*
X627858Y6676D01*
X627863Y6721D01*
Y6761D01*
X627868Y6806D01*
X627863Y6851D01*
Y6891D01*
X627858Y6936D01*
X627848Y6976D01*
X627843Y7016D01*
X627828Y7061D01*
X627818Y7101D01*
X627803Y7141D01*
X627783Y7181D01*
X627768Y7216D01*
X627748Y7256D01*
X627648Y7396D01*
X627618Y7426D01*
Y9556D01*
X627608Y9681D01*
X627568Y9806D01*
X627508Y9916D01*
X627428Y10016D01*
X627328Y10096D01*
X627218Y10156D01*
X627093Y10196D01*
X626968Y10206D01*
X626843Y10196D01*
X626718Y10156D01*
X626608Y10096D01*
X626508Y10016D01*
X626428Y9916D01*
X626368Y9806D01*
X626328Y9681D01*
X626318Y9556D01*
Y7431D01*
X626288Y7401D01*
X626263Y7366D01*
X626233Y7331D01*
X626213Y7296D01*
X626188Y7261D01*
X626148Y7181D01*
X626103Y7061D01*
X626093Y7021D01*
X626083Y6976D01*
X626078Y6936D01*
X626068Y6891D01*
Y6721D01*
X626078Y6676D01*
X626083Y6636D01*
X626093Y6591D01*
X626103Y6551D01*
X626148Y6431D01*
X626188Y6351D01*
X626213Y6316D01*
X626233Y6281D01*
X626263Y6246D01*
X626288Y6211D01*
X626318Y6181D01*
Y3756D01*
X626328Y3631D01*
X626368Y3506D01*
X626428Y3396D01*
X626508Y3296D01*
X626608Y3216D01*
X626718Y3156D01*
X626843Y3116D01*
X626968Y3106D01*
G37*
G36*
G01X622244D02*
X622369Y3116D01*
X622494Y3156D01*
X622604Y3216D01*
X622704Y3296D01*
X622784Y3396D01*
X622844Y3506D01*
X622884Y3631D01*
X622894Y3756D01*
Y6186D01*
X622924Y6216D01*
X623024Y6356D01*
X623044Y6396D01*
X623059Y6431D01*
X623079Y6471D01*
X623094Y6511D01*
X623104Y6551D01*
X623119Y6596D01*
X623124Y6636D01*
X623134Y6676D01*
X623139Y6721D01*
Y6761D01*
X623144Y6806D01*
X623139Y6851D01*
Y6891D01*
X623134Y6936D01*
X623124Y6976D01*
X623119Y7016D01*
X623104Y7061D01*
X623094Y7101D01*
X623079Y7141D01*
X623059Y7181D01*
X623044Y7216D01*
X623024Y7256D01*
X622924Y7396D01*
X622894Y7426D01*
Y9556D01*
X622884Y9681D01*
X622844Y9806D01*
X622784Y9916D01*
X622704Y10016D01*
X622604Y10096D01*
X622494Y10156D01*
X622369Y10196D01*
X622244Y10206D01*
X622119Y10196D01*
X621994Y10156D01*
X621884Y10096D01*
X621784Y10016D01*
X621704Y9916D01*
X621644Y9806D01*
X621604Y9681D01*
X621594Y9556D01*
Y7431D01*
X621564Y7401D01*
X621539Y7366D01*
X621509Y7331D01*
X621489Y7296D01*
X621464Y7261D01*
X621424Y7181D01*
X621379Y7061D01*
X621369Y7021D01*
X621359Y6976D01*
X621354Y6936D01*
X621344Y6891D01*
Y6721D01*
X621354Y6676D01*
X621359Y6636D01*
X621369Y6591D01*
X621379Y6551D01*
X621424Y6431D01*
X621464Y6351D01*
X621489Y6316D01*
X621509Y6281D01*
X621539Y6246D01*
X621564Y6211D01*
X621594Y6181D01*
Y3756D01*
X621604Y3631D01*
X621644Y3506D01*
X621704Y3396D01*
X621784Y3296D01*
X621884Y3216D01*
X621994Y3156D01*
X622119Y3116D01*
X622244Y3106D01*
G37*
G36*
G01X645866D02*
X645991Y3116D01*
X646116Y3156D01*
X646226Y3216D01*
X646326Y3296D01*
X646406Y3396D01*
X646466Y3506D01*
X646506Y3631D01*
X646516Y3756D01*
Y6186D01*
X646546Y6216D01*
X646646Y6356D01*
X646666Y6396D01*
X646681Y6431D01*
X646701Y6471D01*
X646716Y6511D01*
X646726Y6551D01*
X646741Y6596D01*
X646746Y6636D01*
X646756Y6676D01*
X646761Y6721D01*
Y6761D01*
X646766Y6806D01*
X646761Y6851D01*
Y6891D01*
X646756Y6936D01*
X646746Y6976D01*
X646741Y7016D01*
X646726Y7061D01*
X646716Y7101D01*
X646701Y7141D01*
X646681Y7181D01*
X646666Y7216D01*
X646646Y7256D01*
X646546Y7396D01*
X646516Y7426D01*
Y9556D01*
X646506Y9681D01*
X646466Y9806D01*
X646406Y9916D01*
X646326Y10016D01*
X646226Y10096D01*
X646116Y10156D01*
X645991Y10196D01*
X645866Y10206D01*
X645741Y10196D01*
X645616Y10156D01*
X645506Y10096D01*
X645406Y10016D01*
X645326Y9916D01*
X645266Y9806D01*
X645226Y9681D01*
X645216Y9556D01*
Y7431D01*
X645186Y7401D01*
X645161Y7366D01*
X645131Y7331D01*
X645111Y7296D01*
X645086Y7261D01*
X645046Y7181D01*
X645001Y7061D01*
X644991Y7021D01*
X644981Y6976D01*
X644976Y6936D01*
X644966Y6891D01*
Y6721D01*
X644976Y6676D01*
X644981Y6636D01*
X644991Y6591D01*
X645001Y6551D01*
X645046Y6431D01*
X645086Y6351D01*
X645111Y6316D01*
X645131Y6281D01*
X645161Y6246D01*
X645186Y6211D01*
X645216Y6181D01*
Y3756D01*
X645226Y3631D01*
X645266Y3506D01*
X645326Y3396D01*
X645406Y3296D01*
X645506Y3216D01*
X645616Y3156D01*
X645741Y3116D01*
X645866Y3106D01*
G37*
G36*
G01X641141D02*
X641266Y3116D01*
X641391Y3156D01*
X641501Y3216D01*
X641601Y3296D01*
X641681Y3396D01*
X641741Y3506D01*
X641781Y3631D01*
X641791Y3756D01*
Y6186D01*
X641821Y6216D01*
X641921Y6356D01*
X641941Y6396D01*
X641956Y6431D01*
X641976Y6471D01*
X641991Y6511D01*
X642001Y6551D01*
X642016Y6596D01*
X642021Y6636D01*
X642031Y6676D01*
X642036Y6721D01*
Y6761D01*
X642041Y6806D01*
X642036Y6851D01*
Y6891D01*
X642031Y6936D01*
X642021Y6976D01*
X642016Y7016D01*
X642001Y7061D01*
X641991Y7101D01*
X641976Y7141D01*
X641956Y7181D01*
X641941Y7216D01*
X641921Y7256D01*
X641821Y7396D01*
X641791Y7426D01*
Y9556D01*
X641781Y9681D01*
X641741Y9806D01*
X641681Y9916D01*
X641601Y10016D01*
X641501Y10096D01*
X641391Y10156D01*
X641266Y10196D01*
X641141Y10206D01*
X641016Y10196D01*
X640891Y10156D01*
X640781Y10096D01*
X640681Y10016D01*
X640601Y9916D01*
X640541Y9806D01*
X640501Y9681D01*
X640491Y9556D01*
Y7431D01*
X640461Y7401D01*
X640436Y7366D01*
X640406Y7331D01*
X640386Y7296D01*
X640361Y7261D01*
X640321Y7181D01*
X640276Y7061D01*
X640266Y7021D01*
X640256Y6976D01*
X640251Y6936D01*
X640241Y6891D01*
Y6721D01*
X640251Y6676D01*
X640256Y6636D01*
X640266Y6591D01*
X640276Y6551D01*
X640321Y6431D01*
X640361Y6351D01*
X640386Y6316D01*
X640406Y6281D01*
X640436Y6246D01*
X640461Y6211D01*
X640491Y6181D01*
Y3756D01*
X640501Y3631D01*
X640541Y3506D01*
X640601Y3396D01*
X640681Y3296D01*
X640781Y3216D01*
X640891Y3156D01*
X641016Y3116D01*
X641141Y3106D01*
G37*
G36*
G01X636417D02*
X636542Y3116D01*
X636667Y3156D01*
X636777Y3216D01*
X636877Y3296D01*
X636957Y3396D01*
X637017Y3506D01*
X637057Y3631D01*
X637067Y3756D01*
Y6186D01*
X637097Y6216D01*
X637197Y6356D01*
X637217Y6396D01*
X637232Y6431D01*
X637252Y6471D01*
X637267Y6511D01*
X637277Y6551D01*
X637292Y6596D01*
X637297Y6636D01*
X637307Y6676D01*
X637312Y6721D01*
Y6761D01*
X637317Y6806D01*
X637312Y6851D01*
Y6891D01*
X637307Y6936D01*
X637297Y6976D01*
X637292Y7016D01*
X637277Y7061D01*
X637267Y7101D01*
X637252Y7141D01*
X637232Y7181D01*
X637217Y7216D01*
X637197Y7256D01*
X637097Y7396D01*
X637067Y7426D01*
Y9556D01*
X637057Y9681D01*
X637017Y9806D01*
X636957Y9916D01*
X636877Y10016D01*
X636777Y10096D01*
X636667Y10156D01*
X636542Y10196D01*
X636417Y10206D01*
X636292Y10196D01*
X636167Y10156D01*
X636057Y10096D01*
X635957Y10016D01*
X635877Y9916D01*
X635817Y9806D01*
X635777Y9681D01*
X635767Y9556D01*
Y7431D01*
X635737Y7401D01*
X635712Y7366D01*
X635682Y7331D01*
X635662Y7296D01*
X635637Y7261D01*
X635597Y7181D01*
X635552Y7061D01*
X635542Y7021D01*
X635532Y6976D01*
X635527Y6936D01*
X635517Y6891D01*
Y6721D01*
X635527Y6676D01*
X635532Y6636D01*
X635542Y6591D01*
X635552Y6551D01*
X635597Y6431D01*
X635637Y6351D01*
X635662Y6316D01*
X635682Y6281D01*
X635712Y6246D01*
X635737Y6211D01*
X635767Y6181D01*
Y3756D01*
X635777Y3631D01*
X635817Y3506D01*
X635877Y3396D01*
X635957Y3296D01*
X636057Y3216D01*
X636167Y3156D01*
X636292Y3116D01*
X636417Y3106D01*
G37*
G36*
G01X664764D02*
X664889Y3116D01*
X665014Y3156D01*
X665124Y3216D01*
X665224Y3296D01*
X665304Y3396D01*
X665364Y3506D01*
X665404Y3631D01*
X665414Y3756D01*
Y6186D01*
X665444Y6216D01*
X665544Y6356D01*
X665564Y6396D01*
X665579Y6431D01*
X665599Y6471D01*
X665614Y6511D01*
X665624Y6551D01*
X665639Y6596D01*
X665644Y6636D01*
X665654Y6676D01*
X665659Y6721D01*
Y6761D01*
X665664Y6806D01*
X665659Y6851D01*
Y6891D01*
X665654Y6936D01*
X665644Y6976D01*
X665639Y7016D01*
X665624Y7061D01*
X665614Y7101D01*
X665599Y7141D01*
X665579Y7181D01*
X665564Y7216D01*
X665544Y7256D01*
X665444Y7396D01*
X665414Y7426D01*
Y9556D01*
X665404Y9681D01*
X665364Y9806D01*
X665304Y9916D01*
X665224Y10016D01*
X665124Y10096D01*
X665014Y10156D01*
X664889Y10196D01*
X664764Y10206D01*
X664639Y10196D01*
X664514Y10156D01*
X664404Y10096D01*
X664304Y10016D01*
X664224Y9916D01*
X664164Y9806D01*
X664124Y9681D01*
X664114Y9556D01*
Y7431D01*
X664084Y7401D01*
X664059Y7366D01*
X664029Y7331D01*
X664009Y7296D01*
X663984Y7261D01*
X663944Y7181D01*
X663899Y7061D01*
X663889Y7021D01*
X663879Y6976D01*
X663874Y6936D01*
X663864Y6891D01*
Y6721D01*
X663874Y6676D01*
X663879Y6636D01*
X663889Y6591D01*
X663899Y6551D01*
X663944Y6431D01*
X663984Y6351D01*
X664009Y6316D01*
X664029Y6281D01*
X664059Y6246D01*
X664084Y6211D01*
X664114Y6181D01*
Y3756D01*
X664124Y3631D01*
X664164Y3506D01*
X664224Y3396D01*
X664304Y3296D01*
X664404Y3216D01*
X664514Y3156D01*
X664639Y3116D01*
X664764Y3106D01*
G37*
G36*
G01X660039D02*
X660164Y3116D01*
X660289Y3156D01*
X660399Y3216D01*
X660499Y3296D01*
X660579Y3396D01*
X660639Y3506D01*
X660679Y3631D01*
X660689Y3756D01*
Y6186D01*
X660719Y6216D01*
X660819Y6356D01*
X660839Y6396D01*
X660854Y6431D01*
X660874Y6471D01*
X660889Y6511D01*
X660899Y6551D01*
X660914Y6596D01*
X660919Y6636D01*
X660929Y6676D01*
X660934Y6721D01*
Y6761D01*
X660939Y6806D01*
X660934Y6851D01*
Y6891D01*
X660929Y6936D01*
X660919Y6976D01*
X660914Y7016D01*
X660899Y7061D01*
X660889Y7101D01*
X660874Y7141D01*
X660854Y7181D01*
X660839Y7216D01*
X660819Y7256D01*
X660719Y7396D01*
X660689Y7426D01*
Y9556D01*
X660679Y9681D01*
X660639Y9806D01*
X660579Y9916D01*
X660499Y10016D01*
X660399Y10096D01*
X660289Y10156D01*
X660164Y10196D01*
X660039Y10206D01*
X659914Y10196D01*
X659789Y10156D01*
X659679Y10096D01*
X659579Y10016D01*
X659499Y9916D01*
X659439Y9806D01*
X659399Y9681D01*
X659389Y9556D01*
Y7431D01*
X659359Y7401D01*
X659334Y7366D01*
X659304Y7331D01*
X659284Y7296D01*
X659259Y7261D01*
X659219Y7181D01*
X659174Y7061D01*
X659164Y7021D01*
X659154Y6976D01*
X659149Y6936D01*
X659139Y6891D01*
Y6721D01*
X659149Y6676D01*
X659154Y6636D01*
X659164Y6591D01*
X659174Y6551D01*
X659219Y6431D01*
X659259Y6351D01*
X659284Y6316D01*
X659304Y6281D01*
X659334Y6246D01*
X659359Y6211D01*
X659389Y6181D01*
Y3756D01*
X659399Y3631D01*
X659439Y3506D01*
X659499Y3396D01*
X659579Y3296D01*
X659679Y3216D01*
X659789Y3156D01*
X659914Y3116D01*
X660039Y3106D01*
G37*
G36*
G01X655315D02*
X655440Y3116D01*
X655565Y3156D01*
X655675Y3216D01*
X655775Y3296D01*
X655855Y3396D01*
X655915Y3506D01*
X655955Y3631D01*
X655965Y3756D01*
Y6186D01*
X655995Y6216D01*
X656095Y6356D01*
X656115Y6396D01*
X656130Y6431D01*
X656150Y6471D01*
X656165Y6511D01*
X656175Y6551D01*
X656190Y6596D01*
X656195Y6636D01*
X656205Y6676D01*
X656210Y6721D01*
Y6761D01*
X656215Y6806D01*
X656210Y6851D01*
Y6891D01*
X656205Y6936D01*
X656195Y6976D01*
X656190Y7016D01*
X656175Y7061D01*
X656165Y7101D01*
X656150Y7141D01*
X656130Y7181D01*
X656115Y7216D01*
X656095Y7256D01*
X655995Y7396D01*
X655965Y7426D01*
Y9556D01*
X655955Y9681D01*
X655915Y9806D01*
X655855Y9916D01*
X655775Y10016D01*
X655675Y10096D01*
X655565Y10156D01*
X655440Y10196D01*
X655315Y10206D01*
X655190Y10196D01*
X655065Y10156D01*
X654955Y10096D01*
X654855Y10016D01*
X654775Y9916D01*
X654715Y9806D01*
X654675Y9681D01*
X654665Y9556D01*
Y7431D01*
X654635Y7401D01*
X654610Y7366D01*
X654580Y7331D01*
X654560Y7296D01*
X654535Y7261D01*
X654495Y7181D01*
X654450Y7061D01*
X654440Y7021D01*
X654430Y6976D01*
X654425Y6936D01*
X654415Y6891D01*
Y6721D01*
X654425Y6676D01*
X654430Y6636D01*
X654440Y6591D01*
X654450Y6551D01*
X654495Y6431D01*
X654535Y6351D01*
X654560Y6316D01*
X654580Y6281D01*
X654610Y6246D01*
X654635Y6211D01*
X654665Y6181D01*
Y3756D01*
X654675Y3631D01*
X654715Y3506D01*
X654775Y3396D01*
X654855Y3296D01*
X654955Y3216D01*
X655065Y3156D01*
X655190Y3116D01*
X655315Y3106D01*
G37*
G36*
G01X650590D02*
X650715Y3116D01*
X650840Y3156D01*
X650950Y3216D01*
X651050Y3296D01*
X651130Y3396D01*
X651190Y3506D01*
X651230Y3631D01*
X651240Y3756D01*
Y6186D01*
X651270Y6216D01*
X651370Y6356D01*
X651390Y6396D01*
X651405Y6431D01*
X651425Y6471D01*
X651440Y6511D01*
X651450Y6551D01*
X651465Y6596D01*
X651470Y6636D01*
X651480Y6676D01*
X651485Y6721D01*
Y6761D01*
X651490Y6806D01*
X651485Y6851D01*
Y6891D01*
X651480Y6936D01*
X651470Y6976D01*
X651465Y7016D01*
X651450Y7061D01*
X651440Y7101D01*
X651425Y7141D01*
X651405Y7181D01*
X651390Y7216D01*
X651370Y7256D01*
X651270Y7396D01*
X651240Y7426D01*
Y9556D01*
X651230Y9681D01*
X651190Y9806D01*
X651130Y9916D01*
X651050Y10016D01*
X650950Y10096D01*
X650840Y10156D01*
X650715Y10196D01*
X650590Y10206D01*
X650465Y10196D01*
X650340Y10156D01*
X650230Y10096D01*
X650130Y10016D01*
X650050Y9916D01*
X649990Y9806D01*
X649950Y9681D01*
X649940Y9556D01*
Y7431D01*
X649910Y7401D01*
X649885Y7366D01*
X649855Y7331D01*
X649835Y7296D01*
X649810Y7261D01*
X649770Y7181D01*
X649725Y7061D01*
X649715Y7021D01*
X649705Y6976D01*
X649700Y6936D01*
X649690Y6891D01*
Y6721D01*
X649700Y6676D01*
X649705Y6636D01*
X649715Y6591D01*
X649725Y6551D01*
X649770Y6431D01*
X649810Y6351D01*
X649835Y6316D01*
X649855Y6281D01*
X649885Y6246D01*
X649910Y6211D01*
X649940Y6181D01*
Y3756D01*
X649950Y3631D01*
X649990Y3506D01*
X650050Y3396D01*
X650130Y3296D01*
X650230Y3216D01*
X650340Y3156D01*
X650465Y3116D01*
X650590Y3106D01*
G37*
G36*
G01X678937D02*
X679062Y3116D01*
X679187Y3156D01*
X679297Y3216D01*
X679397Y3296D01*
X679477Y3396D01*
X679537Y3506D01*
X679577Y3631D01*
X679587Y3756D01*
Y6186D01*
X679617Y6216D01*
X679717Y6356D01*
X679737Y6396D01*
X679752Y6431D01*
X679772Y6471D01*
X679787Y6511D01*
X679797Y6551D01*
X679812Y6596D01*
X679817Y6636D01*
X679827Y6676D01*
X679832Y6721D01*
Y6761D01*
X679837Y6806D01*
X679832Y6851D01*
Y6891D01*
X679827Y6936D01*
X679817Y6976D01*
X679812Y7016D01*
X679797Y7061D01*
X679787Y7101D01*
X679772Y7141D01*
X679752Y7181D01*
X679737Y7216D01*
X679717Y7256D01*
X679617Y7396D01*
X679587Y7426D01*
Y9556D01*
X679577Y9681D01*
X679537Y9806D01*
X679477Y9916D01*
X679397Y10016D01*
X679297Y10096D01*
X679187Y10156D01*
X679062Y10196D01*
X678937Y10206D01*
X678812Y10196D01*
X678687Y10156D01*
X678577Y10096D01*
X678477Y10016D01*
X678397Y9916D01*
X678337Y9806D01*
X678297Y9681D01*
X678287Y9556D01*
Y7431D01*
X678257Y7401D01*
X678232Y7366D01*
X678202Y7331D01*
X678182Y7296D01*
X678157Y7261D01*
X678117Y7181D01*
X678072Y7061D01*
X678062Y7021D01*
X678052Y6976D01*
X678047Y6936D01*
X678037Y6891D01*
Y6721D01*
X678047Y6676D01*
X678052Y6636D01*
X678062Y6591D01*
X678072Y6551D01*
X678117Y6431D01*
X678157Y6351D01*
X678182Y6316D01*
X678202Y6281D01*
X678232Y6246D01*
X678257Y6211D01*
X678287Y6181D01*
Y3756D01*
X678297Y3631D01*
X678337Y3506D01*
X678397Y3396D01*
X678477Y3296D01*
X678577Y3216D01*
X678687Y3156D01*
X678812Y3116D01*
X678937Y3106D01*
G37*
G36*
G01X674212D02*
X674337Y3116D01*
X674462Y3156D01*
X674572Y3216D01*
X674672Y3296D01*
X674752Y3396D01*
X674812Y3506D01*
X674852Y3631D01*
X674862Y3756D01*
Y6186D01*
X674892Y6216D01*
X674992Y6356D01*
X675012Y6396D01*
X675027Y6431D01*
X675047Y6471D01*
X675062Y6511D01*
X675072Y6551D01*
X675087Y6596D01*
X675092Y6636D01*
X675102Y6676D01*
X675107Y6721D01*
Y6761D01*
X675112Y6806D01*
X675107Y6851D01*
Y6891D01*
X675102Y6936D01*
X675092Y6976D01*
X675087Y7016D01*
X675072Y7061D01*
X675062Y7101D01*
X675047Y7141D01*
X675027Y7181D01*
X675012Y7216D01*
X674992Y7256D01*
X674892Y7396D01*
X674862Y7426D01*
Y9556D01*
X674852Y9681D01*
X674812Y9806D01*
X674752Y9916D01*
X674672Y10016D01*
X674572Y10096D01*
X674462Y10156D01*
X674337Y10196D01*
X674212Y10206D01*
X674087Y10196D01*
X673962Y10156D01*
X673852Y10096D01*
X673752Y10016D01*
X673672Y9916D01*
X673612Y9806D01*
X673572Y9681D01*
X673562Y9556D01*
Y7431D01*
X673532Y7401D01*
X673507Y7366D01*
X673477Y7331D01*
X673457Y7296D01*
X673432Y7261D01*
X673392Y7181D01*
X673347Y7061D01*
X673337Y7021D01*
X673327Y6976D01*
X673322Y6936D01*
X673312Y6891D01*
Y6721D01*
X673322Y6676D01*
X673327Y6636D01*
X673337Y6591D01*
X673347Y6551D01*
X673392Y6431D01*
X673432Y6351D01*
X673457Y6316D01*
X673477Y6281D01*
X673507Y6246D01*
X673532Y6211D01*
X673562Y6181D01*
Y3756D01*
X673572Y3631D01*
X673612Y3506D01*
X673672Y3396D01*
X673752Y3296D01*
X673852Y3216D01*
X673962Y3156D01*
X674087Y3116D01*
X674212Y3106D01*
G37*
G36*
G01X669488D02*
X669613Y3116D01*
X669738Y3156D01*
X669848Y3216D01*
X669948Y3296D01*
X670028Y3396D01*
X670088Y3506D01*
X670128Y3631D01*
X670138Y3756D01*
Y6186D01*
X670168Y6216D01*
X670268Y6356D01*
X670288Y6396D01*
X670303Y6431D01*
X670323Y6471D01*
X670338Y6511D01*
X670348Y6551D01*
X670363Y6596D01*
X670368Y6636D01*
X670378Y6676D01*
X670383Y6721D01*
Y6761D01*
X670388Y6806D01*
X670383Y6851D01*
Y6891D01*
X670378Y6936D01*
X670368Y6976D01*
X670363Y7016D01*
X670348Y7061D01*
X670338Y7101D01*
X670323Y7141D01*
X670303Y7181D01*
X670288Y7216D01*
X670268Y7256D01*
X670168Y7396D01*
X670138Y7426D01*
Y9556D01*
X670128Y9681D01*
X670088Y9806D01*
X670028Y9916D01*
X669948Y10016D01*
X669848Y10096D01*
X669738Y10156D01*
X669613Y10196D01*
X669488Y10206D01*
X669363Y10196D01*
X669238Y10156D01*
X669128Y10096D01*
X669028Y10016D01*
X668948Y9916D01*
X668888Y9806D01*
X668848Y9681D01*
X668838Y9556D01*
Y7431D01*
X668808Y7401D01*
X668783Y7366D01*
X668753Y7331D01*
X668733Y7296D01*
X668708Y7261D01*
X668668Y7181D01*
X668623Y7061D01*
X668613Y7021D01*
X668603Y6976D01*
X668598Y6936D01*
X668588Y6891D01*
Y6721D01*
X668598Y6676D01*
X668603Y6636D01*
X668613Y6591D01*
X668623Y6551D01*
X668668Y6431D01*
X668708Y6351D01*
X668733Y6316D01*
X668753Y6281D01*
X668783Y6246D01*
X668808Y6211D01*
X668838Y6181D01*
Y3756D01*
X668848Y3631D01*
X668888Y3506D01*
X668948Y3396D01*
X669028Y3296D01*
X669128Y3216D01*
X669238Y3156D01*
X669363Y3116D01*
X669488Y3106D01*
G37*
G36*
G01X693110D02*
X693235Y3116D01*
X693360Y3156D01*
X693470Y3216D01*
X693570Y3296D01*
X693650Y3396D01*
X693710Y3506D01*
X693750Y3631D01*
X693760Y3756D01*
Y6186D01*
X693790Y6216D01*
X693890Y6356D01*
X693910Y6396D01*
X693925Y6431D01*
X693945Y6471D01*
X693960Y6511D01*
X693970Y6551D01*
X693985Y6596D01*
X693990Y6636D01*
X694000Y6676D01*
X694005Y6721D01*
Y6761D01*
X694010Y6806D01*
X694005Y6851D01*
Y6891D01*
X694000Y6936D01*
X693990Y6976D01*
X693985Y7016D01*
X693970Y7061D01*
X693960Y7101D01*
X693945Y7141D01*
X693925Y7181D01*
X693910Y7216D01*
X693890Y7256D01*
X693790Y7396D01*
X693760Y7426D01*
Y9556D01*
X693750Y9681D01*
X693710Y9806D01*
X693650Y9916D01*
X693570Y10016D01*
X693470Y10096D01*
X693360Y10156D01*
X693235Y10196D01*
X693110Y10206D01*
X692985Y10196D01*
X692860Y10156D01*
X692750Y10096D01*
X692650Y10016D01*
X692570Y9916D01*
X692510Y9806D01*
X692470Y9681D01*
X692460Y9556D01*
Y7431D01*
X692430Y7401D01*
X692405Y7366D01*
X692375Y7331D01*
X692355Y7296D01*
X692330Y7261D01*
X692290Y7181D01*
X692245Y7061D01*
X692235Y7021D01*
X692225Y6976D01*
X692220Y6936D01*
X692210Y6891D01*
Y6721D01*
X692220Y6676D01*
X692225Y6636D01*
X692235Y6591D01*
X692245Y6551D01*
X692290Y6431D01*
X692330Y6351D01*
X692355Y6316D01*
X692375Y6281D01*
X692405Y6246D01*
X692430Y6211D01*
X692460Y6181D01*
Y3756D01*
X692470Y3631D01*
X692510Y3506D01*
X692570Y3396D01*
X692650Y3296D01*
X692750Y3216D01*
X692860Y3156D01*
X692985Y3116D01*
X693110Y3106D01*
G37*
G36*
G01X688386D02*
X688511Y3116D01*
X688636Y3156D01*
X688746Y3216D01*
X688846Y3296D01*
X688926Y3396D01*
X688986Y3506D01*
X689026Y3631D01*
X689036Y3756D01*
Y6186D01*
X689066Y6216D01*
X689166Y6356D01*
X689186Y6396D01*
X689201Y6431D01*
X689221Y6471D01*
X689236Y6511D01*
X689246Y6551D01*
X689261Y6596D01*
X689266Y6636D01*
X689276Y6676D01*
X689281Y6721D01*
Y6761D01*
X689286Y6806D01*
X689281Y6851D01*
Y6891D01*
X689276Y6936D01*
X689266Y6976D01*
X689261Y7016D01*
X689246Y7061D01*
X689236Y7101D01*
X689221Y7141D01*
X689201Y7181D01*
X689186Y7216D01*
X689166Y7256D01*
X689066Y7396D01*
X689036Y7426D01*
Y9556D01*
X689026Y9681D01*
X688986Y9806D01*
X688926Y9916D01*
X688846Y10016D01*
X688746Y10096D01*
X688636Y10156D01*
X688511Y10196D01*
X688386Y10206D01*
X688261Y10196D01*
X688136Y10156D01*
X688026Y10096D01*
X687926Y10016D01*
X687846Y9916D01*
X687786Y9806D01*
X687746Y9681D01*
X687736Y9556D01*
Y7431D01*
X687706Y7401D01*
X687681Y7366D01*
X687651Y7331D01*
X687631Y7296D01*
X687606Y7261D01*
X687566Y7181D01*
X687521Y7061D01*
X687511Y7021D01*
X687501Y6976D01*
X687496Y6936D01*
X687486Y6891D01*
Y6721D01*
X687496Y6676D01*
X687501Y6636D01*
X687511Y6591D01*
X687521Y6551D01*
X687566Y6431D01*
X687606Y6351D01*
X687631Y6316D01*
X687651Y6281D01*
X687681Y6246D01*
X687706Y6211D01*
X687736Y6181D01*
Y3756D01*
X687746Y3631D01*
X687786Y3506D01*
X687846Y3396D01*
X687926Y3296D01*
X688026Y3216D01*
X688136Y3156D01*
X688261Y3116D01*
X688386Y3106D01*
G37*
G36*
G01X683661D02*
X683786Y3116D01*
X683911Y3156D01*
X684021Y3216D01*
X684121Y3296D01*
X684201Y3396D01*
X684261Y3506D01*
X684301Y3631D01*
X684311Y3756D01*
Y6186D01*
X684341Y6216D01*
X684441Y6356D01*
X684461Y6396D01*
X684476Y6431D01*
X684496Y6471D01*
X684511Y6511D01*
X684521Y6551D01*
X684536Y6596D01*
X684541Y6636D01*
X684551Y6676D01*
X684556Y6721D01*
Y6761D01*
X684561Y6806D01*
X684556Y6851D01*
Y6891D01*
X684551Y6936D01*
X684541Y6976D01*
X684536Y7016D01*
X684521Y7061D01*
X684511Y7101D01*
X684496Y7141D01*
X684476Y7181D01*
X684461Y7216D01*
X684441Y7256D01*
X684341Y7396D01*
X684311Y7426D01*
Y9556D01*
X684301Y9681D01*
X684261Y9806D01*
X684201Y9916D01*
X684121Y10016D01*
X684021Y10096D01*
X683911Y10156D01*
X683786Y10196D01*
X683661Y10206D01*
X683536Y10196D01*
X683411Y10156D01*
X683301Y10096D01*
X683201Y10016D01*
X683121Y9916D01*
X683061Y9806D01*
X683021Y9681D01*
X683011Y9556D01*
Y7431D01*
X682981Y7401D01*
X682956Y7366D01*
X682926Y7331D01*
X682906Y7296D01*
X682881Y7261D01*
X682841Y7181D01*
X682796Y7061D01*
X682786Y7021D01*
X682776Y6976D01*
X682771Y6936D01*
X682761Y6891D01*
Y6721D01*
X682771Y6676D01*
X682776Y6636D01*
X682786Y6591D01*
X682796Y6551D01*
X682841Y6431D01*
X682881Y6351D01*
X682906Y6316D01*
X682926Y6281D01*
X682956Y6246D01*
X682981Y6211D01*
X683011Y6181D01*
Y3756D01*
X683021Y3631D01*
X683061Y3506D01*
X683121Y3396D01*
X683201Y3296D01*
X683301Y3216D01*
X683411Y3156D01*
X683536Y3116D01*
X683661Y3106D01*
G37*
G36*
G01X707283D02*
X707408Y3116D01*
X707533Y3156D01*
X707643Y3216D01*
X707743Y3296D01*
X707823Y3396D01*
X707883Y3506D01*
X707923Y3631D01*
X707933Y3756D01*
Y6186D01*
X707963Y6216D01*
X708063Y6356D01*
X708083Y6396D01*
X708098Y6431D01*
X708118Y6471D01*
X708133Y6511D01*
X708143Y6551D01*
X708158Y6596D01*
X708163Y6636D01*
X708173Y6676D01*
X708178Y6721D01*
Y6761D01*
X708183Y6806D01*
X708178Y6851D01*
Y6891D01*
X708173Y6936D01*
X708163Y6976D01*
X708158Y7016D01*
X708143Y7061D01*
X708133Y7101D01*
X708118Y7141D01*
X708098Y7181D01*
X708083Y7216D01*
X708063Y7256D01*
X707963Y7396D01*
X707933Y7426D01*
Y9556D01*
X707923Y9681D01*
X707883Y9806D01*
X707823Y9916D01*
X707743Y10016D01*
X707643Y10096D01*
X707533Y10156D01*
X707408Y10196D01*
X707283Y10206D01*
X707158Y10196D01*
X707033Y10156D01*
X706923Y10096D01*
X706823Y10016D01*
X706743Y9916D01*
X706683Y9806D01*
X706643Y9681D01*
X706633Y9556D01*
Y7431D01*
X706603Y7401D01*
X706578Y7366D01*
X706548Y7331D01*
X706528Y7296D01*
X706503Y7261D01*
X706463Y7181D01*
X706418Y7061D01*
X706408Y7021D01*
X706398Y6976D01*
X706393Y6936D01*
X706383Y6891D01*
Y6721D01*
X706393Y6676D01*
X706398Y6636D01*
X706408Y6591D01*
X706418Y6551D01*
X706463Y6431D01*
X706503Y6351D01*
X706528Y6316D01*
X706548Y6281D01*
X706578Y6246D01*
X706603Y6211D01*
X706633Y6181D01*
Y3756D01*
X706643Y3631D01*
X706683Y3506D01*
X706743Y3396D01*
X706823Y3296D01*
X706923Y3216D01*
X707033Y3156D01*
X707158Y3116D01*
X707283Y3106D01*
G37*
G36*
G01X702559D02*
X702684Y3116D01*
X702809Y3156D01*
X702919Y3216D01*
X703019Y3296D01*
X703099Y3396D01*
X703159Y3506D01*
X703199Y3631D01*
X703209Y3756D01*
Y6186D01*
X703239Y6216D01*
X703339Y6356D01*
X703359Y6396D01*
X703374Y6431D01*
X703394Y6471D01*
X703409Y6511D01*
X703419Y6551D01*
X703434Y6596D01*
X703439Y6636D01*
X703449Y6676D01*
X703454Y6721D01*
Y6761D01*
X703459Y6806D01*
X703454Y6851D01*
Y6891D01*
X703449Y6936D01*
X703439Y6976D01*
X703434Y7016D01*
X703419Y7061D01*
X703409Y7101D01*
X703394Y7141D01*
X703374Y7181D01*
X703359Y7216D01*
X703339Y7256D01*
X703239Y7396D01*
X703209Y7426D01*
Y9556D01*
X703199Y9681D01*
X703159Y9806D01*
X703099Y9916D01*
X703019Y10016D01*
X702919Y10096D01*
X702809Y10156D01*
X702684Y10196D01*
X702559Y10206D01*
X702434Y10196D01*
X702309Y10156D01*
X702199Y10096D01*
X702099Y10016D01*
X702019Y9916D01*
X701959Y9806D01*
X701919Y9681D01*
X701909Y9556D01*
Y7431D01*
X701879Y7401D01*
X701854Y7366D01*
X701824Y7331D01*
X701804Y7296D01*
X701779Y7261D01*
X701739Y7181D01*
X701694Y7061D01*
X701684Y7021D01*
X701674Y6976D01*
X701669Y6936D01*
X701659Y6891D01*
Y6721D01*
X701669Y6676D01*
X701674Y6636D01*
X701684Y6591D01*
X701694Y6551D01*
X701739Y6431D01*
X701779Y6351D01*
X701804Y6316D01*
X701824Y6281D01*
X701854Y6246D01*
X701879Y6211D01*
X701909Y6181D01*
Y3756D01*
X701919Y3631D01*
X701959Y3506D01*
X702019Y3396D01*
X702099Y3296D01*
X702199Y3216D01*
X702309Y3156D01*
X702434Y3116D01*
X702559Y3106D01*
G37*
G36*
G01X697834D02*
X697959Y3116D01*
X698084Y3156D01*
X698194Y3216D01*
X698294Y3296D01*
X698374Y3396D01*
X698434Y3506D01*
X698474Y3631D01*
X698484Y3756D01*
Y6186D01*
X698514Y6216D01*
X698614Y6356D01*
X698634Y6396D01*
X698649Y6431D01*
X698669Y6471D01*
X698684Y6511D01*
X698694Y6551D01*
X698709Y6596D01*
X698714Y6636D01*
X698724Y6676D01*
X698729Y6721D01*
Y6761D01*
X698734Y6806D01*
X698729Y6851D01*
Y6891D01*
X698724Y6936D01*
X698714Y6976D01*
X698709Y7016D01*
X698694Y7061D01*
X698684Y7101D01*
X698669Y7141D01*
X698649Y7181D01*
X698634Y7216D01*
X698614Y7256D01*
X698514Y7396D01*
X698484Y7426D01*
Y9556D01*
X698474Y9681D01*
X698434Y9806D01*
X698374Y9916D01*
X698294Y10016D01*
X698194Y10096D01*
X698084Y10156D01*
X697959Y10196D01*
X697834Y10206D01*
X697709Y10196D01*
X697584Y10156D01*
X697474Y10096D01*
X697374Y10016D01*
X697294Y9916D01*
X697234Y9806D01*
X697194Y9681D01*
X697184Y9556D01*
Y7431D01*
X697154Y7401D01*
X697129Y7366D01*
X697099Y7331D01*
X697079Y7296D01*
X697054Y7261D01*
X697014Y7181D01*
X696969Y7061D01*
X696959Y7021D01*
X696949Y6976D01*
X696944Y6936D01*
X696934Y6891D01*
Y6721D01*
X696944Y6676D01*
X696949Y6636D01*
X696959Y6591D01*
X696969Y6551D01*
X697014Y6431D01*
X697054Y6351D01*
X697079Y6316D01*
X697099Y6281D01*
X697129Y6246D01*
X697154Y6211D01*
X697184Y6181D01*
Y3756D01*
X697194Y3631D01*
X697234Y3506D01*
X697294Y3396D01*
X697374Y3296D01*
X697474Y3216D01*
X697584Y3156D01*
X697709Y3116D01*
X697834Y3106D01*
G37*
G36*
G01X726181D02*
X726306Y3116D01*
X726431Y3156D01*
X726541Y3216D01*
X726641Y3296D01*
X726721Y3396D01*
X726781Y3506D01*
X726821Y3631D01*
X726831Y3756D01*
Y6186D01*
X726861Y6216D01*
X726961Y6356D01*
X726981Y6396D01*
X726996Y6431D01*
X727016Y6471D01*
X727031Y6511D01*
X727041Y6551D01*
X727056Y6596D01*
X727061Y6636D01*
X727071Y6676D01*
X727076Y6721D01*
Y6761D01*
X727081Y6806D01*
X727076Y6851D01*
Y6891D01*
X727071Y6936D01*
X727061Y6976D01*
X727056Y7016D01*
X727041Y7061D01*
X727031Y7101D01*
X727016Y7141D01*
X726996Y7181D01*
X726981Y7216D01*
X726961Y7256D01*
X726861Y7396D01*
X726831Y7426D01*
Y9556D01*
X726821Y9681D01*
X726781Y9806D01*
X726721Y9916D01*
X726641Y10016D01*
X726541Y10096D01*
X726431Y10156D01*
X726306Y10196D01*
X726181Y10206D01*
X726056Y10196D01*
X725931Y10156D01*
X725821Y10096D01*
X725721Y10016D01*
X725641Y9916D01*
X725581Y9806D01*
X725541Y9681D01*
X725531Y9556D01*
Y7431D01*
X725501Y7401D01*
X725476Y7366D01*
X725446Y7331D01*
X725426Y7296D01*
X725401Y7261D01*
X725361Y7181D01*
X725316Y7061D01*
X725306Y7021D01*
X725296Y6976D01*
X725291Y6936D01*
X725281Y6891D01*
Y6721D01*
X725291Y6676D01*
X725296Y6636D01*
X725306Y6591D01*
X725316Y6551D01*
X725361Y6431D01*
X725401Y6351D01*
X725426Y6316D01*
X725446Y6281D01*
X725476Y6246D01*
X725501Y6211D01*
X725531Y6181D01*
Y3756D01*
X725541Y3631D01*
X725581Y3506D01*
X725641Y3396D01*
X725721Y3296D01*
X725821Y3216D01*
X725931Y3156D01*
X726056Y3116D01*
X726181Y3106D01*
G37*
G36*
G01X721456D02*
X721581Y3116D01*
X721706Y3156D01*
X721816Y3216D01*
X721916Y3296D01*
X721996Y3396D01*
X722056Y3506D01*
X722096Y3631D01*
X722106Y3756D01*
Y6186D01*
X722136Y6216D01*
X722236Y6356D01*
X722256Y6396D01*
X722271Y6431D01*
X722291Y6471D01*
X722306Y6511D01*
X722316Y6551D01*
X722331Y6596D01*
X722336Y6636D01*
X722346Y6676D01*
X722351Y6721D01*
Y6761D01*
X722356Y6806D01*
X722351Y6851D01*
Y6891D01*
X722346Y6936D01*
X722336Y6976D01*
X722331Y7016D01*
X722316Y7061D01*
X722306Y7101D01*
X722291Y7141D01*
X722271Y7181D01*
X722256Y7216D01*
X722236Y7256D01*
X722136Y7396D01*
X722106Y7426D01*
Y9556D01*
X722096Y9681D01*
X722056Y9806D01*
X721996Y9916D01*
X721916Y10016D01*
X721816Y10096D01*
X721706Y10156D01*
X721581Y10196D01*
X721456Y10206D01*
X721331Y10196D01*
X721206Y10156D01*
X721096Y10096D01*
X720996Y10016D01*
X720916Y9916D01*
X720856Y9806D01*
X720816Y9681D01*
X720806Y9556D01*
Y7431D01*
X720776Y7401D01*
X720751Y7366D01*
X720721Y7331D01*
X720701Y7296D01*
X720676Y7261D01*
X720636Y7181D01*
X720591Y7061D01*
X720581Y7021D01*
X720571Y6976D01*
X720566Y6936D01*
X720556Y6891D01*
Y6721D01*
X720566Y6676D01*
X720571Y6636D01*
X720581Y6591D01*
X720591Y6551D01*
X720636Y6431D01*
X720676Y6351D01*
X720701Y6316D01*
X720721Y6281D01*
X720751Y6246D01*
X720776Y6211D01*
X720806Y6181D01*
Y3756D01*
X720816Y3631D01*
X720856Y3506D01*
X720916Y3396D01*
X720996Y3296D01*
X721096Y3216D01*
X721206Y3156D01*
X721331Y3116D01*
X721456Y3106D01*
G37*
G36*
G01X716732D02*
X716857Y3116D01*
X716982Y3156D01*
X717092Y3216D01*
X717192Y3296D01*
X717272Y3396D01*
X717332Y3506D01*
X717372Y3631D01*
X717382Y3756D01*
Y6186D01*
X717412Y6216D01*
X717512Y6356D01*
X717532Y6396D01*
X717547Y6431D01*
X717567Y6471D01*
X717582Y6511D01*
X717592Y6551D01*
X717607Y6596D01*
X717612Y6636D01*
X717622Y6676D01*
X717627Y6721D01*
Y6761D01*
X717632Y6806D01*
X717627Y6851D01*
Y6891D01*
X717622Y6936D01*
X717612Y6976D01*
X717607Y7016D01*
X717592Y7061D01*
X717582Y7101D01*
X717567Y7141D01*
X717547Y7181D01*
X717532Y7216D01*
X717512Y7256D01*
X717412Y7396D01*
X717382Y7426D01*
Y9556D01*
X717372Y9681D01*
X717332Y9806D01*
X717272Y9916D01*
X717192Y10016D01*
X717092Y10096D01*
X716982Y10156D01*
X716857Y10196D01*
X716732Y10206D01*
X716607Y10196D01*
X716482Y10156D01*
X716372Y10096D01*
X716272Y10016D01*
X716192Y9916D01*
X716132Y9806D01*
X716092Y9681D01*
X716082Y9556D01*
Y7431D01*
X716052Y7401D01*
X716027Y7366D01*
X715997Y7331D01*
X715977Y7296D01*
X715952Y7261D01*
X715912Y7181D01*
X715867Y7061D01*
X715857Y7021D01*
X715847Y6976D01*
X715842Y6936D01*
X715832Y6891D01*
Y6721D01*
X715842Y6676D01*
X715847Y6636D01*
X715857Y6591D01*
X715867Y6551D01*
X715912Y6431D01*
X715952Y6351D01*
X715977Y6316D01*
X715997Y6281D01*
X716027Y6246D01*
X716052Y6211D01*
X716082Y6181D01*
Y3756D01*
X716092Y3631D01*
X716132Y3506D01*
X716192Y3396D01*
X716272Y3296D01*
X716372Y3216D01*
X716482Y3156D01*
X716607Y3116D01*
X716732Y3106D01*
G37*
G36*
G01X712008D02*
X712133Y3116D01*
X712258Y3156D01*
X712368Y3216D01*
X712468Y3296D01*
X712548Y3396D01*
X712608Y3506D01*
X712648Y3631D01*
X712658Y3756D01*
Y6186D01*
X712688Y6216D01*
X712788Y6356D01*
X712808Y6396D01*
X712823Y6431D01*
X712843Y6471D01*
X712858Y6511D01*
X712868Y6551D01*
X712883Y6596D01*
X712888Y6636D01*
X712898Y6676D01*
X712903Y6721D01*
Y6761D01*
X712908Y6806D01*
X712903Y6851D01*
Y6891D01*
X712898Y6936D01*
X712888Y6976D01*
X712883Y7016D01*
X712868Y7061D01*
X712858Y7101D01*
X712843Y7141D01*
X712823Y7181D01*
X712808Y7216D01*
X712788Y7256D01*
X712688Y7396D01*
X712658Y7426D01*
Y9556D01*
X712648Y9681D01*
X712608Y9806D01*
X712548Y9916D01*
X712468Y10016D01*
X712368Y10096D01*
X712258Y10156D01*
X712133Y10196D01*
X712008Y10206D01*
X711883Y10196D01*
X711758Y10156D01*
X711648Y10096D01*
X711548Y10016D01*
X711468Y9916D01*
X711408Y9806D01*
X711368Y9681D01*
X711358Y9556D01*
Y7431D01*
X711328Y7401D01*
X711303Y7366D01*
X711273Y7331D01*
X711253Y7296D01*
X711228Y7261D01*
X711188Y7181D01*
X711143Y7061D01*
X711133Y7021D01*
X711123Y6976D01*
X711118Y6936D01*
X711108Y6891D01*
Y6721D01*
X711118Y6676D01*
X711123Y6636D01*
X711133Y6591D01*
X711143Y6551D01*
X711188Y6431D01*
X711228Y6351D01*
X711253Y6316D01*
X711273Y6281D01*
X711303Y6246D01*
X711328Y6211D01*
X711358Y6181D01*
Y3756D01*
X711368Y3631D01*
X711408Y3506D01*
X711468Y3396D01*
X711548Y3296D01*
X711648Y3216D01*
X711758Y3156D01*
X711883Y3116D01*
X712008Y3106D01*
G37*
G36*
G01X740354D02*
X740479Y3116D01*
X740604Y3156D01*
X740714Y3216D01*
X740814Y3296D01*
X740894Y3396D01*
X740954Y3506D01*
X740994Y3631D01*
X741004Y3756D01*
Y6186D01*
X741034Y6216D01*
X741134Y6356D01*
X741154Y6396D01*
X741169Y6431D01*
X741189Y6471D01*
X741204Y6511D01*
X741214Y6551D01*
X741229Y6596D01*
X741234Y6636D01*
X741244Y6676D01*
X741249Y6721D01*
Y6761D01*
X741254Y6806D01*
X741249Y6851D01*
Y6891D01*
X741244Y6936D01*
X741234Y6976D01*
X741229Y7016D01*
X741214Y7061D01*
X741204Y7101D01*
X741189Y7141D01*
X741169Y7181D01*
X741154Y7216D01*
X741134Y7256D01*
X741034Y7396D01*
X741004Y7426D01*
Y9556D01*
X740994Y9681D01*
X740954Y9806D01*
X740894Y9916D01*
X740814Y10016D01*
X740714Y10096D01*
X740604Y10156D01*
X740479Y10196D01*
X740354Y10206D01*
X740229Y10196D01*
X740104Y10156D01*
X739994Y10096D01*
X739894Y10016D01*
X739814Y9916D01*
X739754Y9806D01*
X739714Y9681D01*
X739704Y9556D01*
Y7431D01*
X739674Y7401D01*
X739649Y7366D01*
X739619Y7331D01*
X739599Y7296D01*
X739574Y7261D01*
X739534Y7181D01*
X739489Y7061D01*
X739479Y7021D01*
X739469Y6976D01*
X739464Y6936D01*
X739454Y6891D01*
Y6721D01*
X739464Y6676D01*
X739469Y6636D01*
X739479Y6591D01*
X739489Y6551D01*
X739534Y6431D01*
X739574Y6351D01*
X739599Y6316D01*
X739619Y6281D01*
X739649Y6246D01*
X739674Y6211D01*
X739704Y6181D01*
Y3756D01*
X739714Y3631D01*
X739754Y3506D01*
X739814Y3396D01*
X739894Y3296D01*
X739994Y3216D01*
X740104Y3156D01*
X740229Y3116D01*
X740354Y3106D01*
G37*
G36*
G01X735630D02*
X735755Y3116D01*
X735880Y3156D01*
X735990Y3216D01*
X736090Y3296D01*
X736170Y3396D01*
X736230Y3506D01*
X736270Y3631D01*
X736280Y3756D01*
Y6186D01*
X736310Y6216D01*
X736410Y6356D01*
X736430Y6396D01*
X736445Y6431D01*
X736465Y6471D01*
X736480Y6511D01*
X736490Y6551D01*
X736505Y6596D01*
X736510Y6636D01*
X736520Y6676D01*
X736525Y6721D01*
Y6761D01*
X736530Y6806D01*
X736525Y6851D01*
Y6891D01*
X736520Y6936D01*
X736510Y6976D01*
X736505Y7016D01*
X736490Y7061D01*
X736480Y7101D01*
X736465Y7141D01*
X736445Y7181D01*
X736430Y7216D01*
X736410Y7256D01*
X736310Y7396D01*
X736280Y7426D01*
Y9556D01*
X736270Y9681D01*
X736230Y9806D01*
X736170Y9916D01*
X736090Y10016D01*
X735990Y10096D01*
X735880Y10156D01*
X735755Y10196D01*
X735630Y10206D01*
X735505Y10196D01*
X735380Y10156D01*
X735270Y10096D01*
X735170Y10016D01*
X735090Y9916D01*
X735030Y9806D01*
X734990Y9681D01*
X734980Y9556D01*
Y7431D01*
X734950Y7401D01*
X734925Y7366D01*
X734895Y7331D01*
X734875Y7296D01*
X734850Y7261D01*
X734810Y7181D01*
X734765Y7061D01*
X734755Y7021D01*
X734745Y6976D01*
X734740Y6936D01*
X734730Y6891D01*
Y6721D01*
X734740Y6676D01*
X734745Y6636D01*
X734755Y6591D01*
X734765Y6551D01*
X734810Y6431D01*
X734850Y6351D01*
X734875Y6316D01*
X734895Y6281D01*
X734925Y6246D01*
X734950Y6211D01*
X734980Y6181D01*
Y3756D01*
X734990Y3631D01*
X735030Y3506D01*
X735090Y3396D01*
X735170Y3296D01*
X735270Y3216D01*
X735380Y3156D01*
X735505Y3116D01*
X735630Y3106D01*
G37*
G36*
G01X730905D02*
X731030Y3116D01*
X731155Y3156D01*
X731265Y3216D01*
X731365Y3296D01*
X731445Y3396D01*
X731505Y3506D01*
X731545Y3631D01*
X731555Y3756D01*
Y6186D01*
X731585Y6216D01*
X731685Y6356D01*
X731705Y6396D01*
X731720Y6431D01*
X731740Y6471D01*
X731755Y6511D01*
X731765Y6551D01*
X731780Y6596D01*
X731785Y6636D01*
X731795Y6676D01*
X731800Y6721D01*
Y6761D01*
X731805Y6806D01*
X731800Y6851D01*
Y6891D01*
X731795Y6936D01*
X731785Y6976D01*
X731780Y7016D01*
X731765Y7061D01*
X731755Y7101D01*
X731740Y7141D01*
X731720Y7181D01*
X731705Y7216D01*
X731685Y7256D01*
X731585Y7396D01*
X731555Y7426D01*
Y9556D01*
X731545Y9681D01*
X731505Y9806D01*
X731445Y9916D01*
X731365Y10016D01*
X731265Y10096D01*
X731155Y10156D01*
X731030Y10196D01*
X730905Y10206D01*
X730780Y10196D01*
X730655Y10156D01*
X730545Y10096D01*
X730445Y10016D01*
X730365Y9916D01*
X730305Y9806D01*
X730265Y9681D01*
X730255Y9556D01*
Y7431D01*
X730225Y7401D01*
X730200Y7366D01*
X730170Y7331D01*
X730150Y7296D01*
X730125Y7261D01*
X730085Y7181D01*
X730040Y7061D01*
X730030Y7021D01*
X730020Y6976D01*
X730015Y6936D01*
X730005Y6891D01*
Y6721D01*
X730015Y6676D01*
X730020Y6636D01*
X730030Y6591D01*
X730040Y6551D01*
X730085Y6431D01*
X730125Y6351D01*
X730150Y6316D01*
X730170Y6281D01*
X730200Y6246D01*
X730225Y6211D01*
X730255Y6181D01*
Y3756D01*
X730265Y3631D01*
X730305Y3506D01*
X730365Y3396D01*
X730445Y3296D01*
X730545Y3216D01*
X730655Y3156D01*
X730780Y3116D01*
X730905Y3106D01*
G37*
G36*
G01X754527D02*
X754652Y3116D01*
X754777Y3156D01*
X754887Y3216D01*
X754987Y3296D01*
X755067Y3396D01*
X755127Y3506D01*
X755167Y3631D01*
X755177Y3756D01*
Y6186D01*
X755207Y6216D01*
X755307Y6356D01*
X755327Y6396D01*
X755342Y6431D01*
X755362Y6471D01*
X755377Y6511D01*
X755387Y6551D01*
X755402Y6596D01*
X755407Y6636D01*
X755417Y6676D01*
X755422Y6721D01*
Y6761D01*
X755427Y6806D01*
X755422Y6851D01*
Y6891D01*
X755417Y6936D01*
X755407Y6976D01*
X755402Y7016D01*
X755387Y7061D01*
X755377Y7101D01*
X755362Y7141D01*
X755342Y7181D01*
X755327Y7216D01*
X755307Y7256D01*
X755207Y7396D01*
X755177Y7426D01*
Y9556D01*
X755167Y9681D01*
X755127Y9806D01*
X755067Y9916D01*
X754987Y10016D01*
X754887Y10096D01*
X754777Y10156D01*
X754652Y10196D01*
X754527Y10206D01*
X754402Y10196D01*
X754277Y10156D01*
X754167Y10096D01*
X754067Y10016D01*
X753987Y9916D01*
X753927Y9806D01*
X753887Y9681D01*
X753877Y9556D01*
Y7431D01*
X753847Y7401D01*
X753822Y7366D01*
X753792Y7331D01*
X753772Y7296D01*
X753747Y7261D01*
X753707Y7181D01*
X753662Y7061D01*
X753652Y7021D01*
X753642Y6976D01*
X753637Y6936D01*
X753627Y6891D01*
Y6721D01*
X753637Y6676D01*
X753642Y6636D01*
X753652Y6591D01*
X753662Y6551D01*
X753707Y6431D01*
X753747Y6351D01*
X753772Y6316D01*
X753792Y6281D01*
X753822Y6246D01*
X753847Y6211D01*
X753877Y6181D01*
Y3756D01*
X753887Y3631D01*
X753927Y3506D01*
X753987Y3396D01*
X754067Y3296D01*
X754167Y3216D01*
X754277Y3156D01*
X754402Y3116D01*
X754527Y3106D01*
G37*
G36*
G01X749803D02*
X749928Y3116D01*
X750053Y3156D01*
X750163Y3216D01*
X750263Y3296D01*
X750343Y3396D01*
X750403Y3506D01*
X750443Y3631D01*
X750453Y3756D01*
Y6186D01*
X750483Y6216D01*
X750583Y6356D01*
X750603Y6396D01*
X750618Y6431D01*
X750638Y6471D01*
X750653Y6511D01*
X750663Y6551D01*
X750678Y6596D01*
X750683Y6636D01*
X750693Y6676D01*
X750698Y6721D01*
Y6761D01*
X750703Y6806D01*
X750698Y6851D01*
Y6891D01*
X750693Y6936D01*
X750683Y6976D01*
X750678Y7016D01*
X750663Y7061D01*
X750653Y7101D01*
X750638Y7141D01*
X750618Y7181D01*
X750603Y7216D01*
X750583Y7256D01*
X750483Y7396D01*
X750453Y7426D01*
Y9556D01*
X750443Y9681D01*
X750403Y9806D01*
X750343Y9916D01*
X750263Y10016D01*
X750163Y10096D01*
X750053Y10156D01*
X749928Y10196D01*
X749803Y10206D01*
X749678Y10196D01*
X749553Y10156D01*
X749443Y10096D01*
X749343Y10016D01*
X749263Y9916D01*
X749203Y9806D01*
X749163Y9681D01*
X749153Y9556D01*
Y7431D01*
X749123Y7401D01*
X749098Y7366D01*
X749068Y7331D01*
X749048Y7296D01*
X749023Y7261D01*
X748983Y7181D01*
X748938Y7061D01*
X748928Y7021D01*
X748918Y6976D01*
X748913Y6936D01*
X748903Y6891D01*
Y6721D01*
X748913Y6676D01*
X748918Y6636D01*
X748928Y6591D01*
X748938Y6551D01*
X748983Y6431D01*
X749023Y6351D01*
X749048Y6316D01*
X749068Y6281D01*
X749098Y6246D01*
X749123Y6211D01*
X749153Y6181D01*
Y3756D01*
X749163Y3631D01*
X749203Y3506D01*
X749263Y3396D01*
X749343Y3296D01*
X749443Y3216D01*
X749553Y3156D01*
X749678Y3116D01*
X749803Y3106D01*
G37*
G36*
G01X745078D02*
X745203Y3116D01*
X745328Y3156D01*
X745438Y3216D01*
X745538Y3296D01*
X745618Y3396D01*
X745678Y3506D01*
X745718Y3631D01*
X745728Y3756D01*
Y6186D01*
X745758Y6216D01*
X745858Y6356D01*
X745878Y6396D01*
X745893Y6431D01*
X745913Y6471D01*
X745928Y6511D01*
X745938Y6551D01*
X745953Y6596D01*
X745958Y6636D01*
X745968Y6676D01*
X745973Y6721D01*
Y6761D01*
X745978Y6806D01*
X745973Y6851D01*
Y6891D01*
X745968Y6936D01*
X745958Y6976D01*
X745953Y7016D01*
X745938Y7061D01*
X745928Y7101D01*
X745913Y7141D01*
X745893Y7181D01*
X745878Y7216D01*
X745858Y7256D01*
X745758Y7396D01*
X745728Y7426D01*
Y9556D01*
X745718Y9681D01*
X745678Y9806D01*
X745618Y9916D01*
X745538Y10016D01*
X745438Y10096D01*
X745328Y10156D01*
X745203Y10196D01*
X745078Y10206D01*
X744953Y10196D01*
X744828Y10156D01*
X744718Y10096D01*
X744618Y10016D01*
X744538Y9916D01*
X744478Y9806D01*
X744438Y9681D01*
X744428Y9556D01*
Y7431D01*
X744398Y7401D01*
X744373Y7366D01*
X744343Y7331D01*
X744323Y7296D01*
X744298Y7261D01*
X744258Y7181D01*
X744213Y7061D01*
X744203Y7021D01*
X744193Y6976D01*
X744188Y6936D01*
X744178Y6891D01*
Y6721D01*
X744188Y6676D01*
X744193Y6636D01*
X744203Y6591D01*
X744213Y6551D01*
X744258Y6431D01*
X744298Y6351D01*
X744323Y6316D01*
X744343Y6281D01*
X744373Y6246D01*
X744398Y6211D01*
X744428Y6181D01*
Y3756D01*
X744438Y3631D01*
X744478Y3506D01*
X744538Y3396D01*
X744618Y3296D01*
X744718Y3216D01*
X744828Y3156D01*
X744953Y3116D01*
X745078Y3106D01*
G37*
G54D26*
X58500Y191000D03*
X61500D03*
X79500Y51500D03*
X67500Y191000D03*
X64500D03*
X68000Y238000D03*
X82500Y51500D03*
X88500D03*
X85500D03*
X85200Y242000D03*
X103250Y51500D03*
X100250D03*
X105500Y195000D03*
X119000Y51500D03*
X116000D03*
X134800D03*
X131800D03*
X132700Y189600D03*
X150515Y51500D03*
X147515D03*
X166263D03*
X163263D03*
X160100Y187000D03*
X182000Y51500D03*
X179000D03*
X178000Y167500D03*
X201500Y68500D03*
X204500D03*
X237000Y60300D03*
X268000Y55000D03*
X271000D03*
X275500Y244500D03*
X272500D03*
X290000Y55000D03*
X287000D03*
X286100Y80700D03*
X305000Y54500D03*
X308000D03*
X310500Y63500D03*
X304500Y222000D03*
X302000Y245100D03*
X305000D03*
X316000Y54500D03*
X319000D03*
X334000Y58500D03*
X354000Y66000D03*
X353000Y143500D03*
X364500Y131500D03*
X370300Y134500D03*
X365000Y149500D03*
X359000Y143000D03*
Y177000D03*
X377500Y134500D03*
X374500D03*
X386500Y171500D03*
X378220Y173540D03*
X395500Y78000D03*
X392000D03*
X393496Y109063D03*
X389500Y159263D03*
X390000Y165100D03*
Y171500D03*
X398000Y256000D03*
X410000Y109063D03*
X407000D03*
X416000D03*
X413000D03*
X406000Y266500D03*
X422000Y109063D03*
X419000D03*
X421142Y184024D03*
X436000Y110563D03*
X434900Y149500D03*
X441000Y143000D03*
X601100Y236500D03*
X617800Y236400D03*
X613200Y236100D03*
X610200D03*
X620800Y236400D03*
X623800D03*
X744500Y239000D03*
G54D80*
X771791Y272260D03*
Y279740D03*
X780209Y276000D03*
G54D62*
X380000Y263461D03*
G54D35*
X119760Y191419D03*
X323882Y71643D03*
G54D44*
X219502Y78346D03*
Y81496D03*
Y84646D03*
Y87795D03*
Y90945D03*
Y94094D03*
Y97244D03*
Y100394D03*
Y103543D03*
Y106693D03*
Y109842D03*
Y112992D03*
Y116142D03*
Y119291D03*
Y122441D03*
Y125590D03*
Y128740D03*
Y131890D03*
Y147638D03*
Y150787D03*
Y153937D03*
Y157086D03*
Y160236D03*
Y163386D03*
Y166535D03*
Y169685D03*
X251758Y79921D03*
Y83071D03*
Y86220D03*
Y89370D03*
Y92520D03*
Y95669D03*
Y98819D03*
Y101968D03*
Y105118D03*
Y108268D03*
Y111417D03*
Y114567D03*
Y117716D03*
Y120866D03*
Y124016D03*
Y127165D03*
Y130315D03*
Y133464D03*
Y149212D03*
Y152362D03*
Y155512D03*
Y158661D03*
Y161811D03*
Y164960D03*
Y168110D03*
Y171260D03*
G54D53*
X314639Y74202D03*
Y71643D03*
Y69084D03*
Y66525D03*
Y76761D03*
X333125Y66525D03*
Y69084D03*
Y71643D03*
Y74202D03*
Y76761D03*
G54D17*
X25700Y131500D03*
X22300D03*
X64200Y94500D03*
X60800D03*
X64300Y135500D03*
Y138500D03*
X78800Y110000D03*
X67700Y135500D03*
Y138500D03*
X74900Y238700D03*
X71500D03*
X82200Y110000D03*
X138200Y67000D03*
X134800D03*
X138200Y64000D03*
X134800D03*
X132200Y169000D03*
X128800D03*
X138600Y192500D03*
X135200D03*
X147200Y112000D03*
X143800D03*
X155200Y195300D03*
X151800D03*
X155200Y198300D03*
X151800D03*
X147200Y194500D03*
X143800D03*
X155300Y257000D03*
X163700Y57500D03*
X160300D03*
X171400Y113200D03*
X168000D03*
X171300Y213000D03*
X158700Y257000D03*
X177300Y61300D03*
X173900D03*
X174700Y213000D03*
X193200Y57500D03*
X189800D03*
X200300Y195000D03*
X202300Y230500D03*
X203700Y195000D03*
X205700Y230500D03*
X261400Y73100D03*
X258000D03*
X263800Y70000D03*
X262200Y146300D03*
X267200Y70000D03*
X265600Y146300D03*
X274200Y247500D03*
X270800D03*
X291900Y90600D03*
X288500D03*
X285200Y95000D03*
X281800D03*
X292300Y97600D03*
X293200Y113000D03*
X289800D03*
X293200Y116000D03*
X289800D03*
X293200Y110000D03*
X289800D03*
X293200Y119000D03*
X289800D03*
X293200Y128000D03*
X289800D03*
X293200Y122000D03*
X289800D03*
X293200Y125000D03*
X289800D03*
X293200Y131000D03*
X289800D03*
X293200Y144500D03*
X289800D03*
X293200Y147500D03*
X289800D03*
X293700Y160500D03*
X290300D03*
X293700Y164000D03*
X290300D03*
X293700Y174000D03*
X290300D03*
X293700Y168000D03*
X290300D03*
X293700Y177500D03*
X290300D03*
X293700Y171000D03*
X290300D03*
X293700Y181500D03*
X290300D03*
X293300Y196500D03*
Y193500D03*
X295700Y97600D03*
X307800Y151300D03*
X296700Y196500D03*
Y193500D03*
X321700Y106500D03*
X318300D03*
X317700Y129200D03*
X314300D03*
X311200Y151300D03*
X340700Y84500D03*
X337300D03*
X337200Y125000D03*
X333800D03*
X341300Y181000D03*
X333700Y254000D03*
X330300D03*
X346150Y159200D03*
X342750D03*
X344700Y181000D03*
X392200Y81000D03*
X388800D03*
X397200Y227500D03*
X393800D03*
X415950Y175623D03*
X419350D03*
X444200Y127063D03*
X440800D03*
X458700Y252000D03*
X455300D03*
X530700Y191500D03*
X527300D03*
X530700Y188500D03*
X527300D03*
X557200Y179000D03*
X553800D03*
X570300Y187000D03*
X566900D03*
X638200Y285000D03*
X634800D03*
X736200Y105500D03*
X732800D03*
X738000Y134100D03*
X734600D03*
X748100Y50007D03*
X744700D03*
X751600Y46507D03*
X748200D03*
X778700Y139000D03*
X775300D03*
X778200Y260000D03*
X774800D03*
X778200Y266000D03*
X774800D03*
X778200Y263000D03*
X774800D03*
G36*
G01X506496Y3106D02*
X506621Y3116D01*
X506746Y3156D01*
X506856Y3216D01*
X506956Y3296D01*
X507036Y3396D01*
X507096Y3506D01*
X507136Y3631D01*
X507146Y3756D01*
Y7186D01*
X507176Y7216D01*
X507276Y7356D01*
X507296Y7396D01*
X507311Y7431D01*
X507331Y7471D01*
X507346Y7511D01*
X507356Y7551D01*
X507371Y7596D01*
X507376Y7636D01*
X507386Y7676D01*
X507391Y7721D01*
Y7761D01*
X507396Y7806D01*
X507391Y7851D01*
Y7891D01*
X507386Y7936D01*
X507376Y7976D01*
X507371Y8016D01*
X507356Y8061D01*
X507346Y8101D01*
X507331Y8141D01*
X507311Y8181D01*
X507296Y8216D01*
X507276Y8256D01*
X507176Y8396D01*
X507146Y8426D01*
Y9556D01*
X507136Y9681D01*
X507096Y9806D01*
X507036Y9916D01*
X506956Y10016D01*
X506856Y10096D01*
X506746Y10156D01*
X506621Y10196D01*
X506496Y10206D01*
X506371Y10196D01*
X506246Y10156D01*
X506136Y10096D01*
X506036Y10016D01*
X505956Y9916D01*
X505896Y9806D01*
X505856Y9681D01*
X505846Y9556D01*
Y8426D01*
X505816Y8396D01*
X505716Y8256D01*
X505696Y8216D01*
X505681Y8181D01*
X505661Y8141D01*
X505646Y8101D01*
X505636Y8061D01*
X505621Y8016D01*
X505616Y7976D01*
X505606Y7936D01*
X505601Y7891D01*
Y7851D01*
X505596Y7806D01*
X505601Y7761D01*
Y7721D01*
X505606Y7676D01*
X505616Y7636D01*
X505621Y7596D01*
X505636Y7551D01*
X505646Y7511D01*
X505661Y7471D01*
X505681Y7431D01*
X505696Y7396D01*
X505716Y7356D01*
X505816Y7216D01*
X505846Y7186D01*
Y3756D01*
X505856Y3631D01*
X505896Y3506D01*
X505956Y3396D01*
X506036Y3296D01*
X506136Y3216D01*
X506246Y3156D01*
X506371Y3116D01*
X506496Y3106D01*
G37*
G36*
G01X525393D02*
X525518Y3116D01*
X525643Y3156D01*
X525753Y3216D01*
X525853Y3296D01*
X525933Y3396D01*
X525993Y3506D01*
X526033Y3631D01*
X526043Y3756D01*
Y7186D01*
X526073Y7216D01*
X526173Y7356D01*
X526193Y7396D01*
X526208Y7431D01*
X526228Y7471D01*
X526243Y7511D01*
X526253Y7551D01*
X526268Y7596D01*
X526273Y7636D01*
X526283Y7676D01*
X526288Y7721D01*
Y7761D01*
X526293Y7806D01*
X526288Y7851D01*
Y7891D01*
X526283Y7936D01*
X526273Y7976D01*
X526268Y8016D01*
X526253Y8061D01*
X526243Y8101D01*
X526228Y8141D01*
X526208Y8181D01*
X526193Y8216D01*
X526173Y8256D01*
X526073Y8396D01*
X526043Y8426D01*
Y9556D01*
X526033Y9681D01*
X525993Y9806D01*
X525933Y9916D01*
X525853Y10016D01*
X525753Y10096D01*
X525643Y10156D01*
X525518Y10196D01*
X525393Y10206D01*
X525268Y10196D01*
X525143Y10156D01*
X525033Y10096D01*
X524933Y10016D01*
X524853Y9916D01*
X524793Y9806D01*
X524753Y9681D01*
X524743Y9556D01*
Y8426D01*
X524713Y8396D01*
X524613Y8256D01*
X524593Y8216D01*
X524578Y8181D01*
X524558Y8141D01*
X524543Y8101D01*
X524533Y8061D01*
X524518Y8016D01*
X524513Y7976D01*
X524503Y7936D01*
X524498Y7891D01*
Y7851D01*
X524493Y7806D01*
X524498Y7761D01*
Y7721D01*
X524503Y7676D01*
X524513Y7636D01*
X524518Y7596D01*
X524533Y7551D01*
X524543Y7511D01*
X524558Y7471D01*
X524578Y7431D01*
X524593Y7396D01*
X524613Y7356D01*
X524713Y7216D01*
X524743Y7186D01*
Y3756D01*
X524753Y3631D01*
X524793Y3506D01*
X524853Y3396D01*
X524933Y3296D01*
X525033Y3216D01*
X525143Y3156D01*
X525268Y3116D01*
X525393Y3106D01*
G37*
G36*
G01X520669D02*
X520794Y3116D01*
X520919Y3156D01*
X521029Y3216D01*
X521129Y3296D01*
X521209Y3396D01*
X521269Y3506D01*
X521309Y3631D01*
X521319Y3756D01*
Y7186D01*
X521349Y7216D01*
X521449Y7356D01*
X521469Y7396D01*
X521484Y7431D01*
X521504Y7471D01*
X521519Y7511D01*
X521529Y7551D01*
X521544Y7596D01*
X521549Y7636D01*
X521559Y7676D01*
X521564Y7721D01*
Y7761D01*
X521569Y7806D01*
X521564Y7851D01*
Y7891D01*
X521559Y7936D01*
X521549Y7976D01*
X521544Y8016D01*
X521529Y8061D01*
X521519Y8101D01*
X521504Y8141D01*
X521484Y8181D01*
X521469Y8216D01*
X521449Y8256D01*
X521349Y8396D01*
X521319Y8426D01*
Y9556D01*
X521309Y9681D01*
X521269Y9806D01*
X521209Y9916D01*
X521129Y10016D01*
X521029Y10096D01*
X520919Y10156D01*
X520794Y10196D01*
X520669Y10206D01*
X520544Y10196D01*
X520419Y10156D01*
X520309Y10096D01*
X520209Y10016D01*
X520129Y9916D01*
X520069Y9806D01*
X520029Y9681D01*
X520019Y9556D01*
Y8426D01*
X519989Y8396D01*
X519889Y8256D01*
X519869Y8216D01*
X519854Y8181D01*
X519834Y8141D01*
X519819Y8101D01*
X519809Y8061D01*
X519794Y8016D01*
X519789Y7976D01*
X519779Y7936D01*
X519774Y7891D01*
Y7851D01*
X519769Y7806D01*
X519774Y7761D01*
Y7721D01*
X519779Y7676D01*
X519789Y7636D01*
X519794Y7596D01*
X519809Y7551D01*
X519819Y7511D01*
X519834Y7471D01*
X519854Y7431D01*
X519869Y7396D01*
X519889Y7356D01*
X519989Y7216D01*
X520019Y7186D01*
Y3756D01*
X520029Y3631D01*
X520069Y3506D01*
X520129Y3396D01*
X520209Y3296D01*
X520309Y3216D01*
X520419Y3156D01*
X520544Y3116D01*
X520669Y3106D01*
G37*
G36*
G01X515945D02*
X516070Y3116D01*
X516195Y3156D01*
X516305Y3216D01*
X516405Y3296D01*
X516485Y3396D01*
X516545Y3506D01*
X516585Y3631D01*
X516595Y3756D01*
Y7186D01*
X516625Y7216D01*
X516725Y7356D01*
X516745Y7396D01*
X516760Y7431D01*
X516780Y7471D01*
X516795Y7511D01*
X516805Y7551D01*
X516820Y7596D01*
X516825Y7636D01*
X516835Y7676D01*
X516840Y7721D01*
Y7761D01*
X516845Y7806D01*
X516840Y7851D01*
Y7891D01*
X516835Y7936D01*
X516825Y7976D01*
X516820Y8016D01*
X516805Y8061D01*
X516795Y8101D01*
X516780Y8141D01*
X516760Y8181D01*
X516745Y8216D01*
X516725Y8256D01*
X516625Y8396D01*
X516595Y8426D01*
Y9556D01*
X516585Y9681D01*
X516545Y9806D01*
X516485Y9916D01*
X516405Y10016D01*
X516305Y10096D01*
X516195Y10156D01*
X516070Y10196D01*
X515945Y10206D01*
X515820Y10196D01*
X515695Y10156D01*
X515585Y10096D01*
X515485Y10016D01*
X515405Y9916D01*
X515345Y9806D01*
X515305Y9681D01*
X515295Y9556D01*
Y8426D01*
X515265Y8396D01*
X515165Y8256D01*
X515145Y8216D01*
X515130Y8181D01*
X515110Y8141D01*
X515095Y8101D01*
X515085Y8061D01*
X515070Y8016D01*
X515065Y7976D01*
X515055Y7936D01*
X515050Y7891D01*
Y7851D01*
X515045Y7806D01*
X515050Y7761D01*
Y7721D01*
X515055Y7676D01*
X515065Y7636D01*
X515070Y7596D01*
X515085Y7551D01*
X515095Y7511D01*
X515110Y7471D01*
X515130Y7431D01*
X515145Y7396D01*
X515165Y7356D01*
X515265Y7216D01*
X515295Y7186D01*
Y3756D01*
X515305Y3631D01*
X515345Y3506D01*
X515405Y3396D01*
X515485Y3296D01*
X515585Y3216D01*
X515695Y3156D01*
X515820Y3116D01*
X515945Y3106D01*
G37*
G36*
G01X511220D02*
X511345Y3116D01*
X511470Y3156D01*
X511580Y3216D01*
X511680Y3296D01*
X511760Y3396D01*
X511820Y3506D01*
X511860Y3631D01*
X511870Y3756D01*
Y7186D01*
X511900Y7216D01*
X512000Y7356D01*
X512020Y7396D01*
X512035Y7431D01*
X512055Y7471D01*
X512070Y7511D01*
X512080Y7551D01*
X512095Y7596D01*
X512100Y7636D01*
X512110Y7676D01*
X512115Y7721D01*
Y7761D01*
X512120Y7806D01*
X512115Y7851D01*
Y7891D01*
X512110Y7936D01*
X512100Y7976D01*
X512095Y8016D01*
X512080Y8061D01*
X512070Y8101D01*
X512055Y8141D01*
X512035Y8181D01*
X512020Y8216D01*
X512000Y8256D01*
X511900Y8396D01*
X511870Y8426D01*
Y9556D01*
X511860Y9681D01*
X511820Y9806D01*
X511760Y9916D01*
X511680Y10016D01*
X511580Y10096D01*
X511470Y10156D01*
X511345Y10196D01*
X511220Y10206D01*
X511095Y10196D01*
X510970Y10156D01*
X510860Y10096D01*
X510760Y10016D01*
X510680Y9916D01*
X510620Y9806D01*
X510580Y9681D01*
X510570Y9556D01*
Y8426D01*
X510540Y8396D01*
X510440Y8256D01*
X510420Y8216D01*
X510405Y8181D01*
X510385Y8141D01*
X510370Y8101D01*
X510360Y8061D01*
X510345Y8016D01*
X510340Y7976D01*
X510330Y7936D01*
X510325Y7891D01*
Y7851D01*
X510320Y7806D01*
X510325Y7761D01*
Y7721D01*
X510330Y7676D01*
X510340Y7636D01*
X510345Y7596D01*
X510360Y7551D01*
X510370Y7511D01*
X510385Y7471D01*
X510405Y7431D01*
X510420Y7396D01*
X510440Y7356D01*
X510540Y7216D01*
X510570Y7186D01*
Y3756D01*
X510580Y3631D01*
X510620Y3506D01*
X510680Y3396D01*
X510760Y3296D01*
X510860Y3216D01*
X510970Y3156D01*
X511095Y3116D01*
X511220Y3106D01*
G37*
G36*
G01X539567D02*
X539692Y3116D01*
X539817Y3156D01*
X539927Y3216D01*
X540027Y3296D01*
X540107Y3396D01*
X540167Y3506D01*
X540207Y3631D01*
X540217Y3756D01*
Y7186D01*
X540247Y7216D01*
X540347Y7356D01*
X540367Y7396D01*
X540382Y7431D01*
X540402Y7471D01*
X540417Y7511D01*
X540427Y7551D01*
X540442Y7596D01*
X540447Y7636D01*
X540457Y7676D01*
X540462Y7721D01*
Y7761D01*
X540467Y7806D01*
X540462Y7851D01*
Y7891D01*
X540457Y7936D01*
X540447Y7976D01*
X540442Y8016D01*
X540427Y8061D01*
X540417Y8101D01*
X540402Y8141D01*
X540382Y8181D01*
X540367Y8216D01*
X540347Y8256D01*
X540247Y8396D01*
X540217Y8426D01*
Y9556D01*
X540207Y9681D01*
X540167Y9806D01*
X540107Y9916D01*
X540027Y10016D01*
X539927Y10096D01*
X539817Y10156D01*
X539692Y10196D01*
X539567Y10206D01*
X539442Y10196D01*
X539317Y10156D01*
X539207Y10096D01*
X539107Y10016D01*
X539027Y9916D01*
X538967Y9806D01*
X538927Y9681D01*
X538917Y9556D01*
Y8426D01*
X538887Y8396D01*
X538787Y8256D01*
X538767Y8216D01*
X538752Y8181D01*
X538732Y8141D01*
X538717Y8101D01*
X538707Y8061D01*
X538692Y8016D01*
X538687Y7976D01*
X538677Y7936D01*
X538672Y7891D01*
Y7851D01*
X538667Y7806D01*
X538672Y7761D01*
Y7721D01*
X538677Y7676D01*
X538687Y7636D01*
X538692Y7596D01*
X538707Y7551D01*
X538717Y7511D01*
X538732Y7471D01*
X538752Y7431D01*
X538767Y7396D01*
X538787Y7356D01*
X538887Y7216D01*
X538917Y7186D01*
Y3756D01*
X538927Y3631D01*
X538967Y3506D01*
X539027Y3396D01*
X539107Y3296D01*
X539207Y3216D01*
X539317Y3156D01*
X539442Y3116D01*
X539567Y3106D01*
G37*
G36*
G01X534842D02*
X534967Y3116D01*
X535092Y3156D01*
X535202Y3216D01*
X535302Y3296D01*
X535382Y3396D01*
X535442Y3506D01*
X535482Y3631D01*
X535492Y3756D01*
Y7186D01*
X535522Y7216D01*
X535622Y7356D01*
X535642Y7396D01*
X535657Y7431D01*
X535677Y7471D01*
X535692Y7511D01*
X535702Y7551D01*
X535717Y7596D01*
X535722Y7636D01*
X535732Y7676D01*
X535737Y7721D01*
Y7761D01*
X535742Y7806D01*
X535737Y7851D01*
Y7891D01*
X535732Y7936D01*
X535722Y7976D01*
X535717Y8016D01*
X535702Y8061D01*
X535692Y8101D01*
X535677Y8141D01*
X535657Y8181D01*
X535642Y8216D01*
X535622Y8256D01*
X535522Y8396D01*
X535492Y8426D01*
Y9556D01*
X535482Y9681D01*
X535442Y9806D01*
X535382Y9916D01*
X535302Y10016D01*
X535202Y10096D01*
X535092Y10156D01*
X534967Y10196D01*
X534842Y10206D01*
X534717Y10196D01*
X534592Y10156D01*
X534482Y10096D01*
X534382Y10016D01*
X534302Y9916D01*
X534242Y9806D01*
X534202Y9681D01*
X534192Y9556D01*
Y8426D01*
X534162Y8396D01*
X534062Y8256D01*
X534042Y8216D01*
X534027Y8181D01*
X534007Y8141D01*
X533992Y8101D01*
X533982Y8061D01*
X533967Y8016D01*
X533962Y7976D01*
X533952Y7936D01*
X533947Y7891D01*
Y7851D01*
X533942Y7806D01*
X533947Y7761D01*
Y7721D01*
X533952Y7676D01*
X533962Y7636D01*
X533967Y7596D01*
X533982Y7551D01*
X533992Y7511D01*
X534007Y7471D01*
X534027Y7431D01*
X534042Y7396D01*
X534062Y7356D01*
X534162Y7216D01*
X534192Y7186D01*
Y3756D01*
X534202Y3631D01*
X534242Y3506D01*
X534302Y3396D01*
X534382Y3296D01*
X534482Y3216D01*
X534592Y3156D01*
X534717Y3116D01*
X534842Y3106D01*
G37*
G36*
G01X530118D02*
X530243Y3116D01*
X530368Y3156D01*
X530478Y3216D01*
X530578Y3296D01*
X530658Y3396D01*
X530718Y3506D01*
X530758Y3631D01*
X530768Y3756D01*
Y7186D01*
X530798Y7216D01*
X530898Y7356D01*
X530918Y7396D01*
X530933Y7431D01*
X530953Y7471D01*
X530968Y7511D01*
X530978Y7551D01*
X530993Y7596D01*
X530998Y7636D01*
X531008Y7676D01*
X531013Y7721D01*
Y7761D01*
X531018Y7806D01*
X531013Y7851D01*
Y7891D01*
X531008Y7936D01*
X530998Y7976D01*
X530993Y8016D01*
X530978Y8061D01*
X530968Y8101D01*
X530953Y8141D01*
X530933Y8181D01*
X530918Y8216D01*
X530898Y8256D01*
X530798Y8396D01*
X530768Y8426D01*
Y9556D01*
X530758Y9681D01*
X530718Y9806D01*
X530658Y9916D01*
X530578Y10016D01*
X530478Y10096D01*
X530368Y10156D01*
X530243Y10196D01*
X530118Y10206D01*
X529993Y10196D01*
X529868Y10156D01*
X529758Y10096D01*
X529658Y10016D01*
X529578Y9916D01*
X529518Y9806D01*
X529478Y9681D01*
X529468Y9556D01*
Y8426D01*
X529438Y8396D01*
X529338Y8256D01*
X529318Y8216D01*
X529303Y8181D01*
X529283Y8141D01*
X529268Y8101D01*
X529258Y8061D01*
X529243Y8016D01*
X529238Y7976D01*
X529228Y7936D01*
X529223Y7891D01*
Y7851D01*
X529218Y7806D01*
X529223Y7761D01*
Y7721D01*
X529228Y7676D01*
X529238Y7636D01*
X529243Y7596D01*
X529258Y7551D01*
X529268Y7511D01*
X529283Y7471D01*
X529303Y7431D01*
X529318Y7396D01*
X529338Y7356D01*
X529438Y7216D01*
X529468Y7186D01*
Y3756D01*
X529478Y3631D01*
X529518Y3506D01*
X529578Y3396D01*
X529658Y3296D01*
X529758Y3216D01*
X529868Y3156D01*
X529993Y3116D01*
X530118Y3106D01*
G37*
G36*
G01X553740D02*
X553865Y3116D01*
X553990Y3156D01*
X554100Y3216D01*
X554200Y3296D01*
X554280Y3396D01*
X554340Y3506D01*
X554380Y3631D01*
X554390Y3756D01*
Y7186D01*
X554420Y7216D01*
X554520Y7356D01*
X554540Y7396D01*
X554555Y7431D01*
X554575Y7471D01*
X554590Y7511D01*
X554600Y7551D01*
X554615Y7596D01*
X554620Y7636D01*
X554630Y7676D01*
X554635Y7721D01*
Y7761D01*
X554640Y7806D01*
X554635Y7851D01*
Y7891D01*
X554630Y7936D01*
X554620Y7976D01*
X554615Y8016D01*
X554600Y8061D01*
X554590Y8101D01*
X554575Y8141D01*
X554555Y8181D01*
X554540Y8216D01*
X554520Y8256D01*
X554420Y8396D01*
X554390Y8426D01*
Y9556D01*
X554380Y9681D01*
X554340Y9806D01*
X554280Y9916D01*
X554200Y10016D01*
X554100Y10096D01*
X553990Y10156D01*
X553865Y10196D01*
X553740Y10206D01*
X553615Y10196D01*
X553490Y10156D01*
X553380Y10096D01*
X553280Y10016D01*
X553200Y9916D01*
X553140Y9806D01*
X553100Y9681D01*
X553090Y9556D01*
Y8426D01*
X553060Y8396D01*
X552960Y8256D01*
X552940Y8216D01*
X552925Y8181D01*
X552905Y8141D01*
X552890Y8101D01*
X552880Y8061D01*
X552865Y8016D01*
X552860Y7976D01*
X552850Y7936D01*
X552845Y7891D01*
Y7851D01*
X552840Y7806D01*
X552845Y7761D01*
Y7721D01*
X552850Y7676D01*
X552860Y7636D01*
X552865Y7596D01*
X552880Y7551D01*
X552890Y7511D01*
X552905Y7471D01*
X552925Y7431D01*
X552940Y7396D01*
X552960Y7356D01*
X553060Y7216D01*
X553090Y7186D01*
Y3756D01*
X553100Y3631D01*
X553140Y3506D01*
X553200Y3396D01*
X553280Y3296D01*
X553380Y3216D01*
X553490Y3156D01*
X553615Y3116D01*
X553740Y3106D01*
G37*
G36*
G01X549015D02*
X549140Y3116D01*
X549265Y3156D01*
X549375Y3216D01*
X549475Y3296D01*
X549555Y3396D01*
X549615Y3506D01*
X549655Y3631D01*
X549665Y3756D01*
Y7186D01*
X549695Y7216D01*
X549795Y7356D01*
X549815Y7396D01*
X549830Y7431D01*
X549850Y7471D01*
X549865Y7511D01*
X549875Y7551D01*
X549890Y7596D01*
X549895Y7636D01*
X549905Y7676D01*
X549910Y7721D01*
Y7761D01*
X549915Y7806D01*
X549910Y7851D01*
Y7891D01*
X549905Y7936D01*
X549895Y7976D01*
X549890Y8016D01*
X549875Y8061D01*
X549865Y8101D01*
X549850Y8141D01*
X549830Y8181D01*
X549815Y8216D01*
X549795Y8256D01*
X549695Y8396D01*
X549665Y8426D01*
Y9556D01*
X549655Y9681D01*
X549615Y9806D01*
X549555Y9916D01*
X549475Y10016D01*
X549375Y10096D01*
X549265Y10156D01*
X549140Y10196D01*
X549015Y10206D01*
X548890Y10196D01*
X548765Y10156D01*
X548655Y10096D01*
X548555Y10016D01*
X548475Y9916D01*
X548415Y9806D01*
X548375Y9681D01*
X548365Y9556D01*
Y8426D01*
X548335Y8396D01*
X548235Y8256D01*
X548215Y8216D01*
X548200Y8181D01*
X548180Y8141D01*
X548165Y8101D01*
X548155Y8061D01*
X548140Y8016D01*
X548135Y7976D01*
X548125Y7936D01*
X548120Y7891D01*
Y7851D01*
X548115Y7806D01*
X548120Y7761D01*
Y7721D01*
X548125Y7676D01*
X548135Y7636D01*
X548140Y7596D01*
X548155Y7551D01*
X548165Y7511D01*
X548180Y7471D01*
X548200Y7431D01*
X548215Y7396D01*
X548235Y7356D01*
X548335Y7216D01*
X548365Y7186D01*
Y3756D01*
X548375Y3631D01*
X548415Y3506D01*
X548475Y3396D01*
X548555Y3296D01*
X548655Y3216D01*
X548765Y3156D01*
X548890Y3116D01*
X549015Y3106D01*
G37*
G36*
G01X544291D02*
X544416Y3116D01*
X544541Y3156D01*
X544651Y3216D01*
X544751Y3296D01*
X544831Y3396D01*
X544891Y3506D01*
X544931Y3631D01*
X544941Y3756D01*
Y7186D01*
X544971Y7216D01*
X545071Y7356D01*
X545091Y7396D01*
X545106Y7431D01*
X545126Y7471D01*
X545141Y7511D01*
X545151Y7551D01*
X545166Y7596D01*
X545171Y7636D01*
X545181Y7676D01*
X545186Y7721D01*
Y7761D01*
X545191Y7806D01*
X545186Y7851D01*
Y7891D01*
X545181Y7936D01*
X545171Y7976D01*
X545166Y8016D01*
X545151Y8061D01*
X545141Y8101D01*
X545126Y8141D01*
X545106Y8181D01*
X545091Y8216D01*
X545071Y8256D01*
X544971Y8396D01*
X544941Y8426D01*
Y9556D01*
X544931Y9681D01*
X544891Y9806D01*
X544831Y9916D01*
X544751Y10016D01*
X544651Y10096D01*
X544541Y10156D01*
X544416Y10196D01*
X544291Y10206D01*
X544166Y10196D01*
X544041Y10156D01*
X543931Y10096D01*
X543831Y10016D01*
X543751Y9916D01*
X543691Y9806D01*
X543651Y9681D01*
X543641Y9556D01*
Y8426D01*
X543611Y8396D01*
X543511Y8256D01*
X543491Y8216D01*
X543476Y8181D01*
X543456Y8141D01*
X543441Y8101D01*
X543431Y8061D01*
X543416Y8016D01*
X543411Y7976D01*
X543401Y7936D01*
X543396Y7891D01*
Y7851D01*
X543391Y7806D01*
X543396Y7761D01*
Y7721D01*
X543401Y7676D01*
X543411Y7636D01*
X543416Y7596D01*
X543431Y7551D01*
X543441Y7511D01*
X543456Y7471D01*
X543476Y7431D01*
X543491Y7396D01*
X543511Y7356D01*
X543611Y7216D01*
X543641Y7186D01*
Y3756D01*
X543651Y3631D01*
X543691Y3506D01*
X543751Y3396D01*
X543831Y3296D01*
X543931Y3216D01*
X544041Y3156D01*
X544166Y3116D01*
X544291Y3106D01*
G37*
G36*
G01X572638D02*
X572763Y3116D01*
X572888Y3156D01*
X572998Y3216D01*
X573098Y3296D01*
X573178Y3396D01*
X573238Y3506D01*
X573278Y3631D01*
X573288Y3756D01*
Y7186D01*
X573318Y7216D01*
X573418Y7356D01*
X573438Y7396D01*
X573453Y7431D01*
X573473Y7471D01*
X573488Y7511D01*
X573498Y7551D01*
X573513Y7596D01*
X573518Y7636D01*
X573528Y7676D01*
X573533Y7721D01*
Y7761D01*
X573538Y7806D01*
X573533Y7851D01*
Y7891D01*
X573528Y7936D01*
X573518Y7976D01*
X573513Y8016D01*
X573498Y8061D01*
X573488Y8101D01*
X573473Y8141D01*
X573453Y8181D01*
X573438Y8216D01*
X573418Y8256D01*
X573318Y8396D01*
X573288Y8426D01*
Y9556D01*
X573278Y9681D01*
X573238Y9806D01*
X573178Y9916D01*
X573098Y10016D01*
X572998Y10096D01*
X572888Y10156D01*
X572763Y10196D01*
X572638Y10206D01*
X572513Y10196D01*
X572388Y10156D01*
X572278Y10096D01*
X572178Y10016D01*
X572098Y9916D01*
X572038Y9806D01*
X571998Y9681D01*
X571988Y9556D01*
Y8426D01*
X571958Y8396D01*
X571858Y8256D01*
X571838Y8216D01*
X571823Y8181D01*
X571803Y8141D01*
X571788Y8101D01*
X571778Y8061D01*
X571763Y8016D01*
X571758Y7976D01*
X571748Y7936D01*
X571743Y7891D01*
Y7851D01*
X571738Y7806D01*
X571743Y7761D01*
Y7721D01*
X571748Y7676D01*
X571758Y7636D01*
X571763Y7596D01*
X571778Y7551D01*
X571788Y7511D01*
X571803Y7471D01*
X571823Y7431D01*
X571838Y7396D01*
X571858Y7356D01*
X571958Y7216D01*
X571988Y7186D01*
Y3756D01*
X571998Y3631D01*
X572038Y3506D01*
X572098Y3396D01*
X572178Y3296D01*
X572278Y3216D01*
X572388Y3156D01*
X572513Y3116D01*
X572638Y3106D01*
G37*
G36*
G01X567913D02*
X568038Y3116D01*
X568163Y3156D01*
X568273Y3216D01*
X568373Y3296D01*
X568453Y3396D01*
X568513Y3506D01*
X568553Y3631D01*
X568563Y3756D01*
Y7186D01*
X568593Y7216D01*
X568693Y7356D01*
X568713Y7396D01*
X568728Y7431D01*
X568748Y7471D01*
X568763Y7511D01*
X568773Y7551D01*
X568788Y7596D01*
X568793Y7636D01*
X568803Y7676D01*
X568808Y7721D01*
Y7761D01*
X568813Y7806D01*
X568808Y7851D01*
Y7891D01*
X568803Y7936D01*
X568793Y7976D01*
X568788Y8016D01*
X568773Y8061D01*
X568763Y8101D01*
X568748Y8141D01*
X568728Y8181D01*
X568713Y8216D01*
X568693Y8256D01*
X568593Y8396D01*
X568563Y8426D01*
Y9556D01*
X568553Y9681D01*
X568513Y9806D01*
X568453Y9916D01*
X568373Y10016D01*
X568273Y10096D01*
X568163Y10156D01*
X568038Y10196D01*
X567913Y10206D01*
X567788Y10196D01*
X567663Y10156D01*
X567553Y10096D01*
X567453Y10016D01*
X567373Y9916D01*
X567313Y9806D01*
X567273Y9681D01*
X567263Y9556D01*
Y8426D01*
X567233Y8396D01*
X567133Y8256D01*
X567113Y8216D01*
X567098Y8181D01*
X567078Y8141D01*
X567063Y8101D01*
X567053Y8061D01*
X567038Y8016D01*
X567033Y7976D01*
X567023Y7936D01*
X567018Y7891D01*
Y7851D01*
X567013Y7806D01*
X567018Y7761D01*
Y7721D01*
X567023Y7676D01*
X567033Y7636D01*
X567038Y7596D01*
X567053Y7551D01*
X567063Y7511D01*
X567078Y7471D01*
X567098Y7431D01*
X567113Y7396D01*
X567133Y7356D01*
X567233Y7216D01*
X567263Y7186D01*
Y3756D01*
X567273Y3631D01*
X567313Y3506D01*
X567373Y3396D01*
X567453Y3296D01*
X567553Y3216D01*
X567663Y3156D01*
X567788Y3116D01*
X567913Y3106D01*
G37*
G36*
G01X563189D02*
X563314Y3116D01*
X563439Y3156D01*
X563549Y3216D01*
X563649Y3296D01*
X563729Y3396D01*
X563789Y3506D01*
X563829Y3631D01*
X563839Y3756D01*
Y7186D01*
X563869Y7216D01*
X563969Y7356D01*
X563989Y7396D01*
X564004Y7431D01*
X564024Y7471D01*
X564039Y7511D01*
X564049Y7551D01*
X564064Y7596D01*
X564069Y7636D01*
X564079Y7676D01*
X564084Y7721D01*
Y7761D01*
X564089Y7806D01*
X564084Y7851D01*
Y7891D01*
X564079Y7936D01*
X564069Y7976D01*
X564064Y8016D01*
X564049Y8061D01*
X564039Y8101D01*
X564024Y8141D01*
X564004Y8181D01*
X563989Y8216D01*
X563969Y8256D01*
X563869Y8396D01*
X563839Y8426D01*
Y9556D01*
X563829Y9681D01*
X563789Y9806D01*
X563729Y9916D01*
X563649Y10016D01*
X563549Y10096D01*
X563439Y10156D01*
X563314Y10196D01*
X563189Y10206D01*
X563064Y10196D01*
X562939Y10156D01*
X562829Y10096D01*
X562729Y10016D01*
X562649Y9916D01*
X562589Y9806D01*
X562549Y9681D01*
X562539Y9556D01*
Y8426D01*
X562509Y8396D01*
X562409Y8256D01*
X562389Y8216D01*
X562374Y8181D01*
X562354Y8141D01*
X562339Y8101D01*
X562329Y8061D01*
X562314Y8016D01*
X562309Y7976D01*
X562299Y7936D01*
X562294Y7891D01*
Y7851D01*
X562289Y7806D01*
X562294Y7761D01*
Y7721D01*
X562299Y7676D01*
X562309Y7636D01*
X562314Y7596D01*
X562329Y7551D01*
X562339Y7511D01*
X562354Y7471D01*
X562374Y7431D01*
X562389Y7396D01*
X562409Y7356D01*
X562509Y7216D01*
X562539Y7186D01*
Y3756D01*
X562549Y3631D01*
X562589Y3506D01*
X562649Y3396D01*
X562729Y3296D01*
X562829Y3216D01*
X562939Y3156D01*
X563064Y3116D01*
X563189Y3106D01*
G37*
G36*
G01X558464D02*
X558589Y3116D01*
X558714Y3156D01*
X558824Y3216D01*
X558924Y3296D01*
X559004Y3396D01*
X559064Y3506D01*
X559104Y3631D01*
X559114Y3756D01*
Y7186D01*
X559144Y7216D01*
X559244Y7356D01*
X559264Y7396D01*
X559279Y7431D01*
X559299Y7471D01*
X559314Y7511D01*
X559324Y7551D01*
X559339Y7596D01*
X559344Y7636D01*
X559354Y7676D01*
X559359Y7721D01*
Y7761D01*
X559364Y7806D01*
X559359Y7851D01*
Y7891D01*
X559354Y7936D01*
X559344Y7976D01*
X559339Y8016D01*
X559324Y8061D01*
X559314Y8101D01*
X559299Y8141D01*
X559279Y8181D01*
X559264Y8216D01*
X559244Y8256D01*
X559144Y8396D01*
X559114Y8426D01*
Y9556D01*
X559104Y9681D01*
X559064Y9806D01*
X559004Y9916D01*
X558924Y10016D01*
X558824Y10096D01*
X558714Y10156D01*
X558589Y10196D01*
X558464Y10206D01*
X558339Y10196D01*
X558214Y10156D01*
X558104Y10096D01*
X558004Y10016D01*
X557924Y9916D01*
X557864Y9806D01*
X557824Y9681D01*
X557814Y9556D01*
Y8426D01*
X557784Y8396D01*
X557684Y8256D01*
X557664Y8216D01*
X557649Y8181D01*
X557629Y8141D01*
X557614Y8101D01*
X557604Y8061D01*
X557589Y8016D01*
X557584Y7976D01*
X557574Y7936D01*
X557569Y7891D01*
Y7851D01*
X557564Y7806D01*
X557569Y7761D01*
Y7721D01*
X557574Y7676D01*
X557584Y7636D01*
X557589Y7596D01*
X557604Y7551D01*
X557614Y7511D01*
X557629Y7471D01*
X557649Y7431D01*
X557664Y7396D01*
X557684Y7356D01*
X557784Y7216D01*
X557814Y7186D01*
Y3756D01*
X557824Y3631D01*
X557864Y3506D01*
X557924Y3396D01*
X558004Y3296D01*
X558104Y3216D01*
X558214Y3156D01*
X558339Y3116D01*
X558464Y3106D01*
G37*
G36*
G01X586811D02*
X586936Y3116D01*
X587061Y3156D01*
X587171Y3216D01*
X587271Y3296D01*
X587351Y3396D01*
X587411Y3506D01*
X587451Y3631D01*
X587461Y3756D01*
Y7186D01*
X587491Y7216D01*
X587591Y7356D01*
X587611Y7396D01*
X587626Y7431D01*
X587646Y7471D01*
X587661Y7511D01*
X587671Y7551D01*
X587686Y7596D01*
X587691Y7636D01*
X587701Y7676D01*
X587706Y7721D01*
Y7761D01*
X587711Y7806D01*
X587706Y7851D01*
Y7891D01*
X587701Y7936D01*
X587691Y7976D01*
X587686Y8016D01*
X587671Y8061D01*
X587661Y8101D01*
X587646Y8141D01*
X587626Y8181D01*
X587611Y8216D01*
X587591Y8256D01*
X587491Y8396D01*
X587461Y8426D01*
Y9556D01*
X587451Y9681D01*
X587411Y9806D01*
X587351Y9916D01*
X587271Y10016D01*
X587171Y10096D01*
X587061Y10156D01*
X586936Y10196D01*
X586811Y10206D01*
X586686Y10196D01*
X586561Y10156D01*
X586451Y10096D01*
X586351Y10016D01*
X586271Y9916D01*
X586211Y9806D01*
X586171Y9681D01*
X586161Y9556D01*
Y8426D01*
X586131Y8396D01*
X586031Y8256D01*
X586011Y8216D01*
X585996Y8181D01*
X585976Y8141D01*
X585961Y8101D01*
X585951Y8061D01*
X585936Y8016D01*
X585931Y7976D01*
X585921Y7936D01*
X585916Y7891D01*
Y7851D01*
X585911Y7806D01*
X585916Y7761D01*
Y7721D01*
X585921Y7676D01*
X585931Y7636D01*
X585936Y7596D01*
X585951Y7551D01*
X585961Y7511D01*
X585976Y7471D01*
X585996Y7431D01*
X586011Y7396D01*
X586031Y7356D01*
X586131Y7216D01*
X586161Y7186D01*
Y3756D01*
X586171Y3631D01*
X586211Y3506D01*
X586271Y3396D01*
X586351Y3296D01*
X586451Y3216D01*
X586561Y3156D01*
X586686Y3116D01*
X586811Y3106D01*
G37*
G36*
G01X582086D02*
X582211Y3116D01*
X582336Y3156D01*
X582446Y3216D01*
X582546Y3296D01*
X582626Y3396D01*
X582686Y3506D01*
X582726Y3631D01*
X582736Y3756D01*
Y7186D01*
X582766Y7216D01*
X582866Y7356D01*
X582886Y7396D01*
X582901Y7431D01*
X582921Y7471D01*
X582936Y7511D01*
X582946Y7551D01*
X582961Y7596D01*
X582966Y7636D01*
X582976Y7676D01*
X582981Y7721D01*
Y7761D01*
X582986Y7806D01*
X582981Y7851D01*
Y7891D01*
X582976Y7936D01*
X582966Y7976D01*
X582961Y8016D01*
X582946Y8061D01*
X582936Y8101D01*
X582921Y8141D01*
X582901Y8181D01*
X582886Y8216D01*
X582866Y8256D01*
X582766Y8396D01*
X582736Y8426D01*
Y9556D01*
X582726Y9681D01*
X582686Y9806D01*
X582626Y9916D01*
X582546Y10016D01*
X582446Y10096D01*
X582336Y10156D01*
X582211Y10196D01*
X582086Y10206D01*
X581961Y10196D01*
X581836Y10156D01*
X581726Y10096D01*
X581626Y10016D01*
X581546Y9916D01*
X581486Y9806D01*
X581446Y9681D01*
X581436Y9556D01*
Y8426D01*
X581406Y8396D01*
X581306Y8256D01*
X581286Y8216D01*
X581271Y8181D01*
X581251Y8141D01*
X581236Y8101D01*
X581226Y8061D01*
X581211Y8016D01*
X581206Y7976D01*
X581196Y7936D01*
X581191Y7891D01*
Y7851D01*
X581186Y7806D01*
X581191Y7761D01*
Y7721D01*
X581196Y7676D01*
X581206Y7636D01*
X581211Y7596D01*
X581226Y7551D01*
X581236Y7511D01*
X581251Y7471D01*
X581271Y7431D01*
X581286Y7396D01*
X581306Y7356D01*
X581406Y7216D01*
X581436Y7186D01*
Y3756D01*
X581446Y3631D01*
X581486Y3506D01*
X581546Y3396D01*
X581626Y3296D01*
X581726Y3216D01*
X581836Y3156D01*
X581961Y3116D01*
X582086Y3106D01*
G37*
G36*
G01X577362D02*
X577487Y3116D01*
X577612Y3156D01*
X577722Y3216D01*
X577822Y3296D01*
X577902Y3396D01*
X577962Y3506D01*
X578002Y3631D01*
X578012Y3756D01*
Y7186D01*
X578042Y7216D01*
X578142Y7356D01*
X578162Y7396D01*
X578177Y7431D01*
X578197Y7471D01*
X578212Y7511D01*
X578222Y7551D01*
X578237Y7596D01*
X578242Y7636D01*
X578252Y7676D01*
X578257Y7721D01*
Y7761D01*
X578262Y7806D01*
X578257Y7851D01*
Y7891D01*
X578252Y7936D01*
X578242Y7976D01*
X578237Y8016D01*
X578222Y8061D01*
X578212Y8101D01*
X578197Y8141D01*
X578177Y8181D01*
X578162Y8216D01*
X578142Y8256D01*
X578042Y8396D01*
X578012Y8426D01*
Y9556D01*
X578002Y9681D01*
X577962Y9806D01*
X577902Y9916D01*
X577822Y10016D01*
X577722Y10096D01*
X577612Y10156D01*
X577487Y10196D01*
X577362Y10206D01*
X577237Y10196D01*
X577112Y10156D01*
X577002Y10096D01*
X576902Y10016D01*
X576822Y9916D01*
X576762Y9806D01*
X576722Y9681D01*
X576712Y9556D01*
Y8426D01*
X576682Y8396D01*
X576582Y8256D01*
X576562Y8216D01*
X576547Y8181D01*
X576527Y8141D01*
X576512Y8101D01*
X576502Y8061D01*
X576487Y8016D01*
X576482Y7976D01*
X576472Y7936D01*
X576467Y7891D01*
Y7851D01*
X576462Y7806D01*
X576467Y7761D01*
Y7721D01*
X576472Y7676D01*
X576482Y7636D01*
X576487Y7596D01*
X576502Y7551D01*
X576512Y7511D01*
X576527Y7471D01*
X576547Y7431D01*
X576562Y7396D01*
X576582Y7356D01*
X576682Y7216D01*
X576712Y7186D01*
Y3756D01*
X576722Y3631D01*
X576762Y3506D01*
X576822Y3396D01*
X576902Y3296D01*
X577002Y3216D01*
X577112Y3156D01*
X577237Y3116D01*
X577362Y3106D01*
G37*
G36*
G01X600984D02*
X601109Y3116D01*
X601234Y3156D01*
X601344Y3216D01*
X601444Y3296D01*
X601524Y3396D01*
X601584Y3506D01*
X601624Y3631D01*
X601634Y3756D01*
Y7186D01*
X601664Y7216D01*
X601764Y7356D01*
X601784Y7396D01*
X601799Y7431D01*
X601819Y7471D01*
X601834Y7511D01*
X601844Y7551D01*
X601859Y7596D01*
X601864Y7636D01*
X601874Y7676D01*
X601879Y7721D01*
Y7761D01*
X601884Y7806D01*
X601879Y7851D01*
Y7891D01*
X601874Y7936D01*
X601864Y7976D01*
X601859Y8016D01*
X601844Y8061D01*
X601834Y8101D01*
X601819Y8141D01*
X601799Y8181D01*
X601784Y8216D01*
X601764Y8256D01*
X601664Y8396D01*
X601634Y8426D01*
Y9556D01*
X601624Y9681D01*
X601584Y9806D01*
X601524Y9916D01*
X601444Y10016D01*
X601344Y10096D01*
X601234Y10156D01*
X601109Y10196D01*
X600984Y10206D01*
X600859Y10196D01*
X600734Y10156D01*
X600624Y10096D01*
X600524Y10016D01*
X600444Y9916D01*
X600384Y9806D01*
X600344Y9681D01*
X600334Y9556D01*
Y8426D01*
X600304Y8396D01*
X600204Y8256D01*
X600184Y8216D01*
X600169Y8181D01*
X600149Y8141D01*
X600134Y8101D01*
X600124Y8061D01*
X600109Y8016D01*
X600104Y7976D01*
X600094Y7936D01*
X600089Y7891D01*
Y7851D01*
X600084Y7806D01*
X600089Y7761D01*
Y7721D01*
X600094Y7676D01*
X600104Y7636D01*
X600109Y7596D01*
X600124Y7551D01*
X600134Y7511D01*
X600149Y7471D01*
X600169Y7431D01*
X600184Y7396D01*
X600204Y7356D01*
X600304Y7216D01*
X600334Y7186D01*
Y3756D01*
X600344Y3631D01*
X600384Y3506D01*
X600444Y3396D01*
X600524Y3296D01*
X600624Y3216D01*
X600734Y3156D01*
X600859Y3116D01*
X600984Y3106D01*
G37*
G36*
G01X615157D02*
X615282Y3116D01*
X615407Y3156D01*
X615517Y3216D01*
X615617Y3296D01*
X615697Y3396D01*
X615757Y3506D01*
X615797Y3631D01*
X615807Y3756D01*
Y7186D01*
X615837Y7216D01*
X615937Y7356D01*
X615957Y7396D01*
X615972Y7431D01*
X615992Y7471D01*
X616007Y7511D01*
X616017Y7551D01*
X616032Y7596D01*
X616037Y7636D01*
X616047Y7676D01*
X616052Y7721D01*
Y7761D01*
X616057Y7806D01*
X616052Y7851D01*
Y7891D01*
X616047Y7936D01*
X616037Y7976D01*
X616032Y8016D01*
X616017Y8061D01*
X616007Y8101D01*
X615992Y8141D01*
X615972Y8181D01*
X615957Y8216D01*
X615937Y8256D01*
X615837Y8396D01*
X615807Y8426D01*
Y9556D01*
X615797Y9681D01*
X615757Y9806D01*
X615697Y9916D01*
X615617Y10016D01*
X615517Y10096D01*
X615407Y10156D01*
X615282Y10196D01*
X615157Y10206D01*
X615032Y10196D01*
X614907Y10156D01*
X614797Y10096D01*
X614697Y10016D01*
X614617Y9916D01*
X614557Y9806D01*
X614517Y9681D01*
X614507Y9556D01*
Y8426D01*
X614477Y8396D01*
X614377Y8256D01*
X614357Y8216D01*
X614342Y8181D01*
X614322Y8141D01*
X614307Y8101D01*
X614297Y8061D01*
X614282Y8016D01*
X614277Y7976D01*
X614267Y7936D01*
X614262Y7891D01*
Y7851D01*
X614257Y7806D01*
X614262Y7761D01*
Y7721D01*
X614267Y7676D01*
X614277Y7636D01*
X614282Y7596D01*
X614297Y7551D01*
X614307Y7511D01*
X614322Y7471D01*
X614342Y7431D01*
X614357Y7396D01*
X614377Y7356D01*
X614477Y7216D01*
X614507Y7186D01*
Y3756D01*
X614517Y3631D01*
X614557Y3506D01*
X614617Y3396D01*
X614697Y3296D01*
X614797Y3216D01*
X614907Y3156D01*
X615032Y3116D01*
X615157Y3106D01*
G37*
G36*
G01X610433D02*
X610558Y3116D01*
X610683Y3156D01*
X610793Y3216D01*
X610893Y3296D01*
X610973Y3396D01*
X611033Y3506D01*
X611073Y3631D01*
X611083Y3756D01*
Y7186D01*
X611113Y7216D01*
X611213Y7356D01*
X611233Y7396D01*
X611248Y7431D01*
X611268Y7471D01*
X611283Y7511D01*
X611293Y7551D01*
X611308Y7596D01*
X611313Y7636D01*
X611323Y7676D01*
X611328Y7721D01*
Y7761D01*
X611333Y7806D01*
X611328Y7851D01*
Y7891D01*
X611323Y7936D01*
X611313Y7976D01*
X611308Y8016D01*
X611293Y8061D01*
X611283Y8101D01*
X611268Y8141D01*
X611248Y8181D01*
X611233Y8216D01*
X611213Y8256D01*
X611113Y8396D01*
X611083Y8426D01*
Y9556D01*
X611073Y9681D01*
X611033Y9806D01*
X610973Y9916D01*
X610893Y10016D01*
X610793Y10096D01*
X610683Y10156D01*
X610558Y10196D01*
X610433Y10206D01*
X610308Y10196D01*
X610183Y10156D01*
X610073Y10096D01*
X609973Y10016D01*
X609893Y9916D01*
X609833Y9806D01*
X609793Y9681D01*
X609783Y9556D01*
Y8426D01*
X609753Y8396D01*
X609653Y8256D01*
X609633Y8216D01*
X609618Y8181D01*
X609598Y8141D01*
X609583Y8101D01*
X609573Y8061D01*
X609558Y8016D01*
X609553Y7976D01*
X609543Y7936D01*
X609538Y7891D01*
Y7851D01*
X609533Y7806D01*
X609538Y7761D01*
Y7721D01*
X609543Y7676D01*
X609553Y7636D01*
X609558Y7596D01*
X609573Y7551D01*
X609583Y7511D01*
X609598Y7471D01*
X609618Y7431D01*
X609633Y7396D01*
X609653Y7356D01*
X609753Y7216D01*
X609783Y7186D01*
Y3756D01*
X609793Y3631D01*
X609833Y3506D01*
X609893Y3396D01*
X609973Y3296D01*
X610073Y3216D01*
X610183Y3156D01*
X610308Y3116D01*
X610433Y3106D01*
G37*
G36*
G01X605708D02*
X605833Y3116D01*
X605958Y3156D01*
X606068Y3216D01*
X606168Y3296D01*
X606248Y3396D01*
X606308Y3506D01*
X606348Y3631D01*
X606358Y3756D01*
Y7186D01*
X606388Y7216D01*
X606488Y7356D01*
X606508Y7396D01*
X606523Y7431D01*
X606543Y7471D01*
X606558Y7511D01*
X606568Y7551D01*
X606583Y7596D01*
X606588Y7636D01*
X606598Y7676D01*
X606603Y7721D01*
Y7761D01*
X606608Y7806D01*
X606603Y7851D01*
Y7891D01*
X606598Y7936D01*
X606588Y7976D01*
X606583Y8016D01*
X606568Y8061D01*
X606558Y8101D01*
X606543Y8141D01*
X606523Y8181D01*
X606508Y8216D01*
X606488Y8256D01*
X606388Y8396D01*
X606358Y8426D01*
Y9556D01*
X606348Y9681D01*
X606308Y9806D01*
X606248Y9916D01*
X606168Y10016D01*
X606068Y10096D01*
X605958Y10156D01*
X605833Y10196D01*
X605708Y10206D01*
X605583Y10196D01*
X605458Y10156D01*
X605348Y10096D01*
X605248Y10016D01*
X605168Y9916D01*
X605108Y9806D01*
X605068Y9681D01*
X605058Y9556D01*
Y8426D01*
X605028Y8396D01*
X604928Y8256D01*
X604908Y8216D01*
X604893Y8181D01*
X604873Y8141D01*
X604858Y8101D01*
X604848Y8061D01*
X604833Y8016D01*
X604828Y7976D01*
X604818Y7936D01*
X604813Y7891D01*
Y7851D01*
X604808Y7806D01*
X604813Y7761D01*
Y7721D01*
X604818Y7676D01*
X604828Y7636D01*
X604833Y7596D01*
X604848Y7551D01*
X604858Y7511D01*
X604873Y7471D01*
X604893Y7431D01*
X604908Y7396D01*
X604928Y7356D01*
X605028Y7216D01*
X605058Y7186D01*
Y3756D01*
X605068Y3631D01*
X605108Y3506D01*
X605168Y3396D01*
X605248Y3296D01*
X605348Y3216D01*
X605458Y3156D01*
X605583Y3116D01*
X605708Y3106D01*
G37*
G36*
G01X634055D02*
X634180Y3116D01*
X634305Y3156D01*
X634415Y3216D01*
X634515Y3296D01*
X634595Y3396D01*
X634655Y3506D01*
X634695Y3631D01*
X634705Y3756D01*
Y7186D01*
X634735Y7216D01*
X634835Y7356D01*
X634855Y7396D01*
X634870Y7431D01*
X634890Y7471D01*
X634905Y7511D01*
X634915Y7551D01*
X634930Y7596D01*
X634935Y7636D01*
X634945Y7676D01*
X634950Y7721D01*
Y7761D01*
X634955Y7806D01*
X634950Y7851D01*
Y7891D01*
X634945Y7936D01*
X634935Y7976D01*
X634930Y8016D01*
X634915Y8061D01*
X634905Y8101D01*
X634890Y8141D01*
X634870Y8181D01*
X634855Y8216D01*
X634835Y8256D01*
X634735Y8396D01*
X634705Y8426D01*
Y9556D01*
X634695Y9681D01*
X634655Y9806D01*
X634595Y9916D01*
X634515Y10016D01*
X634415Y10096D01*
X634305Y10156D01*
X634180Y10196D01*
X634055Y10206D01*
X633930Y10196D01*
X633805Y10156D01*
X633695Y10096D01*
X633595Y10016D01*
X633515Y9916D01*
X633455Y9806D01*
X633415Y9681D01*
X633405Y9556D01*
Y8426D01*
X633375Y8396D01*
X633275Y8256D01*
X633255Y8216D01*
X633240Y8181D01*
X633220Y8141D01*
X633205Y8101D01*
X633195Y8061D01*
X633180Y8016D01*
X633175Y7976D01*
X633165Y7936D01*
X633160Y7891D01*
Y7851D01*
X633155Y7806D01*
X633160Y7761D01*
Y7721D01*
X633165Y7676D01*
X633175Y7636D01*
X633180Y7596D01*
X633195Y7551D01*
X633205Y7511D01*
X633220Y7471D01*
X633240Y7431D01*
X633255Y7396D01*
X633275Y7356D01*
X633375Y7216D01*
X633405Y7186D01*
Y3756D01*
X633415Y3631D01*
X633455Y3506D01*
X633515Y3396D01*
X633595Y3296D01*
X633695Y3216D01*
X633805Y3156D01*
X633930Y3116D01*
X634055Y3106D01*
G37*
G36*
G01X629330D02*
X629455Y3116D01*
X629580Y3156D01*
X629690Y3216D01*
X629790Y3296D01*
X629870Y3396D01*
X629930Y3506D01*
X629970Y3631D01*
X629980Y3756D01*
Y7186D01*
X630010Y7216D01*
X630110Y7356D01*
X630130Y7396D01*
X630145Y7431D01*
X630165Y7471D01*
X630180Y7511D01*
X630190Y7551D01*
X630205Y7596D01*
X630210Y7636D01*
X630220Y7676D01*
X630225Y7721D01*
Y7761D01*
X630230Y7806D01*
X630225Y7851D01*
Y7891D01*
X630220Y7936D01*
X630210Y7976D01*
X630205Y8016D01*
X630190Y8061D01*
X630180Y8101D01*
X630165Y8141D01*
X630145Y8181D01*
X630130Y8216D01*
X630110Y8256D01*
X630010Y8396D01*
X629980Y8426D01*
Y9556D01*
X629970Y9681D01*
X629930Y9806D01*
X629870Y9916D01*
X629790Y10016D01*
X629690Y10096D01*
X629580Y10156D01*
X629455Y10196D01*
X629330Y10206D01*
X629205Y10196D01*
X629080Y10156D01*
X628970Y10096D01*
X628870Y10016D01*
X628790Y9916D01*
X628730Y9806D01*
X628690Y9681D01*
X628680Y9556D01*
Y8426D01*
X628650Y8396D01*
X628550Y8256D01*
X628530Y8216D01*
X628515Y8181D01*
X628495Y8141D01*
X628480Y8101D01*
X628470Y8061D01*
X628455Y8016D01*
X628450Y7976D01*
X628440Y7936D01*
X628435Y7891D01*
Y7851D01*
X628430Y7806D01*
X628435Y7761D01*
Y7721D01*
X628440Y7676D01*
X628450Y7636D01*
X628455Y7596D01*
X628470Y7551D01*
X628480Y7511D01*
X628495Y7471D01*
X628515Y7431D01*
X628530Y7396D01*
X628550Y7356D01*
X628650Y7216D01*
X628680Y7186D01*
Y3756D01*
X628690Y3631D01*
X628730Y3506D01*
X628790Y3396D01*
X628870Y3296D01*
X628970Y3216D01*
X629080Y3156D01*
X629205Y3116D01*
X629330Y3106D01*
G37*
G36*
G01X624606D02*
X624731Y3116D01*
X624856Y3156D01*
X624966Y3216D01*
X625066Y3296D01*
X625146Y3396D01*
X625206Y3506D01*
X625246Y3631D01*
X625256Y3756D01*
Y7186D01*
X625286Y7216D01*
X625386Y7356D01*
X625406Y7396D01*
X625421Y7431D01*
X625441Y7471D01*
X625456Y7511D01*
X625466Y7551D01*
X625481Y7596D01*
X625486Y7636D01*
X625496Y7676D01*
X625501Y7721D01*
Y7761D01*
X625506Y7806D01*
X625501Y7851D01*
Y7891D01*
X625496Y7936D01*
X625486Y7976D01*
X625481Y8016D01*
X625466Y8061D01*
X625456Y8101D01*
X625441Y8141D01*
X625421Y8181D01*
X625406Y8216D01*
X625386Y8256D01*
X625286Y8396D01*
X625256Y8426D01*
Y9556D01*
X625246Y9681D01*
X625206Y9806D01*
X625146Y9916D01*
X625066Y10016D01*
X624966Y10096D01*
X624856Y10156D01*
X624731Y10196D01*
X624606Y10206D01*
X624481Y10196D01*
X624356Y10156D01*
X624246Y10096D01*
X624146Y10016D01*
X624066Y9916D01*
X624006Y9806D01*
X623966Y9681D01*
X623956Y9556D01*
Y8426D01*
X623926Y8396D01*
X623826Y8256D01*
X623806Y8216D01*
X623791Y8181D01*
X623771Y8141D01*
X623756Y8101D01*
X623746Y8061D01*
X623731Y8016D01*
X623726Y7976D01*
X623716Y7936D01*
X623711Y7891D01*
Y7851D01*
X623706Y7806D01*
X623711Y7761D01*
Y7721D01*
X623716Y7676D01*
X623726Y7636D01*
X623731Y7596D01*
X623746Y7551D01*
X623756Y7511D01*
X623771Y7471D01*
X623791Y7431D01*
X623806Y7396D01*
X623826Y7356D01*
X623926Y7216D01*
X623956Y7186D01*
Y3756D01*
X623966Y3631D01*
X624006Y3506D01*
X624066Y3396D01*
X624146Y3296D01*
X624246Y3216D01*
X624356Y3156D01*
X624481Y3116D01*
X624606Y3106D01*
G37*
G36*
G01X619882D02*
X620007Y3116D01*
X620132Y3156D01*
X620242Y3216D01*
X620342Y3296D01*
X620422Y3396D01*
X620482Y3506D01*
X620522Y3631D01*
X620532Y3756D01*
Y7186D01*
X620562Y7216D01*
X620662Y7356D01*
X620682Y7396D01*
X620697Y7431D01*
X620717Y7471D01*
X620732Y7511D01*
X620742Y7551D01*
X620757Y7596D01*
X620762Y7636D01*
X620772Y7676D01*
X620777Y7721D01*
Y7761D01*
X620782Y7806D01*
X620777Y7851D01*
Y7891D01*
X620772Y7936D01*
X620762Y7976D01*
X620757Y8016D01*
X620742Y8061D01*
X620732Y8101D01*
X620717Y8141D01*
X620697Y8181D01*
X620682Y8216D01*
X620662Y8256D01*
X620562Y8396D01*
X620532Y8426D01*
Y9556D01*
X620522Y9681D01*
X620482Y9806D01*
X620422Y9916D01*
X620342Y10016D01*
X620242Y10096D01*
X620132Y10156D01*
X620007Y10196D01*
X619882Y10206D01*
X619757Y10196D01*
X619632Y10156D01*
X619522Y10096D01*
X619422Y10016D01*
X619342Y9916D01*
X619282Y9806D01*
X619242Y9681D01*
X619232Y9556D01*
Y8426D01*
X619202Y8396D01*
X619102Y8256D01*
X619082Y8216D01*
X619067Y8181D01*
X619047Y8141D01*
X619032Y8101D01*
X619022Y8061D01*
X619007Y8016D01*
X619002Y7976D01*
X618992Y7936D01*
X618987Y7891D01*
Y7851D01*
X618982Y7806D01*
X618987Y7761D01*
Y7721D01*
X618992Y7676D01*
X619002Y7636D01*
X619007Y7596D01*
X619022Y7551D01*
X619032Y7511D01*
X619047Y7471D01*
X619067Y7431D01*
X619082Y7396D01*
X619102Y7356D01*
X619202Y7216D01*
X619232Y7186D01*
Y3756D01*
X619242Y3631D01*
X619282Y3506D01*
X619342Y3396D01*
X619422Y3296D01*
X619522Y3216D01*
X619632Y3156D01*
X619757Y3116D01*
X619882Y3106D01*
G37*
G36*
G01X648228D02*
X648353Y3116D01*
X648478Y3156D01*
X648588Y3216D01*
X648688Y3296D01*
X648768Y3396D01*
X648828Y3506D01*
X648868Y3631D01*
X648878Y3756D01*
Y7186D01*
X648908Y7216D01*
X649008Y7356D01*
X649028Y7396D01*
X649043Y7431D01*
X649063Y7471D01*
X649078Y7511D01*
X649088Y7551D01*
X649103Y7596D01*
X649108Y7636D01*
X649118Y7676D01*
X649123Y7721D01*
Y7761D01*
X649128Y7806D01*
X649123Y7851D01*
Y7891D01*
X649118Y7936D01*
X649108Y7976D01*
X649103Y8016D01*
X649088Y8061D01*
X649078Y8101D01*
X649063Y8141D01*
X649043Y8181D01*
X649028Y8216D01*
X649008Y8256D01*
X648908Y8396D01*
X648878Y8426D01*
Y9556D01*
X648868Y9681D01*
X648828Y9806D01*
X648768Y9916D01*
X648688Y10016D01*
X648588Y10096D01*
X648478Y10156D01*
X648353Y10196D01*
X648228Y10206D01*
X648103Y10196D01*
X647978Y10156D01*
X647868Y10096D01*
X647768Y10016D01*
X647688Y9916D01*
X647628Y9806D01*
X647588Y9681D01*
X647578Y9556D01*
Y8426D01*
X647548Y8396D01*
X647448Y8256D01*
X647428Y8216D01*
X647413Y8181D01*
X647393Y8141D01*
X647378Y8101D01*
X647368Y8061D01*
X647353Y8016D01*
X647348Y7976D01*
X647338Y7936D01*
X647333Y7891D01*
Y7851D01*
X647328Y7806D01*
X647333Y7761D01*
Y7721D01*
X647338Y7676D01*
X647348Y7636D01*
X647353Y7596D01*
X647368Y7551D01*
X647378Y7511D01*
X647393Y7471D01*
X647413Y7431D01*
X647428Y7396D01*
X647448Y7356D01*
X647548Y7216D01*
X647578Y7186D01*
Y3756D01*
X647588Y3631D01*
X647628Y3506D01*
X647688Y3396D01*
X647768Y3296D01*
X647868Y3216D01*
X647978Y3156D01*
X648103Y3116D01*
X648228Y3106D01*
G37*
G36*
G01X643504D02*
X643629Y3116D01*
X643754Y3156D01*
X643864Y3216D01*
X643964Y3296D01*
X644044Y3396D01*
X644104Y3506D01*
X644144Y3631D01*
X644154Y3756D01*
Y7186D01*
X644184Y7216D01*
X644284Y7356D01*
X644304Y7396D01*
X644319Y7431D01*
X644339Y7471D01*
X644354Y7511D01*
X644364Y7551D01*
X644379Y7596D01*
X644384Y7636D01*
X644394Y7676D01*
X644399Y7721D01*
Y7761D01*
X644404Y7806D01*
X644399Y7851D01*
Y7891D01*
X644394Y7936D01*
X644384Y7976D01*
X644379Y8016D01*
X644364Y8061D01*
X644354Y8101D01*
X644339Y8141D01*
X644319Y8181D01*
X644304Y8216D01*
X644284Y8256D01*
X644184Y8396D01*
X644154Y8426D01*
Y9556D01*
X644144Y9681D01*
X644104Y9806D01*
X644044Y9916D01*
X643964Y10016D01*
X643864Y10096D01*
X643754Y10156D01*
X643629Y10196D01*
X643504Y10206D01*
X643379Y10196D01*
X643254Y10156D01*
X643144Y10096D01*
X643044Y10016D01*
X642964Y9916D01*
X642904Y9806D01*
X642864Y9681D01*
X642854Y9556D01*
Y8426D01*
X642824Y8396D01*
X642724Y8256D01*
X642704Y8216D01*
X642689Y8181D01*
X642669Y8141D01*
X642654Y8101D01*
X642644Y8061D01*
X642629Y8016D01*
X642624Y7976D01*
X642614Y7936D01*
X642609Y7891D01*
Y7851D01*
X642604Y7806D01*
X642609Y7761D01*
Y7721D01*
X642614Y7676D01*
X642624Y7636D01*
X642629Y7596D01*
X642644Y7551D01*
X642654Y7511D01*
X642669Y7471D01*
X642689Y7431D01*
X642704Y7396D01*
X642724Y7356D01*
X642824Y7216D01*
X642854Y7186D01*
Y3756D01*
X642864Y3631D01*
X642904Y3506D01*
X642964Y3396D01*
X643044Y3296D01*
X643144Y3216D01*
X643254Y3156D01*
X643379Y3116D01*
X643504Y3106D01*
G37*
G36*
G01X638779D02*
X638904Y3116D01*
X639029Y3156D01*
X639139Y3216D01*
X639239Y3296D01*
X639319Y3396D01*
X639379Y3506D01*
X639419Y3631D01*
X639429Y3756D01*
Y7186D01*
X639459Y7216D01*
X639559Y7356D01*
X639579Y7396D01*
X639594Y7431D01*
X639614Y7471D01*
X639629Y7511D01*
X639639Y7551D01*
X639654Y7596D01*
X639659Y7636D01*
X639669Y7676D01*
X639674Y7721D01*
Y7761D01*
X639679Y7806D01*
X639674Y7851D01*
Y7891D01*
X639669Y7936D01*
X639659Y7976D01*
X639654Y8016D01*
X639639Y8061D01*
X639629Y8101D01*
X639614Y8141D01*
X639594Y8181D01*
X639579Y8216D01*
X639559Y8256D01*
X639459Y8396D01*
X639429Y8426D01*
Y9556D01*
X639419Y9681D01*
X639379Y9806D01*
X639319Y9916D01*
X639239Y10016D01*
X639139Y10096D01*
X639029Y10156D01*
X638904Y10196D01*
X638779Y10206D01*
X638654Y10196D01*
X638529Y10156D01*
X638419Y10096D01*
X638319Y10016D01*
X638239Y9916D01*
X638179Y9806D01*
X638139Y9681D01*
X638129Y9556D01*
Y8426D01*
X638099Y8396D01*
X637999Y8256D01*
X637979Y8216D01*
X637964Y8181D01*
X637944Y8141D01*
X637929Y8101D01*
X637919Y8061D01*
X637904Y8016D01*
X637899Y7976D01*
X637889Y7936D01*
X637884Y7891D01*
Y7851D01*
X637879Y7806D01*
X637884Y7761D01*
Y7721D01*
X637889Y7676D01*
X637899Y7636D01*
X637904Y7596D01*
X637919Y7551D01*
X637929Y7511D01*
X637944Y7471D01*
X637964Y7431D01*
X637979Y7396D01*
X637999Y7356D01*
X638099Y7216D01*
X638129Y7186D01*
Y3756D01*
X638139Y3631D01*
X638179Y3506D01*
X638239Y3396D01*
X638319Y3296D01*
X638419Y3216D01*
X638529Y3156D01*
X638654Y3116D01*
X638779Y3106D01*
G37*
G36*
G01X662401D02*
X662526Y3116D01*
X662651Y3156D01*
X662761Y3216D01*
X662861Y3296D01*
X662941Y3396D01*
X663001Y3506D01*
X663041Y3631D01*
X663051Y3756D01*
Y7186D01*
X663081Y7216D01*
X663181Y7356D01*
X663201Y7396D01*
X663216Y7431D01*
X663236Y7471D01*
X663251Y7511D01*
X663261Y7551D01*
X663276Y7596D01*
X663281Y7636D01*
X663291Y7676D01*
X663296Y7721D01*
Y7761D01*
X663301Y7806D01*
X663296Y7851D01*
Y7891D01*
X663291Y7936D01*
X663281Y7976D01*
X663276Y8016D01*
X663261Y8061D01*
X663251Y8101D01*
X663236Y8141D01*
X663216Y8181D01*
X663201Y8216D01*
X663181Y8256D01*
X663081Y8396D01*
X663051Y8426D01*
Y9556D01*
X663041Y9681D01*
X663001Y9806D01*
X662941Y9916D01*
X662861Y10016D01*
X662761Y10096D01*
X662651Y10156D01*
X662526Y10196D01*
X662401Y10206D01*
X662276Y10196D01*
X662151Y10156D01*
X662041Y10096D01*
X661941Y10016D01*
X661861Y9916D01*
X661801Y9806D01*
X661761Y9681D01*
X661751Y9556D01*
Y8426D01*
X661721Y8396D01*
X661621Y8256D01*
X661601Y8216D01*
X661586Y8181D01*
X661566Y8141D01*
X661551Y8101D01*
X661541Y8061D01*
X661526Y8016D01*
X661521Y7976D01*
X661511Y7936D01*
X661506Y7891D01*
Y7851D01*
X661501Y7806D01*
X661506Y7761D01*
Y7721D01*
X661511Y7676D01*
X661521Y7636D01*
X661526Y7596D01*
X661541Y7551D01*
X661551Y7511D01*
X661566Y7471D01*
X661586Y7431D01*
X661601Y7396D01*
X661621Y7356D01*
X661721Y7216D01*
X661751Y7186D01*
Y3756D01*
X661761Y3631D01*
X661801Y3506D01*
X661861Y3396D01*
X661941Y3296D01*
X662041Y3216D01*
X662151Y3156D01*
X662276Y3116D01*
X662401Y3106D01*
G37*
G36*
G01X657677D02*
X657802Y3116D01*
X657927Y3156D01*
X658037Y3216D01*
X658137Y3296D01*
X658217Y3396D01*
X658277Y3506D01*
X658317Y3631D01*
X658327Y3756D01*
Y7186D01*
X658357Y7216D01*
X658457Y7356D01*
X658477Y7396D01*
X658492Y7431D01*
X658512Y7471D01*
X658527Y7511D01*
X658537Y7551D01*
X658552Y7596D01*
X658557Y7636D01*
X658567Y7676D01*
X658572Y7721D01*
Y7761D01*
X658577Y7806D01*
X658572Y7851D01*
Y7891D01*
X658567Y7936D01*
X658557Y7976D01*
X658552Y8016D01*
X658537Y8061D01*
X658527Y8101D01*
X658512Y8141D01*
X658492Y8181D01*
X658477Y8216D01*
X658457Y8256D01*
X658357Y8396D01*
X658327Y8426D01*
Y9556D01*
X658317Y9681D01*
X658277Y9806D01*
X658217Y9916D01*
X658137Y10016D01*
X658037Y10096D01*
X657927Y10156D01*
X657802Y10196D01*
X657677Y10206D01*
X657552Y10196D01*
X657427Y10156D01*
X657317Y10096D01*
X657217Y10016D01*
X657137Y9916D01*
X657077Y9806D01*
X657037Y9681D01*
X657027Y9556D01*
Y8426D01*
X656997Y8396D01*
X656897Y8256D01*
X656877Y8216D01*
X656862Y8181D01*
X656842Y8141D01*
X656827Y8101D01*
X656817Y8061D01*
X656802Y8016D01*
X656797Y7976D01*
X656787Y7936D01*
X656782Y7891D01*
Y7851D01*
X656777Y7806D01*
X656782Y7761D01*
Y7721D01*
X656787Y7676D01*
X656797Y7636D01*
X656802Y7596D01*
X656817Y7551D01*
X656827Y7511D01*
X656842Y7471D01*
X656862Y7431D01*
X656877Y7396D01*
X656897Y7356D01*
X656997Y7216D01*
X657027Y7186D01*
Y3756D01*
X657037Y3631D01*
X657077Y3506D01*
X657137Y3396D01*
X657217Y3296D01*
X657317Y3216D01*
X657427Y3156D01*
X657552Y3116D01*
X657677Y3106D01*
G37*
G36*
G01X652952D02*
X653077Y3116D01*
X653202Y3156D01*
X653312Y3216D01*
X653412Y3296D01*
X653492Y3396D01*
X653552Y3506D01*
X653592Y3631D01*
X653602Y3756D01*
Y7186D01*
X653632Y7216D01*
X653732Y7356D01*
X653752Y7396D01*
X653767Y7431D01*
X653787Y7471D01*
X653802Y7511D01*
X653812Y7551D01*
X653827Y7596D01*
X653832Y7636D01*
X653842Y7676D01*
X653847Y7721D01*
Y7761D01*
X653852Y7806D01*
X653847Y7851D01*
Y7891D01*
X653842Y7936D01*
X653832Y7976D01*
X653827Y8016D01*
X653812Y8061D01*
X653802Y8101D01*
X653787Y8141D01*
X653767Y8181D01*
X653752Y8216D01*
X653732Y8256D01*
X653632Y8396D01*
X653602Y8426D01*
Y9556D01*
X653592Y9681D01*
X653552Y9806D01*
X653492Y9916D01*
X653412Y10016D01*
X653312Y10096D01*
X653202Y10156D01*
X653077Y10196D01*
X652952Y10206D01*
X652827Y10196D01*
X652702Y10156D01*
X652592Y10096D01*
X652492Y10016D01*
X652412Y9916D01*
X652352Y9806D01*
X652312Y9681D01*
X652302Y9556D01*
Y8426D01*
X652272Y8396D01*
X652172Y8256D01*
X652152Y8216D01*
X652137Y8181D01*
X652117Y8141D01*
X652102Y8101D01*
X652092Y8061D01*
X652077Y8016D01*
X652072Y7976D01*
X652062Y7936D01*
X652057Y7891D01*
Y7851D01*
X652052Y7806D01*
X652057Y7761D01*
Y7721D01*
X652062Y7676D01*
X652072Y7636D01*
X652077Y7596D01*
X652092Y7551D01*
X652102Y7511D01*
X652117Y7471D01*
X652137Y7431D01*
X652152Y7396D01*
X652172Y7356D01*
X652272Y7216D01*
X652302Y7186D01*
Y3756D01*
X652312Y3631D01*
X652352Y3506D01*
X652412Y3396D01*
X652492Y3296D01*
X652592Y3216D01*
X652702Y3156D01*
X652827Y3116D01*
X652952Y3106D01*
G37*
G36*
G01X676575D02*
X676700Y3116D01*
X676825Y3156D01*
X676935Y3216D01*
X677035Y3296D01*
X677115Y3396D01*
X677175Y3506D01*
X677215Y3631D01*
X677225Y3756D01*
Y7186D01*
X677255Y7216D01*
X677355Y7356D01*
X677375Y7396D01*
X677390Y7431D01*
X677410Y7471D01*
X677425Y7511D01*
X677435Y7551D01*
X677450Y7596D01*
X677455Y7636D01*
X677465Y7676D01*
X677470Y7721D01*
Y7761D01*
X677475Y7806D01*
X677470Y7851D01*
Y7891D01*
X677465Y7936D01*
X677455Y7976D01*
X677450Y8016D01*
X677435Y8061D01*
X677425Y8101D01*
X677410Y8141D01*
X677390Y8181D01*
X677375Y8216D01*
X677355Y8256D01*
X677255Y8396D01*
X677225Y8426D01*
Y9556D01*
X677215Y9681D01*
X677175Y9806D01*
X677115Y9916D01*
X677035Y10016D01*
X676935Y10096D01*
X676825Y10156D01*
X676700Y10196D01*
X676575Y10206D01*
X676450Y10196D01*
X676325Y10156D01*
X676215Y10096D01*
X676115Y10016D01*
X676035Y9916D01*
X675975Y9806D01*
X675935Y9681D01*
X675925Y9556D01*
Y8426D01*
X675895Y8396D01*
X675795Y8256D01*
X675775Y8216D01*
X675760Y8181D01*
X675740Y8141D01*
X675725Y8101D01*
X675715Y8061D01*
X675700Y8016D01*
X675695Y7976D01*
X675685Y7936D01*
X675680Y7891D01*
Y7851D01*
X675675Y7806D01*
X675680Y7761D01*
Y7721D01*
X675685Y7676D01*
X675695Y7636D01*
X675700Y7596D01*
X675715Y7551D01*
X675725Y7511D01*
X675740Y7471D01*
X675760Y7431D01*
X675775Y7396D01*
X675795Y7356D01*
X675895Y7216D01*
X675925Y7186D01*
Y3756D01*
X675935Y3631D01*
X675975Y3506D01*
X676035Y3396D01*
X676115Y3296D01*
X676215Y3216D01*
X676325Y3156D01*
X676450Y3116D01*
X676575Y3106D01*
G37*
G36*
G01X671850D02*
X671975Y3116D01*
X672100Y3156D01*
X672210Y3216D01*
X672310Y3296D01*
X672390Y3396D01*
X672450Y3506D01*
X672490Y3631D01*
X672500Y3756D01*
Y7186D01*
X672530Y7216D01*
X672630Y7356D01*
X672650Y7396D01*
X672665Y7431D01*
X672685Y7471D01*
X672700Y7511D01*
X672710Y7551D01*
X672725Y7596D01*
X672730Y7636D01*
X672740Y7676D01*
X672745Y7721D01*
Y7761D01*
X672750Y7806D01*
X672745Y7851D01*
Y7891D01*
X672740Y7936D01*
X672730Y7976D01*
X672725Y8016D01*
X672710Y8061D01*
X672700Y8101D01*
X672685Y8141D01*
X672665Y8181D01*
X672650Y8216D01*
X672630Y8256D01*
X672530Y8396D01*
X672500Y8426D01*
Y9556D01*
X672490Y9681D01*
X672450Y9806D01*
X672390Y9916D01*
X672310Y10016D01*
X672210Y10096D01*
X672100Y10156D01*
X671975Y10196D01*
X671850Y10206D01*
X671725Y10196D01*
X671600Y10156D01*
X671490Y10096D01*
X671390Y10016D01*
X671310Y9916D01*
X671250Y9806D01*
X671210Y9681D01*
X671200Y9556D01*
Y8426D01*
X671170Y8396D01*
X671070Y8256D01*
X671050Y8216D01*
X671035Y8181D01*
X671015Y8141D01*
X671000Y8101D01*
X670990Y8061D01*
X670975Y8016D01*
X670970Y7976D01*
X670960Y7936D01*
X670955Y7891D01*
Y7851D01*
X670950Y7806D01*
X670955Y7761D01*
Y7721D01*
X670960Y7676D01*
X670970Y7636D01*
X670975Y7596D01*
X670990Y7551D01*
X671000Y7511D01*
X671015Y7471D01*
X671035Y7431D01*
X671050Y7396D01*
X671070Y7356D01*
X671170Y7216D01*
X671200Y7186D01*
Y3756D01*
X671210Y3631D01*
X671250Y3506D01*
X671310Y3396D01*
X671390Y3296D01*
X671490Y3216D01*
X671600Y3156D01*
X671725Y3116D01*
X671850Y3106D01*
G37*
G36*
G01X667126D02*
X667251Y3116D01*
X667376Y3156D01*
X667486Y3216D01*
X667586Y3296D01*
X667666Y3396D01*
X667726Y3506D01*
X667766Y3631D01*
X667776Y3756D01*
Y7186D01*
X667806Y7216D01*
X667906Y7356D01*
X667926Y7396D01*
X667941Y7431D01*
X667961Y7471D01*
X667976Y7511D01*
X667986Y7551D01*
X668001Y7596D01*
X668006Y7636D01*
X668016Y7676D01*
X668021Y7721D01*
Y7761D01*
X668026Y7806D01*
X668021Y7851D01*
Y7891D01*
X668016Y7936D01*
X668006Y7976D01*
X668001Y8016D01*
X667986Y8061D01*
X667976Y8101D01*
X667961Y8141D01*
X667941Y8181D01*
X667926Y8216D01*
X667906Y8256D01*
X667806Y8396D01*
X667776Y8426D01*
Y9556D01*
X667766Y9681D01*
X667726Y9806D01*
X667666Y9916D01*
X667586Y10016D01*
X667486Y10096D01*
X667376Y10156D01*
X667251Y10196D01*
X667126Y10206D01*
X667001Y10196D01*
X666876Y10156D01*
X666766Y10096D01*
X666666Y10016D01*
X666586Y9916D01*
X666526Y9806D01*
X666486Y9681D01*
X666476Y9556D01*
Y8426D01*
X666446Y8396D01*
X666346Y8256D01*
X666326Y8216D01*
X666311Y8181D01*
X666291Y8141D01*
X666276Y8101D01*
X666266Y8061D01*
X666251Y8016D01*
X666246Y7976D01*
X666236Y7936D01*
X666231Y7891D01*
Y7851D01*
X666226Y7806D01*
X666231Y7761D01*
Y7721D01*
X666236Y7676D01*
X666246Y7636D01*
X666251Y7596D01*
X666266Y7551D01*
X666276Y7511D01*
X666291Y7471D01*
X666311Y7431D01*
X666326Y7396D01*
X666346Y7356D01*
X666446Y7216D01*
X666476Y7186D01*
Y3756D01*
X666486Y3631D01*
X666526Y3506D01*
X666586Y3396D01*
X666666Y3296D01*
X666766Y3216D01*
X666876Y3156D01*
X667001Y3116D01*
X667126Y3106D01*
G37*
G36*
G01X695472D02*
X695597Y3116D01*
X695722Y3156D01*
X695832Y3216D01*
X695932Y3296D01*
X696012Y3396D01*
X696072Y3506D01*
X696112Y3631D01*
X696122Y3756D01*
Y7186D01*
X696152Y7216D01*
X696252Y7356D01*
X696272Y7396D01*
X696287Y7431D01*
X696307Y7471D01*
X696322Y7511D01*
X696332Y7551D01*
X696347Y7596D01*
X696352Y7636D01*
X696362Y7676D01*
X696367Y7721D01*
Y7761D01*
X696372Y7806D01*
X696367Y7851D01*
Y7891D01*
X696362Y7936D01*
X696352Y7976D01*
X696347Y8016D01*
X696332Y8061D01*
X696322Y8101D01*
X696307Y8141D01*
X696287Y8181D01*
X696272Y8216D01*
X696252Y8256D01*
X696152Y8396D01*
X696122Y8426D01*
Y9556D01*
X696112Y9681D01*
X696072Y9806D01*
X696012Y9916D01*
X695932Y10016D01*
X695832Y10096D01*
X695722Y10156D01*
X695597Y10196D01*
X695472Y10206D01*
X695347Y10196D01*
X695222Y10156D01*
X695112Y10096D01*
X695012Y10016D01*
X694932Y9916D01*
X694872Y9806D01*
X694832Y9681D01*
X694822Y9556D01*
Y8426D01*
X694792Y8396D01*
X694692Y8256D01*
X694672Y8216D01*
X694657Y8181D01*
X694637Y8141D01*
X694622Y8101D01*
X694612Y8061D01*
X694597Y8016D01*
X694592Y7976D01*
X694582Y7936D01*
X694577Y7891D01*
Y7851D01*
X694572Y7806D01*
X694577Y7761D01*
Y7721D01*
X694582Y7676D01*
X694592Y7636D01*
X694597Y7596D01*
X694612Y7551D01*
X694622Y7511D01*
X694637Y7471D01*
X694657Y7431D01*
X694672Y7396D01*
X694692Y7356D01*
X694792Y7216D01*
X694822Y7186D01*
Y3756D01*
X694832Y3631D01*
X694872Y3506D01*
X694932Y3396D01*
X695012Y3296D01*
X695112Y3216D01*
X695222Y3156D01*
X695347Y3116D01*
X695472Y3106D01*
G37*
G36*
G01X690748D02*
X690873Y3116D01*
X690998Y3156D01*
X691108Y3216D01*
X691208Y3296D01*
X691288Y3396D01*
X691348Y3506D01*
X691388Y3631D01*
X691398Y3756D01*
Y7186D01*
X691428Y7216D01*
X691528Y7356D01*
X691548Y7396D01*
X691563Y7431D01*
X691583Y7471D01*
X691598Y7511D01*
X691608Y7551D01*
X691623Y7596D01*
X691628Y7636D01*
X691638Y7676D01*
X691643Y7721D01*
Y7761D01*
X691648Y7806D01*
X691643Y7851D01*
Y7891D01*
X691638Y7936D01*
X691628Y7976D01*
X691623Y8016D01*
X691608Y8061D01*
X691598Y8101D01*
X691583Y8141D01*
X691563Y8181D01*
X691548Y8216D01*
X691528Y8256D01*
X691428Y8396D01*
X691398Y8426D01*
Y9556D01*
X691388Y9681D01*
X691348Y9806D01*
X691288Y9916D01*
X691208Y10016D01*
X691108Y10096D01*
X690998Y10156D01*
X690873Y10196D01*
X690748Y10206D01*
X690623Y10196D01*
X690498Y10156D01*
X690388Y10096D01*
X690288Y10016D01*
X690208Y9916D01*
X690148Y9806D01*
X690108Y9681D01*
X690098Y9556D01*
Y8426D01*
X690068Y8396D01*
X689968Y8256D01*
X689948Y8216D01*
X689933Y8181D01*
X689913Y8141D01*
X689898Y8101D01*
X689888Y8061D01*
X689873Y8016D01*
X689868Y7976D01*
X689858Y7936D01*
X689853Y7891D01*
Y7851D01*
X689848Y7806D01*
X689853Y7761D01*
Y7721D01*
X689858Y7676D01*
X689868Y7636D01*
X689873Y7596D01*
X689888Y7551D01*
X689898Y7511D01*
X689913Y7471D01*
X689933Y7431D01*
X689948Y7396D01*
X689968Y7356D01*
X690068Y7216D01*
X690098Y7186D01*
Y3756D01*
X690108Y3631D01*
X690148Y3506D01*
X690208Y3396D01*
X690288Y3296D01*
X690388Y3216D01*
X690498Y3156D01*
X690623Y3116D01*
X690748Y3106D01*
G37*
G36*
G01X686023D02*
X686148Y3116D01*
X686273Y3156D01*
X686383Y3216D01*
X686483Y3296D01*
X686563Y3396D01*
X686623Y3506D01*
X686663Y3631D01*
X686673Y3756D01*
Y7186D01*
X686703Y7216D01*
X686803Y7356D01*
X686823Y7396D01*
X686838Y7431D01*
X686858Y7471D01*
X686873Y7511D01*
X686883Y7551D01*
X686898Y7596D01*
X686903Y7636D01*
X686913Y7676D01*
X686918Y7721D01*
Y7761D01*
X686923Y7806D01*
X686918Y7851D01*
Y7891D01*
X686913Y7936D01*
X686903Y7976D01*
X686898Y8016D01*
X686883Y8061D01*
X686873Y8101D01*
X686858Y8141D01*
X686838Y8181D01*
X686823Y8216D01*
X686803Y8256D01*
X686703Y8396D01*
X686673Y8426D01*
Y9556D01*
X686663Y9681D01*
X686623Y9806D01*
X686563Y9916D01*
X686483Y10016D01*
X686383Y10096D01*
X686273Y10156D01*
X686148Y10196D01*
X686023Y10206D01*
X685898Y10196D01*
X685773Y10156D01*
X685663Y10096D01*
X685563Y10016D01*
X685483Y9916D01*
X685423Y9806D01*
X685383Y9681D01*
X685373Y9556D01*
Y8426D01*
X685343Y8396D01*
X685243Y8256D01*
X685223Y8216D01*
X685208Y8181D01*
X685188Y8141D01*
X685173Y8101D01*
X685163Y8061D01*
X685148Y8016D01*
X685143Y7976D01*
X685133Y7936D01*
X685128Y7891D01*
Y7851D01*
X685123Y7806D01*
X685128Y7761D01*
Y7721D01*
X685133Y7676D01*
X685143Y7636D01*
X685148Y7596D01*
X685163Y7551D01*
X685173Y7511D01*
X685188Y7471D01*
X685208Y7431D01*
X685223Y7396D01*
X685243Y7356D01*
X685343Y7216D01*
X685373Y7186D01*
Y3756D01*
X685383Y3631D01*
X685423Y3506D01*
X685483Y3396D01*
X685563Y3296D01*
X685663Y3216D01*
X685773Y3156D01*
X685898Y3116D01*
X686023Y3106D01*
G37*
G36*
G01X681299D02*
X681424Y3116D01*
X681549Y3156D01*
X681659Y3216D01*
X681759Y3296D01*
X681839Y3396D01*
X681899Y3506D01*
X681939Y3631D01*
X681949Y3756D01*
Y7186D01*
X681979Y7216D01*
X682079Y7356D01*
X682099Y7396D01*
X682114Y7431D01*
X682134Y7471D01*
X682149Y7511D01*
X682159Y7551D01*
X682174Y7596D01*
X682179Y7636D01*
X682189Y7676D01*
X682194Y7721D01*
Y7761D01*
X682199Y7806D01*
X682194Y7851D01*
Y7891D01*
X682189Y7936D01*
X682179Y7976D01*
X682174Y8016D01*
X682159Y8061D01*
X682149Y8101D01*
X682134Y8141D01*
X682114Y8181D01*
X682099Y8216D01*
X682079Y8256D01*
X681979Y8396D01*
X681949Y8426D01*
Y9556D01*
X681939Y9681D01*
X681899Y9806D01*
X681839Y9916D01*
X681759Y10016D01*
X681659Y10096D01*
X681549Y10156D01*
X681424Y10196D01*
X681299Y10206D01*
X681174Y10196D01*
X681049Y10156D01*
X680939Y10096D01*
X680839Y10016D01*
X680759Y9916D01*
X680699Y9806D01*
X680659Y9681D01*
X680649Y9556D01*
Y8426D01*
X680619Y8396D01*
X680519Y8256D01*
X680499Y8216D01*
X680484Y8181D01*
X680464Y8141D01*
X680449Y8101D01*
X680439Y8061D01*
X680424Y8016D01*
X680419Y7976D01*
X680409Y7936D01*
X680404Y7891D01*
Y7851D01*
X680399Y7806D01*
X680404Y7761D01*
Y7721D01*
X680409Y7676D01*
X680419Y7636D01*
X680424Y7596D01*
X680439Y7551D01*
X680449Y7511D01*
X680464Y7471D01*
X680484Y7431D01*
X680499Y7396D01*
X680519Y7356D01*
X680619Y7216D01*
X680649Y7186D01*
Y3756D01*
X680659Y3631D01*
X680699Y3506D01*
X680759Y3396D01*
X680839Y3296D01*
X680939Y3216D01*
X681049Y3156D01*
X681174Y3116D01*
X681299Y3106D01*
G37*
G36*
G01X709645D02*
X709770Y3116D01*
X709895Y3156D01*
X710005Y3216D01*
X710105Y3296D01*
X710185Y3396D01*
X710245Y3506D01*
X710285Y3631D01*
X710295Y3756D01*
Y7186D01*
X710325Y7216D01*
X710425Y7356D01*
X710445Y7396D01*
X710460Y7431D01*
X710480Y7471D01*
X710495Y7511D01*
X710505Y7551D01*
X710520Y7596D01*
X710525Y7636D01*
X710535Y7676D01*
X710540Y7721D01*
Y7761D01*
X710545Y7806D01*
X710540Y7851D01*
Y7891D01*
X710535Y7936D01*
X710525Y7976D01*
X710520Y8016D01*
X710505Y8061D01*
X710495Y8101D01*
X710480Y8141D01*
X710460Y8181D01*
X710445Y8216D01*
X710425Y8256D01*
X710325Y8396D01*
X710295Y8426D01*
Y9556D01*
X710285Y9681D01*
X710245Y9806D01*
X710185Y9916D01*
X710105Y10016D01*
X710005Y10096D01*
X709895Y10156D01*
X709770Y10196D01*
X709645Y10206D01*
X709520Y10196D01*
X709395Y10156D01*
X709285Y10096D01*
X709185Y10016D01*
X709105Y9916D01*
X709045Y9806D01*
X709005Y9681D01*
X708995Y9556D01*
Y8426D01*
X708965Y8396D01*
X708865Y8256D01*
X708845Y8216D01*
X708830Y8181D01*
X708810Y8141D01*
X708795Y8101D01*
X708785Y8061D01*
X708770Y8016D01*
X708765Y7976D01*
X708755Y7936D01*
X708750Y7891D01*
Y7851D01*
X708745Y7806D01*
X708750Y7761D01*
Y7721D01*
X708755Y7676D01*
X708765Y7636D01*
X708770Y7596D01*
X708785Y7551D01*
X708795Y7511D01*
X708810Y7471D01*
X708830Y7431D01*
X708845Y7396D01*
X708865Y7356D01*
X708965Y7216D01*
X708995Y7186D01*
Y3756D01*
X709005Y3631D01*
X709045Y3506D01*
X709105Y3396D01*
X709185Y3296D01*
X709285Y3216D01*
X709395Y3156D01*
X709520Y3116D01*
X709645Y3106D01*
G37*
G36*
G01X704921D02*
X705046Y3116D01*
X705171Y3156D01*
X705281Y3216D01*
X705381Y3296D01*
X705461Y3396D01*
X705521Y3506D01*
X705561Y3631D01*
X705571Y3756D01*
Y7186D01*
X705601Y7216D01*
X705701Y7356D01*
X705721Y7396D01*
X705736Y7431D01*
X705756Y7471D01*
X705771Y7511D01*
X705781Y7551D01*
X705796Y7596D01*
X705801Y7636D01*
X705811Y7676D01*
X705816Y7721D01*
Y7761D01*
X705821Y7806D01*
X705816Y7851D01*
Y7891D01*
X705811Y7936D01*
X705801Y7976D01*
X705796Y8016D01*
X705781Y8061D01*
X705771Y8101D01*
X705756Y8141D01*
X705736Y8181D01*
X705721Y8216D01*
X705701Y8256D01*
X705601Y8396D01*
X705571Y8426D01*
Y9556D01*
X705561Y9681D01*
X705521Y9806D01*
X705461Y9916D01*
X705381Y10016D01*
X705281Y10096D01*
X705171Y10156D01*
X705046Y10196D01*
X704921Y10206D01*
X704796Y10196D01*
X704671Y10156D01*
X704561Y10096D01*
X704461Y10016D01*
X704381Y9916D01*
X704321Y9806D01*
X704281Y9681D01*
X704271Y9556D01*
Y8426D01*
X704241Y8396D01*
X704141Y8256D01*
X704121Y8216D01*
X704106Y8181D01*
X704086Y8141D01*
X704071Y8101D01*
X704061Y8061D01*
X704046Y8016D01*
X704041Y7976D01*
X704031Y7936D01*
X704026Y7891D01*
Y7851D01*
X704021Y7806D01*
X704026Y7761D01*
Y7721D01*
X704031Y7676D01*
X704041Y7636D01*
X704046Y7596D01*
X704061Y7551D01*
X704071Y7511D01*
X704086Y7471D01*
X704106Y7431D01*
X704121Y7396D01*
X704141Y7356D01*
X704241Y7216D01*
X704271Y7186D01*
Y3756D01*
X704281Y3631D01*
X704321Y3506D01*
X704381Y3396D01*
X704461Y3296D01*
X704561Y3216D01*
X704671Y3156D01*
X704796Y3116D01*
X704921Y3106D01*
G37*
G36*
G01X700197D02*
X700322Y3116D01*
X700447Y3156D01*
X700557Y3216D01*
X700657Y3296D01*
X700737Y3396D01*
X700797Y3506D01*
X700837Y3631D01*
X700847Y3756D01*
Y7186D01*
X700877Y7216D01*
X700977Y7356D01*
X700997Y7396D01*
X701012Y7431D01*
X701032Y7471D01*
X701047Y7511D01*
X701057Y7551D01*
X701072Y7596D01*
X701077Y7636D01*
X701087Y7676D01*
X701092Y7721D01*
Y7761D01*
X701097Y7806D01*
X701092Y7851D01*
Y7891D01*
X701087Y7936D01*
X701077Y7976D01*
X701072Y8016D01*
X701057Y8061D01*
X701047Y8101D01*
X701032Y8141D01*
X701012Y8181D01*
X700997Y8216D01*
X700977Y8256D01*
X700877Y8396D01*
X700847Y8426D01*
Y9556D01*
X700837Y9681D01*
X700797Y9806D01*
X700737Y9916D01*
X700657Y10016D01*
X700557Y10096D01*
X700447Y10156D01*
X700322Y10196D01*
X700197Y10206D01*
X700072Y10196D01*
X699947Y10156D01*
X699837Y10096D01*
X699737Y10016D01*
X699657Y9916D01*
X699597Y9806D01*
X699557Y9681D01*
X699547Y9556D01*
Y8426D01*
X699517Y8396D01*
X699417Y8256D01*
X699397Y8216D01*
X699382Y8181D01*
X699362Y8141D01*
X699347Y8101D01*
X699337Y8061D01*
X699322Y8016D01*
X699317Y7976D01*
X699307Y7936D01*
X699302Y7891D01*
Y7851D01*
X699297Y7806D01*
X699302Y7761D01*
Y7721D01*
X699307Y7676D01*
X699317Y7636D01*
X699322Y7596D01*
X699337Y7551D01*
X699347Y7511D01*
X699362Y7471D01*
X699382Y7431D01*
X699397Y7396D01*
X699417Y7356D01*
X699517Y7216D01*
X699547Y7186D01*
Y3756D01*
X699557Y3631D01*
X699597Y3506D01*
X699657Y3396D01*
X699737Y3296D01*
X699837Y3216D01*
X699947Y3156D01*
X700072Y3116D01*
X700197Y3106D01*
G37*
G36*
G01X723819D02*
X723944Y3116D01*
X724069Y3156D01*
X724179Y3216D01*
X724279Y3296D01*
X724359Y3396D01*
X724419Y3506D01*
X724459Y3631D01*
X724469Y3756D01*
Y7186D01*
X724499Y7216D01*
X724599Y7356D01*
X724619Y7396D01*
X724634Y7431D01*
X724654Y7471D01*
X724669Y7511D01*
X724679Y7551D01*
X724694Y7596D01*
X724699Y7636D01*
X724709Y7676D01*
X724714Y7721D01*
Y7761D01*
X724719Y7806D01*
X724714Y7851D01*
Y7891D01*
X724709Y7936D01*
X724699Y7976D01*
X724694Y8016D01*
X724679Y8061D01*
X724669Y8101D01*
X724654Y8141D01*
X724634Y8181D01*
X724619Y8216D01*
X724599Y8256D01*
X724499Y8396D01*
X724469Y8426D01*
Y9556D01*
X724459Y9681D01*
X724419Y9806D01*
X724359Y9916D01*
X724279Y10016D01*
X724179Y10096D01*
X724069Y10156D01*
X723944Y10196D01*
X723819Y10206D01*
X723694Y10196D01*
X723569Y10156D01*
X723459Y10096D01*
X723359Y10016D01*
X723279Y9916D01*
X723219Y9806D01*
X723179Y9681D01*
X723169Y9556D01*
Y8426D01*
X723139Y8396D01*
X723039Y8256D01*
X723019Y8216D01*
X723004Y8181D01*
X722984Y8141D01*
X722969Y8101D01*
X722959Y8061D01*
X722944Y8016D01*
X722939Y7976D01*
X722929Y7936D01*
X722924Y7891D01*
Y7851D01*
X722919Y7806D01*
X722924Y7761D01*
Y7721D01*
X722929Y7676D01*
X722939Y7636D01*
X722944Y7596D01*
X722959Y7551D01*
X722969Y7511D01*
X722984Y7471D01*
X723004Y7431D01*
X723019Y7396D01*
X723039Y7356D01*
X723139Y7216D01*
X723169Y7186D01*
Y3756D01*
X723179Y3631D01*
X723219Y3506D01*
X723279Y3396D01*
X723359Y3296D01*
X723459Y3216D01*
X723569Y3156D01*
X723694Y3116D01*
X723819Y3106D01*
G37*
G36*
G01X719094D02*
X719219Y3116D01*
X719344Y3156D01*
X719454Y3216D01*
X719554Y3296D01*
X719634Y3396D01*
X719694Y3506D01*
X719734Y3631D01*
X719744Y3756D01*
Y7186D01*
X719774Y7216D01*
X719874Y7356D01*
X719894Y7396D01*
X719909Y7431D01*
X719929Y7471D01*
X719944Y7511D01*
X719954Y7551D01*
X719969Y7596D01*
X719974Y7636D01*
X719984Y7676D01*
X719989Y7721D01*
Y7761D01*
X719994Y7806D01*
X719989Y7851D01*
Y7891D01*
X719984Y7936D01*
X719974Y7976D01*
X719969Y8016D01*
X719954Y8061D01*
X719944Y8101D01*
X719929Y8141D01*
X719909Y8181D01*
X719894Y8216D01*
X719874Y8256D01*
X719774Y8396D01*
X719744Y8426D01*
Y9556D01*
X719734Y9681D01*
X719694Y9806D01*
X719634Y9916D01*
X719554Y10016D01*
X719454Y10096D01*
X719344Y10156D01*
X719219Y10196D01*
X719094Y10206D01*
X718969Y10196D01*
X718844Y10156D01*
X718734Y10096D01*
X718634Y10016D01*
X718554Y9916D01*
X718494Y9806D01*
X718454Y9681D01*
X718444Y9556D01*
Y8426D01*
X718414Y8396D01*
X718314Y8256D01*
X718294Y8216D01*
X718279Y8181D01*
X718259Y8141D01*
X718244Y8101D01*
X718234Y8061D01*
X718219Y8016D01*
X718214Y7976D01*
X718204Y7936D01*
X718199Y7891D01*
Y7851D01*
X718194Y7806D01*
X718199Y7761D01*
Y7721D01*
X718204Y7676D01*
X718214Y7636D01*
X718219Y7596D01*
X718234Y7551D01*
X718244Y7511D01*
X718259Y7471D01*
X718279Y7431D01*
X718294Y7396D01*
X718314Y7356D01*
X718414Y7216D01*
X718444Y7186D01*
Y3756D01*
X718454Y3631D01*
X718494Y3506D01*
X718554Y3396D01*
X718634Y3296D01*
X718734Y3216D01*
X718844Y3156D01*
X718969Y3116D01*
X719094Y3106D01*
G37*
G36*
G01X714370D02*
X714495Y3116D01*
X714620Y3156D01*
X714730Y3216D01*
X714830Y3296D01*
X714910Y3396D01*
X714970Y3506D01*
X715010Y3631D01*
X715020Y3756D01*
Y7186D01*
X715050Y7216D01*
X715150Y7356D01*
X715170Y7396D01*
X715185Y7431D01*
X715205Y7471D01*
X715220Y7511D01*
X715230Y7551D01*
X715245Y7596D01*
X715250Y7636D01*
X715260Y7676D01*
X715265Y7721D01*
Y7761D01*
X715270Y7806D01*
X715265Y7851D01*
Y7891D01*
X715260Y7936D01*
X715250Y7976D01*
X715245Y8016D01*
X715230Y8061D01*
X715220Y8101D01*
X715205Y8141D01*
X715185Y8181D01*
X715170Y8216D01*
X715150Y8256D01*
X715050Y8396D01*
X715020Y8426D01*
Y9556D01*
X715010Y9681D01*
X714970Y9806D01*
X714910Y9916D01*
X714830Y10016D01*
X714730Y10096D01*
X714620Y10156D01*
X714495Y10196D01*
X714370Y10206D01*
X714245Y10196D01*
X714120Y10156D01*
X714010Y10096D01*
X713910Y10016D01*
X713830Y9916D01*
X713770Y9806D01*
X713730Y9681D01*
X713720Y9556D01*
Y8426D01*
X713690Y8396D01*
X713590Y8256D01*
X713570Y8216D01*
X713555Y8181D01*
X713535Y8141D01*
X713520Y8101D01*
X713510Y8061D01*
X713495Y8016D01*
X713490Y7976D01*
X713480Y7936D01*
X713475Y7891D01*
Y7851D01*
X713470Y7806D01*
X713475Y7761D01*
Y7721D01*
X713480Y7676D01*
X713490Y7636D01*
X713495Y7596D01*
X713510Y7551D01*
X713520Y7511D01*
X713535Y7471D01*
X713555Y7431D01*
X713570Y7396D01*
X713590Y7356D01*
X713690Y7216D01*
X713720Y7186D01*
Y3756D01*
X713730Y3631D01*
X713770Y3506D01*
X713830Y3396D01*
X713910Y3296D01*
X714010Y3216D01*
X714120Y3156D01*
X714245Y3116D01*
X714370Y3106D01*
G37*
G36*
G01X737992D02*
X738117Y3116D01*
X738242Y3156D01*
X738352Y3216D01*
X738452Y3296D01*
X738532Y3396D01*
X738592Y3506D01*
X738632Y3631D01*
X738642Y3756D01*
Y7186D01*
X738672Y7216D01*
X738772Y7356D01*
X738792Y7396D01*
X738807Y7431D01*
X738827Y7471D01*
X738842Y7511D01*
X738852Y7551D01*
X738867Y7596D01*
X738872Y7636D01*
X738882Y7676D01*
X738887Y7721D01*
Y7761D01*
X738892Y7806D01*
X738887Y7851D01*
Y7891D01*
X738882Y7936D01*
X738872Y7976D01*
X738867Y8016D01*
X738852Y8061D01*
X738842Y8101D01*
X738827Y8141D01*
X738807Y8181D01*
X738792Y8216D01*
X738772Y8256D01*
X738672Y8396D01*
X738642Y8426D01*
Y9556D01*
X738632Y9681D01*
X738592Y9806D01*
X738532Y9916D01*
X738452Y10016D01*
X738352Y10096D01*
X738242Y10156D01*
X738117Y10196D01*
X737992Y10206D01*
X737867Y10196D01*
X737742Y10156D01*
X737632Y10096D01*
X737532Y10016D01*
X737452Y9916D01*
X737392Y9806D01*
X737352Y9681D01*
X737342Y9556D01*
Y8426D01*
X737312Y8396D01*
X737212Y8256D01*
X737192Y8216D01*
X737177Y8181D01*
X737157Y8141D01*
X737142Y8101D01*
X737132Y8061D01*
X737117Y8016D01*
X737112Y7976D01*
X737102Y7936D01*
X737097Y7891D01*
Y7851D01*
X737092Y7806D01*
X737097Y7761D01*
Y7721D01*
X737102Y7676D01*
X737112Y7636D01*
X737117Y7596D01*
X737132Y7551D01*
X737142Y7511D01*
X737157Y7471D01*
X737177Y7431D01*
X737192Y7396D01*
X737212Y7356D01*
X737312Y7216D01*
X737342Y7186D01*
Y3756D01*
X737352Y3631D01*
X737392Y3506D01*
X737452Y3396D01*
X737532Y3296D01*
X737632Y3216D01*
X737742Y3156D01*
X737867Y3116D01*
X737992Y3106D01*
G37*
G36*
G01X733267D02*
X733392Y3116D01*
X733517Y3156D01*
X733627Y3216D01*
X733727Y3296D01*
X733807Y3396D01*
X733867Y3506D01*
X733907Y3631D01*
X733917Y3756D01*
Y7186D01*
X733947Y7216D01*
X734047Y7356D01*
X734067Y7396D01*
X734082Y7431D01*
X734102Y7471D01*
X734117Y7511D01*
X734127Y7551D01*
X734142Y7596D01*
X734147Y7636D01*
X734157Y7676D01*
X734162Y7721D01*
Y7761D01*
X734167Y7806D01*
X734162Y7851D01*
Y7891D01*
X734157Y7936D01*
X734147Y7976D01*
X734142Y8016D01*
X734127Y8061D01*
X734117Y8101D01*
X734102Y8141D01*
X734082Y8181D01*
X734067Y8216D01*
X734047Y8256D01*
X733947Y8396D01*
X733917Y8426D01*
Y9556D01*
X733907Y9681D01*
X733867Y9806D01*
X733807Y9916D01*
X733727Y10016D01*
X733627Y10096D01*
X733517Y10156D01*
X733392Y10196D01*
X733267Y10206D01*
X733142Y10196D01*
X733017Y10156D01*
X732907Y10096D01*
X732807Y10016D01*
X732727Y9916D01*
X732667Y9806D01*
X732627Y9681D01*
X732617Y9556D01*
Y8426D01*
X732587Y8396D01*
X732487Y8256D01*
X732467Y8216D01*
X732452Y8181D01*
X732432Y8141D01*
X732417Y8101D01*
X732407Y8061D01*
X732392Y8016D01*
X732387Y7976D01*
X732377Y7936D01*
X732372Y7891D01*
Y7851D01*
X732367Y7806D01*
X732372Y7761D01*
Y7721D01*
X732377Y7676D01*
X732387Y7636D01*
X732392Y7596D01*
X732407Y7551D01*
X732417Y7511D01*
X732432Y7471D01*
X732452Y7431D01*
X732467Y7396D01*
X732487Y7356D01*
X732587Y7216D01*
X732617Y7186D01*
Y3756D01*
X732627Y3631D01*
X732667Y3506D01*
X732727Y3396D01*
X732807Y3296D01*
X732907Y3216D01*
X733017Y3156D01*
X733142Y3116D01*
X733267Y3106D01*
G37*
G36*
G01X728543D02*
X728668Y3116D01*
X728793Y3156D01*
X728903Y3216D01*
X729003Y3296D01*
X729083Y3396D01*
X729143Y3506D01*
X729183Y3631D01*
X729193Y3756D01*
Y7186D01*
X729223Y7216D01*
X729323Y7356D01*
X729343Y7396D01*
X729358Y7431D01*
X729378Y7471D01*
X729393Y7511D01*
X729403Y7551D01*
X729418Y7596D01*
X729423Y7636D01*
X729433Y7676D01*
X729438Y7721D01*
Y7761D01*
X729443Y7806D01*
X729438Y7851D01*
Y7891D01*
X729433Y7936D01*
X729423Y7976D01*
X729418Y8016D01*
X729403Y8061D01*
X729393Y8101D01*
X729378Y8141D01*
X729358Y8181D01*
X729343Y8216D01*
X729323Y8256D01*
X729223Y8396D01*
X729193Y8426D01*
Y9556D01*
X729183Y9681D01*
X729143Y9806D01*
X729083Y9916D01*
X729003Y10016D01*
X728903Y10096D01*
X728793Y10156D01*
X728668Y10196D01*
X728543Y10206D01*
X728418Y10196D01*
X728293Y10156D01*
X728183Y10096D01*
X728083Y10016D01*
X728003Y9916D01*
X727943Y9806D01*
X727903Y9681D01*
X727893Y9556D01*
Y8426D01*
X727863Y8396D01*
X727763Y8256D01*
X727743Y8216D01*
X727728Y8181D01*
X727708Y8141D01*
X727693Y8101D01*
X727683Y8061D01*
X727668Y8016D01*
X727663Y7976D01*
X727653Y7936D01*
X727648Y7891D01*
Y7851D01*
X727643Y7806D01*
X727648Y7761D01*
Y7721D01*
X727653Y7676D01*
X727663Y7636D01*
X727668Y7596D01*
X727683Y7551D01*
X727693Y7511D01*
X727708Y7471D01*
X727728Y7431D01*
X727743Y7396D01*
X727763Y7356D01*
X727863Y7216D01*
X727893Y7186D01*
Y3756D01*
X727903Y3631D01*
X727943Y3506D01*
X728003Y3396D01*
X728083Y3296D01*
X728183Y3216D01*
X728293Y3156D01*
X728418Y3116D01*
X728543Y3106D01*
G37*
G36*
G01X752165D02*
X752290Y3116D01*
X752415Y3156D01*
X752525Y3216D01*
X752625Y3296D01*
X752705Y3396D01*
X752765Y3506D01*
X752805Y3631D01*
X752815Y3756D01*
Y7186D01*
X752845Y7216D01*
X752945Y7356D01*
X752965Y7396D01*
X752980Y7431D01*
X753000Y7471D01*
X753015Y7511D01*
X753025Y7551D01*
X753040Y7596D01*
X753045Y7636D01*
X753055Y7676D01*
X753060Y7721D01*
Y7761D01*
X753065Y7806D01*
X753060Y7851D01*
Y7891D01*
X753055Y7936D01*
X753045Y7976D01*
X753040Y8016D01*
X753025Y8061D01*
X753015Y8101D01*
X753000Y8141D01*
X752980Y8181D01*
X752965Y8216D01*
X752945Y8256D01*
X752845Y8396D01*
X752815Y8426D01*
Y9556D01*
X752805Y9681D01*
X752765Y9806D01*
X752705Y9916D01*
X752625Y10016D01*
X752525Y10096D01*
X752415Y10156D01*
X752290Y10196D01*
X752165Y10206D01*
X752040Y10196D01*
X751915Y10156D01*
X751805Y10096D01*
X751705Y10016D01*
X751625Y9916D01*
X751565Y9806D01*
X751525Y9681D01*
X751515Y9556D01*
Y8426D01*
X751485Y8396D01*
X751385Y8256D01*
X751365Y8216D01*
X751350Y8181D01*
X751330Y8141D01*
X751315Y8101D01*
X751305Y8061D01*
X751290Y8016D01*
X751285Y7976D01*
X751275Y7936D01*
X751270Y7891D01*
Y7851D01*
X751265Y7806D01*
X751270Y7761D01*
Y7721D01*
X751275Y7676D01*
X751285Y7636D01*
X751290Y7596D01*
X751305Y7551D01*
X751315Y7511D01*
X751330Y7471D01*
X751350Y7431D01*
X751365Y7396D01*
X751385Y7356D01*
X751485Y7216D01*
X751515Y7186D01*
Y3756D01*
X751525Y3631D01*
X751565Y3506D01*
X751625Y3396D01*
X751705Y3296D01*
X751805Y3216D01*
X751915Y3156D01*
X752040Y3116D01*
X752165Y3106D01*
G37*
G36*
G01X747441D02*
X747566Y3116D01*
X747691Y3156D01*
X747801Y3216D01*
X747901Y3296D01*
X747981Y3396D01*
X748041Y3506D01*
X748081Y3631D01*
X748091Y3756D01*
Y7186D01*
X748121Y7216D01*
X748221Y7356D01*
X748241Y7396D01*
X748256Y7431D01*
X748276Y7471D01*
X748291Y7511D01*
X748301Y7551D01*
X748316Y7596D01*
X748321Y7636D01*
X748331Y7676D01*
X748336Y7721D01*
Y7761D01*
X748341Y7806D01*
X748336Y7851D01*
Y7891D01*
X748331Y7936D01*
X748321Y7976D01*
X748316Y8016D01*
X748301Y8061D01*
X748291Y8101D01*
X748276Y8141D01*
X748256Y8181D01*
X748241Y8216D01*
X748221Y8256D01*
X748121Y8396D01*
X748091Y8426D01*
Y9556D01*
X748081Y9681D01*
X748041Y9806D01*
X747981Y9916D01*
X747901Y10016D01*
X747801Y10096D01*
X747691Y10156D01*
X747566Y10196D01*
X747441Y10206D01*
X747316Y10196D01*
X747191Y10156D01*
X747081Y10096D01*
X746981Y10016D01*
X746901Y9916D01*
X746841Y9806D01*
X746801Y9681D01*
X746791Y9556D01*
Y8426D01*
X746761Y8396D01*
X746661Y8256D01*
X746641Y8216D01*
X746626Y8181D01*
X746606Y8141D01*
X746591Y8101D01*
X746581Y8061D01*
X746566Y8016D01*
X746561Y7976D01*
X746551Y7936D01*
X746546Y7891D01*
Y7851D01*
X746541Y7806D01*
X746546Y7761D01*
Y7721D01*
X746551Y7676D01*
X746561Y7636D01*
X746566Y7596D01*
X746581Y7551D01*
X746591Y7511D01*
X746606Y7471D01*
X746626Y7431D01*
X746641Y7396D01*
X746661Y7356D01*
X746761Y7216D01*
X746791Y7186D01*
Y3756D01*
X746801Y3631D01*
X746841Y3506D01*
X746901Y3396D01*
X746981Y3296D01*
X747081Y3216D01*
X747191Y3156D01*
X747316Y3116D01*
X747441Y3106D01*
G37*
G36*
G01X742716D02*
X742841Y3116D01*
X742966Y3156D01*
X743076Y3216D01*
X743176Y3296D01*
X743256Y3396D01*
X743316Y3506D01*
X743356Y3631D01*
X743366Y3756D01*
Y7186D01*
X743396Y7216D01*
X743496Y7356D01*
X743516Y7396D01*
X743531Y7431D01*
X743551Y7471D01*
X743566Y7511D01*
X743576Y7551D01*
X743591Y7596D01*
X743596Y7636D01*
X743606Y7676D01*
X743611Y7721D01*
Y7761D01*
X743616Y7806D01*
X743611Y7851D01*
Y7891D01*
X743606Y7936D01*
X743596Y7976D01*
X743591Y8016D01*
X743576Y8061D01*
X743566Y8101D01*
X743551Y8141D01*
X743531Y8181D01*
X743516Y8216D01*
X743496Y8256D01*
X743396Y8396D01*
X743366Y8426D01*
Y9556D01*
X743356Y9681D01*
X743316Y9806D01*
X743256Y9916D01*
X743176Y10016D01*
X743076Y10096D01*
X742966Y10156D01*
X742841Y10196D01*
X742716Y10206D01*
X742591Y10196D01*
X742466Y10156D01*
X742356Y10096D01*
X742256Y10016D01*
X742176Y9916D01*
X742116Y9806D01*
X742076Y9681D01*
X742066Y9556D01*
Y8426D01*
X742036Y8396D01*
X741936Y8256D01*
X741916Y8216D01*
X741901Y8181D01*
X741881Y8141D01*
X741866Y8101D01*
X741856Y8061D01*
X741841Y8016D01*
X741836Y7976D01*
X741826Y7936D01*
X741821Y7891D01*
Y7851D01*
X741816Y7806D01*
X741821Y7761D01*
Y7721D01*
X741826Y7676D01*
X741836Y7636D01*
X741841Y7596D01*
X741856Y7551D01*
X741866Y7511D01*
X741881Y7471D01*
X741901Y7431D01*
X741916Y7396D01*
X741936Y7356D01*
X742036Y7216D01*
X742066Y7186D01*
Y3756D01*
X742076Y3631D01*
X742116Y3506D01*
X742176Y3396D01*
X742256Y3296D01*
X742356Y3216D01*
X742466Y3156D01*
X742591Y3116D01*
X742716Y3106D01*
G37*
G54D36*
X141500Y167976D03*
Y183024D03*
G54D54*
X318764Y62400D03*
X321323D03*
X323882D03*
Y80886D03*
X321323D03*
X318764D03*
X326441Y62400D03*
X329000D03*
Y80886D03*
X326441D03*
G54D81*
X787215Y261024D03*
X782077D03*
X787215Y270866D03*
X782077D03*
X794969Y134600D03*
X789831D03*
X794969Y129300D03*
X789831D03*
X794969Y124000D03*
X789831D03*
X795069Y152300D03*
X789931D03*
X794969Y139900D03*
X789831D03*
X795069Y157500D03*
X789931D03*
X795069Y162700D03*
X789931D03*
X795069Y167900D03*
X789931D03*
G54D45*
X231760Y48820D03*
Y56180D03*
X226640D03*
Y48820D03*
X229200D03*
X274560Y145320D03*
Y152680D03*
X269440D03*
Y145320D03*
X272000D03*
X438940Y24820D03*
X444060D03*
X438940Y32180D03*
X444060D03*
X441500D03*
G36*
G01X507677Y35390D02*
X507802Y35400D01*
X507927Y35440D01*
X508037Y35500D01*
X508137Y35580D01*
X508217Y35680D01*
X508277Y35790D01*
X508317Y35915D01*
X508327Y36040D01*
Y38165D01*
X508357Y38195D01*
X508382Y38230D01*
X508412Y38265D01*
X508432Y38300D01*
X508457Y38335D01*
X508497Y38415D01*
X508542Y38535D01*
X508552Y38575D01*
X508562Y38620D01*
X508567Y38660D01*
X508577Y38705D01*
Y38875D01*
X508567Y38920D01*
X508562Y38960D01*
X508552Y39005D01*
X508542Y39045D01*
X508497Y39165D01*
X508457Y39245D01*
X508432Y39280D01*
X508412Y39315D01*
X508382Y39350D01*
X508357Y39385D01*
X508327Y39415D01*
Y41840D01*
X508317Y41965D01*
X508277Y42090D01*
X508217Y42200D01*
X508137Y42300D01*
X508037Y42380D01*
X507927Y42440D01*
X507802Y42480D01*
X507677Y42490D01*
X507552Y42480D01*
X507427Y42440D01*
X507317Y42380D01*
X507217Y42300D01*
X507137Y42200D01*
X507077Y42090D01*
X507037Y41965D01*
X507027Y41840D01*
Y39410D01*
X506997Y39380D01*
X506897Y39240D01*
X506877Y39200D01*
X506862Y39165D01*
X506842Y39125D01*
X506827Y39085D01*
X506817Y39045D01*
X506802Y39000D01*
X506797Y38960D01*
X506787Y38920D01*
X506782Y38875D01*
Y38835D01*
X506777Y38790D01*
X506782Y38745D01*
Y38705D01*
X506787Y38660D01*
X506797Y38620D01*
X506802Y38580D01*
X506817Y38535D01*
X506827Y38495D01*
X506842Y38455D01*
X506862Y38415D01*
X506877Y38380D01*
X506897Y38340D01*
X506997Y38200D01*
X507027Y38170D01*
Y36040D01*
X507037Y35915D01*
X507077Y35790D01*
X507137Y35680D01*
X507217Y35580D01*
X507317Y35500D01*
X507427Y35440D01*
X507552Y35400D01*
X507677Y35390D01*
G37*
G36*
G01X521850D02*
X521975Y35400D01*
X522100Y35440D01*
X522210Y35500D01*
X522310Y35580D01*
X522390Y35680D01*
X522450Y35790D01*
X522490Y35915D01*
X522500Y36040D01*
Y38165D01*
X522530Y38195D01*
X522555Y38230D01*
X522585Y38265D01*
X522605Y38300D01*
X522630Y38335D01*
X522670Y38415D01*
X522715Y38535D01*
X522725Y38575D01*
X522735Y38620D01*
X522740Y38660D01*
X522750Y38705D01*
Y38875D01*
X522740Y38920D01*
X522735Y38960D01*
X522725Y39005D01*
X522715Y39045D01*
X522670Y39165D01*
X522630Y39245D01*
X522605Y39280D01*
X522585Y39315D01*
X522555Y39350D01*
X522530Y39385D01*
X522500Y39415D01*
Y41840D01*
X522490Y41965D01*
X522450Y42090D01*
X522390Y42200D01*
X522310Y42300D01*
X522210Y42380D01*
X522100Y42440D01*
X521975Y42480D01*
X521850Y42490D01*
X521725Y42480D01*
X521600Y42440D01*
X521490Y42380D01*
X521390Y42300D01*
X521310Y42200D01*
X521250Y42090D01*
X521210Y41965D01*
X521200Y41840D01*
Y39410D01*
X521170Y39380D01*
X521070Y39240D01*
X521050Y39200D01*
X521035Y39165D01*
X521015Y39125D01*
X521000Y39085D01*
X520990Y39045D01*
X520975Y39000D01*
X520970Y38960D01*
X520960Y38920D01*
X520955Y38875D01*
Y38835D01*
X520950Y38790D01*
X520955Y38745D01*
Y38705D01*
X520960Y38660D01*
X520970Y38620D01*
X520975Y38580D01*
X520990Y38535D01*
X521000Y38495D01*
X521015Y38455D01*
X521035Y38415D01*
X521050Y38380D01*
X521070Y38340D01*
X521170Y38200D01*
X521200Y38170D01*
Y36040D01*
X521210Y35915D01*
X521250Y35790D01*
X521310Y35680D01*
X521390Y35580D01*
X521490Y35500D01*
X521600Y35440D01*
X521725Y35400D01*
X521850Y35390D01*
G37*
G36*
G01X517126D02*
X517251Y35400D01*
X517376Y35440D01*
X517486Y35500D01*
X517586Y35580D01*
X517666Y35680D01*
X517726Y35790D01*
X517766Y35915D01*
X517776Y36040D01*
Y38165D01*
X517806Y38195D01*
X517831Y38230D01*
X517861Y38265D01*
X517881Y38300D01*
X517906Y38335D01*
X517946Y38415D01*
X517991Y38535D01*
X518001Y38575D01*
X518011Y38620D01*
X518016Y38660D01*
X518026Y38705D01*
Y38875D01*
X518016Y38920D01*
X518011Y38960D01*
X518001Y39005D01*
X517991Y39045D01*
X517946Y39165D01*
X517906Y39245D01*
X517881Y39280D01*
X517861Y39315D01*
X517831Y39350D01*
X517806Y39385D01*
X517776Y39415D01*
Y41840D01*
X517766Y41965D01*
X517726Y42090D01*
X517666Y42200D01*
X517586Y42300D01*
X517486Y42380D01*
X517376Y42440D01*
X517251Y42480D01*
X517126Y42490D01*
X517001Y42480D01*
X516876Y42440D01*
X516766Y42380D01*
X516666Y42300D01*
X516586Y42200D01*
X516526Y42090D01*
X516486Y41965D01*
X516476Y41840D01*
Y39410D01*
X516446Y39380D01*
X516346Y39240D01*
X516326Y39200D01*
X516311Y39165D01*
X516291Y39125D01*
X516276Y39085D01*
X516266Y39045D01*
X516251Y39000D01*
X516246Y38960D01*
X516236Y38920D01*
X516231Y38875D01*
Y38835D01*
X516226Y38790D01*
X516231Y38745D01*
Y38705D01*
X516236Y38660D01*
X516246Y38620D01*
X516251Y38580D01*
X516266Y38535D01*
X516276Y38495D01*
X516291Y38455D01*
X516311Y38415D01*
X516326Y38380D01*
X516346Y38340D01*
X516446Y38200D01*
X516476Y38170D01*
Y36040D01*
X516486Y35915D01*
X516526Y35790D01*
X516586Y35680D01*
X516666Y35580D01*
X516766Y35500D01*
X516876Y35440D01*
X517001Y35400D01*
X517126Y35390D01*
G37*
G36*
G01X512401D02*
X512526Y35400D01*
X512651Y35440D01*
X512761Y35500D01*
X512861Y35580D01*
X512941Y35680D01*
X513001Y35790D01*
X513041Y35915D01*
X513051Y36040D01*
Y38165D01*
X513081Y38195D01*
X513106Y38230D01*
X513136Y38265D01*
X513156Y38300D01*
X513181Y38335D01*
X513221Y38415D01*
X513266Y38535D01*
X513276Y38575D01*
X513286Y38620D01*
X513291Y38660D01*
X513301Y38705D01*
Y38875D01*
X513291Y38920D01*
X513286Y38960D01*
X513276Y39005D01*
X513266Y39045D01*
X513221Y39165D01*
X513181Y39245D01*
X513156Y39280D01*
X513136Y39315D01*
X513106Y39350D01*
X513081Y39385D01*
X513051Y39415D01*
Y41840D01*
X513041Y41965D01*
X513001Y42090D01*
X512941Y42200D01*
X512861Y42300D01*
X512761Y42380D01*
X512651Y42440D01*
X512526Y42480D01*
X512401Y42490D01*
X512276Y42480D01*
X512151Y42440D01*
X512041Y42380D01*
X511941Y42300D01*
X511861Y42200D01*
X511801Y42090D01*
X511761Y41965D01*
X511751Y41840D01*
Y39410D01*
X511721Y39380D01*
X511621Y39240D01*
X511601Y39200D01*
X511586Y39165D01*
X511566Y39125D01*
X511551Y39085D01*
X511541Y39045D01*
X511526Y39000D01*
X511521Y38960D01*
X511511Y38920D01*
X511506Y38875D01*
Y38835D01*
X511501Y38790D01*
X511506Y38745D01*
Y38705D01*
X511511Y38660D01*
X511521Y38620D01*
X511526Y38580D01*
X511541Y38535D01*
X511551Y38495D01*
X511566Y38455D01*
X511586Y38415D01*
X511601Y38380D01*
X511621Y38340D01*
X511721Y38200D01*
X511751Y38170D01*
Y36040D01*
X511761Y35915D01*
X511801Y35790D01*
X511861Y35680D01*
X511941Y35580D01*
X512041Y35500D01*
X512151Y35440D01*
X512276Y35400D01*
X512401Y35390D01*
G37*
G36*
G01X540748D02*
X540873Y35400D01*
X540998Y35440D01*
X541108Y35500D01*
X541208Y35580D01*
X541288Y35680D01*
X541348Y35790D01*
X541388Y35915D01*
X541398Y36040D01*
Y38165D01*
X541428Y38195D01*
X541453Y38230D01*
X541483Y38265D01*
X541503Y38300D01*
X541528Y38335D01*
X541568Y38415D01*
X541613Y38535D01*
X541623Y38575D01*
X541633Y38620D01*
X541638Y38660D01*
X541648Y38705D01*
Y38875D01*
X541638Y38920D01*
X541633Y38960D01*
X541623Y39005D01*
X541613Y39045D01*
X541568Y39165D01*
X541528Y39245D01*
X541503Y39280D01*
X541483Y39315D01*
X541453Y39350D01*
X541428Y39385D01*
X541398Y39415D01*
Y41840D01*
X541388Y41965D01*
X541348Y42090D01*
X541288Y42200D01*
X541208Y42300D01*
X541108Y42380D01*
X540998Y42440D01*
X540873Y42480D01*
X540748Y42490D01*
X540623Y42480D01*
X540498Y42440D01*
X540388Y42380D01*
X540288Y42300D01*
X540208Y42200D01*
X540148Y42090D01*
X540108Y41965D01*
X540098Y41840D01*
Y39410D01*
X540068Y39380D01*
X539968Y39240D01*
X539948Y39200D01*
X539933Y39165D01*
X539913Y39125D01*
X539898Y39085D01*
X539888Y39045D01*
X539873Y39000D01*
X539868Y38960D01*
X539858Y38920D01*
X539853Y38875D01*
Y38835D01*
X539848Y38790D01*
X539853Y38745D01*
Y38705D01*
X539858Y38660D01*
X539868Y38620D01*
X539873Y38580D01*
X539888Y38535D01*
X539898Y38495D01*
X539913Y38455D01*
X539933Y38415D01*
X539948Y38380D01*
X539968Y38340D01*
X540068Y38200D01*
X540098Y38170D01*
Y36040D01*
X540108Y35915D01*
X540148Y35790D01*
X540208Y35680D01*
X540288Y35580D01*
X540388Y35500D01*
X540498Y35440D01*
X540623Y35400D01*
X540748Y35390D01*
G37*
G36*
G01X536023D02*
X536148Y35400D01*
X536273Y35440D01*
X536383Y35500D01*
X536483Y35580D01*
X536563Y35680D01*
X536623Y35790D01*
X536663Y35915D01*
X536673Y36040D01*
Y38165D01*
X536703Y38195D01*
X536728Y38230D01*
X536758Y38265D01*
X536778Y38300D01*
X536803Y38335D01*
X536843Y38415D01*
X536888Y38535D01*
X536898Y38575D01*
X536908Y38620D01*
X536913Y38660D01*
X536923Y38705D01*
Y38875D01*
X536913Y38920D01*
X536908Y38960D01*
X536898Y39005D01*
X536888Y39045D01*
X536843Y39165D01*
X536803Y39245D01*
X536778Y39280D01*
X536758Y39315D01*
X536728Y39350D01*
X536703Y39385D01*
X536673Y39415D01*
Y41840D01*
X536663Y41965D01*
X536623Y42090D01*
X536563Y42200D01*
X536483Y42300D01*
X536383Y42380D01*
X536273Y42440D01*
X536148Y42480D01*
X536023Y42490D01*
X535898Y42480D01*
X535773Y42440D01*
X535663Y42380D01*
X535563Y42300D01*
X535483Y42200D01*
X535423Y42090D01*
X535383Y41965D01*
X535373Y41840D01*
Y39410D01*
X535343Y39380D01*
X535243Y39240D01*
X535223Y39200D01*
X535208Y39165D01*
X535188Y39125D01*
X535173Y39085D01*
X535163Y39045D01*
X535148Y39000D01*
X535143Y38960D01*
X535133Y38920D01*
X535128Y38875D01*
Y38835D01*
X535123Y38790D01*
X535128Y38745D01*
Y38705D01*
X535133Y38660D01*
X535143Y38620D01*
X535148Y38580D01*
X535163Y38535D01*
X535173Y38495D01*
X535188Y38455D01*
X535208Y38415D01*
X535223Y38380D01*
X535243Y38340D01*
X535343Y38200D01*
X535373Y38170D01*
Y36040D01*
X535383Y35915D01*
X535423Y35790D01*
X535483Y35680D01*
X535563Y35580D01*
X535663Y35500D01*
X535773Y35440D01*
X535898Y35400D01*
X536023Y35390D01*
G37*
G36*
G01X531299D02*
X531424Y35400D01*
X531549Y35440D01*
X531659Y35500D01*
X531759Y35580D01*
X531839Y35680D01*
X531899Y35790D01*
X531939Y35915D01*
X531949Y36040D01*
Y38165D01*
X531979Y38195D01*
X532004Y38230D01*
X532034Y38265D01*
X532054Y38300D01*
X532079Y38335D01*
X532119Y38415D01*
X532164Y38535D01*
X532174Y38575D01*
X532184Y38620D01*
X532189Y38660D01*
X532199Y38705D01*
Y38875D01*
X532189Y38920D01*
X532184Y38960D01*
X532174Y39005D01*
X532164Y39045D01*
X532119Y39165D01*
X532079Y39245D01*
X532054Y39280D01*
X532034Y39315D01*
X532004Y39350D01*
X531979Y39385D01*
X531949Y39415D01*
Y41840D01*
X531939Y41965D01*
X531899Y42090D01*
X531839Y42200D01*
X531759Y42300D01*
X531659Y42380D01*
X531549Y42440D01*
X531424Y42480D01*
X531299Y42490D01*
X531174Y42480D01*
X531049Y42440D01*
X530939Y42380D01*
X530839Y42300D01*
X530759Y42200D01*
X530699Y42090D01*
X530659Y41965D01*
X530649Y41840D01*
Y39410D01*
X530619Y39380D01*
X530519Y39240D01*
X530499Y39200D01*
X530484Y39165D01*
X530464Y39125D01*
X530449Y39085D01*
X530439Y39045D01*
X530424Y39000D01*
X530419Y38960D01*
X530409Y38920D01*
X530404Y38875D01*
Y38835D01*
X530399Y38790D01*
X530404Y38745D01*
Y38705D01*
X530409Y38660D01*
X530419Y38620D01*
X530424Y38580D01*
X530439Y38535D01*
X530449Y38495D01*
X530464Y38455D01*
X530484Y38415D01*
X530499Y38380D01*
X530519Y38340D01*
X530619Y38200D01*
X530649Y38170D01*
Y36040D01*
X530659Y35915D01*
X530699Y35790D01*
X530759Y35680D01*
X530839Y35580D01*
X530939Y35500D01*
X531049Y35440D01*
X531174Y35400D01*
X531299Y35390D01*
G37*
G36*
G01X526575D02*
X526700Y35400D01*
X526825Y35440D01*
X526935Y35500D01*
X527035Y35580D01*
X527115Y35680D01*
X527175Y35790D01*
X527215Y35915D01*
X527225Y36040D01*
Y38165D01*
X527255Y38195D01*
X527280Y38230D01*
X527310Y38265D01*
X527330Y38300D01*
X527355Y38335D01*
X527395Y38415D01*
X527440Y38535D01*
X527450Y38575D01*
X527460Y38620D01*
X527465Y38660D01*
X527475Y38705D01*
Y38875D01*
X527465Y38920D01*
X527460Y38960D01*
X527450Y39005D01*
X527440Y39045D01*
X527395Y39165D01*
X527355Y39245D01*
X527330Y39280D01*
X527310Y39315D01*
X527280Y39350D01*
X527255Y39385D01*
X527225Y39415D01*
Y41840D01*
X527215Y41965D01*
X527175Y42090D01*
X527115Y42200D01*
X527035Y42300D01*
X526935Y42380D01*
X526825Y42440D01*
X526700Y42480D01*
X526575Y42490D01*
X526450Y42480D01*
X526325Y42440D01*
X526215Y42380D01*
X526115Y42300D01*
X526035Y42200D01*
X525975Y42090D01*
X525935Y41965D01*
X525925Y41840D01*
Y39410D01*
X525895Y39380D01*
X525795Y39240D01*
X525775Y39200D01*
X525760Y39165D01*
X525740Y39125D01*
X525725Y39085D01*
X525715Y39045D01*
X525700Y39000D01*
X525695Y38960D01*
X525685Y38920D01*
X525680Y38875D01*
Y38835D01*
X525675Y38790D01*
X525680Y38745D01*
Y38705D01*
X525685Y38660D01*
X525695Y38620D01*
X525700Y38580D01*
X525715Y38535D01*
X525725Y38495D01*
X525740Y38455D01*
X525760Y38415D01*
X525775Y38380D01*
X525795Y38340D01*
X525895Y38200D01*
X525925Y38170D01*
Y36040D01*
X525935Y35915D01*
X525975Y35790D01*
X526035Y35680D01*
X526115Y35580D01*
X526215Y35500D01*
X526325Y35440D01*
X526450Y35400D01*
X526575Y35390D01*
G37*
G36*
G01X554921D02*
X555046Y35400D01*
X555171Y35440D01*
X555281Y35500D01*
X555381Y35580D01*
X555461Y35680D01*
X555521Y35790D01*
X555561Y35915D01*
X555571Y36040D01*
Y38165D01*
X555601Y38195D01*
X555626Y38230D01*
X555656Y38265D01*
X555676Y38300D01*
X555701Y38335D01*
X555741Y38415D01*
X555786Y38535D01*
X555796Y38575D01*
X555806Y38620D01*
X555811Y38660D01*
X555821Y38705D01*
Y38875D01*
X555811Y38920D01*
X555806Y38960D01*
X555796Y39005D01*
X555786Y39045D01*
X555741Y39165D01*
X555701Y39245D01*
X555676Y39280D01*
X555656Y39315D01*
X555626Y39350D01*
X555601Y39385D01*
X555571Y39415D01*
Y41840D01*
X555561Y41965D01*
X555521Y42090D01*
X555461Y42200D01*
X555381Y42300D01*
X555281Y42380D01*
X555171Y42440D01*
X555046Y42480D01*
X554921Y42490D01*
X554796Y42480D01*
X554671Y42440D01*
X554561Y42380D01*
X554461Y42300D01*
X554381Y42200D01*
X554321Y42090D01*
X554281Y41965D01*
X554271Y41840D01*
Y39410D01*
X554241Y39380D01*
X554141Y39240D01*
X554121Y39200D01*
X554106Y39165D01*
X554086Y39125D01*
X554071Y39085D01*
X554061Y39045D01*
X554046Y39000D01*
X554041Y38960D01*
X554031Y38920D01*
X554026Y38875D01*
Y38835D01*
X554021Y38790D01*
X554026Y38745D01*
Y38705D01*
X554031Y38660D01*
X554041Y38620D01*
X554046Y38580D01*
X554061Y38535D01*
X554071Y38495D01*
X554086Y38455D01*
X554106Y38415D01*
X554121Y38380D01*
X554141Y38340D01*
X554241Y38200D01*
X554271Y38170D01*
Y36040D01*
X554281Y35915D01*
X554321Y35790D01*
X554381Y35680D01*
X554461Y35580D01*
X554561Y35500D01*
X554671Y35440D01*
X554796Y35400D01*
X554921Y35390D01*
G37*
G36*
G01X550197D02*
X550322Y35400D01*
X550447Y35440D01*
X550557Y35500D01*
X550657Y35580D01*
X550737Y35680D01*
X550797Y35790D01*
X550837Y35915D01*
X550847Y36040D01*
Y38165D01*
X550877Y38195D01*
X550902Y38230D01*
X550932Y38265D01*
X550952Y38300D01*
X550977Y38335D01*
X551017Y38415D01*
X551062Y38535D01*
X551072Y38575D01*
X551082Y38620D01*
X551087Y38660D01*
X551097Y38705D01*
Y38875D01*
X551087Y38920D01*
X551082Y38960D01*
X551072Y39005D01*
X551062Y39045D01*
X551017Y39165D01*
X550977Y39245D01*
X550952Y39280D01*
X550932Y39315D01*
X550902Y39350D01*
X550877Y39385D01*
X550847Y39415D01*
Y41840D01*
X550837Y41965D01*
X550797Y42090D01*
X550737Y42200D01*
X550657Y42300D01*
X550557Y42380D01*
X550447Y42440D01*
X550322Y42480D01*
X550197Y42490D01*
X550072Y42480D01*
X549947Y42440D01*
X549837Y42380D01*
X549737Y42300D01*
X549657Y42200D01*
X549597Y42090D01*
X549557Y41965D01*
X549547Y41840D01*
Y39410D01*
X549517Y39380D01*
X549417Y39240D01*
X549397Y39200D01*
X549382Y39165D01*
X549362Y39125D01*
X549347Y39085D01*
X549337Y39045D01*
X549322Y39000D01*
X549317Y38960D01*
X549307Y38920D01*
X549302Y38875D01*
Y38835D01*
X549297Y38790D01*
X549302Y38745D01*
Y38705D01*
X549307Y38660D01*
X549317Y38620D01*
X549322Y38580D01*
X549337Y38535D01*
X549347Y38495D01*
X549362Y38455D01*
X549382Y38415D01*
X549397Y38380D01*
X549417Y38340D01*
X549517Y38200D01*
X549547Y38170D01*
Y36040D01*
X549557Y35915D01*
X549597Y35790D01*
X549657Y35680D01*
X549737Y35580D01*
X549837Y35500D01*
X549947Y35440D01*
X550072Y35400D01*
X550197Y35390D01*
G37*
G36*
G01X545472D02*
X545597Y35400D01*
X545722Y35440D01*
X545832Y35500D01*
X545932Y35580D01*
X546012Y35680D01*
X546072Y35790D01*
X546112Y35915D01*
X546122Y36040D01*
Y38165D01*
X546152Y38195D01*
X546177Y38230D01*
X546207Y38265D01*
X546227Y38300D01*
X546252Y38335D01*
X546292Y38415D01*
X546337Y38535D01*
X546347Y38575D01*
X546357Y38620D01*
X546362Y38660D01*
X546372Y38705D01*
Y38875D01*
X546362Y38920D01*
X546357Y38960D01*
X546347Y39005D01*
X546337Y39045D01*
X546292Y39165D01*
X546252Y39245D01*
X546227Y39280D01*
X546207Y39315D01*
X546177Y39350D01*
X546152Y39385D01*
X546122Y39415D01*
Y41840D01*
X546112Y41965D01*
X546072Y42090D01*
X546012Y42200D01*
X545932Y42300D01*
X545832Y42380D01*
X545722Y42440D01*
X545597Y42480D01*
X545472Y42490D01*
X545347Y42480D01*
X545222Y42440D01*
X545112Y42380D01*
X545012Y42300D01*
X544932Y42200D01*
X544872Y42090D01*
X544832Y41965D01*
X544822Y41840D01*
Y39410D01*
X544792Y39380D01*
X544692Y39240D01*
X544672Y39200D01*
X544657Y39165D01*
X544637Y39125D01*
X544622Y39085D01*
X544612Y39045D01*
X544597Y39000D01*
X544592Y38960D01*
X544582Y38920D01*
X544577Y38875D01*
Y38835D01*
X544572Y38790D01*
X544577Y38745D01*
Y38705D01*
X544582Y38660D01*
X544592Y38620D01*
X544597Y38580D01*
X544612Y38535D01*
X544622Y38495D01*
X544637Y38455D01*
X544657Y38415D01*
X544672Y38380D01*
X544692Y38340D01*
X544792Y38200D01*
X544822Y38170D01*
Y36040D01*
X544832Y35915D01*
X544872Y35790D01*
X544932Y35680D01*
X545012Y35580D01*
X545112Y35500D01*
X545222Y35440D01*
X545347Y35400D01*
X545472Y35390D01*
G37*
G36*
G01X569094D02*
X569219Y35400D01*
X569344Y35440D01*
X569454Y35500D01*
X569554Y35580D01*
X569634Y35680D01*
X569694Y35790D01*
X569734Y35915D01*
X569744Y36040D01*
Y38165D01*
X569774Y38195D01*
X569799Y38230D01*
X569829Y38265D01*
X569849Y38300D01*
X569874Y38335D01*
X569914Y38415D01*
X569959Y38535D01*
X569969Y38575D01*
X569979Y38620D01*
X569984Y38660D01*
X569994Y38705D01*
Y38875D01*
X569984Y38920D01*
X569979Y38960D01*
X569969Y39005D01*
X569959Y39045D01*
X569914Y39165D01*
X569874Y39245D01*
X569849Y39280D01*
X569829Y39315D01*
X569799Y39350D01*
X569774Y39385D01*
X569744Y39415D01*
Y41840D01*
X569734Y41965D01*
X569694Y42090D01*
X569634Y42200D01*
X569554Y42300D01*
X569454Y42380D01*
X569344Y42440D01*
X569219Y42480D01*
X569094Y42490D01*
X568969Y42480D01*
X568844Y42440D01*
X568734Y42380D01*
X568634Y42300D01*
X568554Y42200D01*
X568494Y42090D01*
X568454Y41965D01*
X568444Y41840D01*
Y39410D01*
X568414Y39380D01*
X568314Y39240D01*
X568294Y39200D01*
X568279Y39165D01*
X568259Y39125D01*
X568244Y39085D01*
X568234Y39045D01*
X568219Y39000D01*
X568214Y38960D01*
X568204Y38920D01*
X568199Y38875D01*
Y38835D01*
X568194Y38790D01*
X568199Y38745D01*
Y38705D01*
X568204Y38660D01*
X568214Y38620D01*
X568219Y38580D01*
X568234Y38535D01*
X568244Y38495D01*
X568259Y38455D01*
X568279Y38415D01*
X568294Y38380D01*
X568314Y38340D01*
X568414Y38200D01*
X568444Y38170D01*
Y36040D01*
X568454Y35915D01*
X568494Y35790D01*
X568554Y35680D01*
X568634Y35580D01*
X568734Y35500D01*
X568844Y35440D01*
X568969Y35400D01*
X569094Y35390D01*
G37*
G36*
G01X564370D02*
X564495Y35400D01*
X564620Y35440D01*
X564730Y35500D01*
X564830Y35580D01*
X564910Y35680D01*
X564970Y35790D01*
X565010Y35915D01*
X565020Y36040D01*
Y38165D01*
X565050Y38195D01*
X565075Y38230D01*
X565105Y38265D01*
X565125Y38300D01*
X565150Y38335D01*
X565190Y38415D01*
X565235Y38535D01*
X565245Y38575D01*
X565255Y38620D01*
X565260Y38660D01*
X565270Y38705D01*
Y38875D01*
X565260Y38920D01*
X565255Y38960D01*
X565245Y39005D01*
X565235Y39045D01*
X565190Y39165D01*
X565150Y39245D01*
X565125Y39280D01*
X565105Y39315D01*
X565075Y39350D01*
X565050Y39385D01*
X565020Y39415D01*
Y41840D01*
X565010Y41965D01*
X564970Y42090D01*
X564910Y42200D01*
X564830Y42300D01*
X564730Y42380D01*
X564620Y42440D01*
X564495Y42480D01*
X564370Y42490D01*
X564245Y42480D01*
X564120Y42440D01*
X564010Y42380D01*
X563910Y42300D01*
X563830Y42200D01*
X563770Y42090D01*
X563730Y41965D01*
X563720Y41840D01*
Y39410D01*
X563690Y39380D01*
X563590Y39240D01*
X563570Y39200D01*
X563555Y39165D01*
X563535Y39125D01*
X563520Y39085D01*
X563510Y39045D01*
X563495Y39000D01*
X563490Y38960D01*
X563480Y38920D01*
X563475Y38875D01*
Y38835D01*
X563470Y38790D01*
X563475Y38745D01*
Y38705D01*
X563480Y38660D01*
X563490Y38620D01*
X563495Y38580D01*
X563510Y38535D01*
X563520Y38495D01*
X563535Y38455D01*
X563555Y38415D01*
X563570Y38380D01*
X563590Y38340D01*
X563690Y38200D01*
X563720Y38170D01*
Y36040D01*
X563730Y35915D01*
X563770Y35790D01*
X563830Y35680D01*
X563910Y35580D01*
X564010Y35500D01*
X564120Y35440D01*
X564245Y35400D01*
X564370Y35390D01*
G37*
G36*
G01X559645D02*
X559770Y35400D01*
X559895Y35440D01*
X560005Y35500D01*
X560105Y35580D01*
X560185Y35680D01*
X560245Y35790D01*
X560285Y35915D01*
X560295Y36040D01*
Y38165D01*
X560325Y38195D01*
X560350Y38230D01*
X560380Y38265D01*
X560400Y38300D01*
X560425Y38335D01*
X560465Y38415D01*
X560510Y38535D01*
X560520Y38575D01*
X560530Y38620D01*
X560535Y38660D01*
X560545Y38705D01*
Y38875D01*
X560535Y38920D01*
X560530Y38960D01*
X560520Y39005D01*
X560510Y39045D01*
X560465Y39165D01*
X560425Y39245D01*
X560400Y39280D01*
X560380Y39315D01*
X560350Y39350D01*
X560325Y39385D01*
X560295Y39415D01*
Y41840D01*
X560285Y41965D01*
X560245Y42090D01*
X560185Y42200D01*
X560105Y42300D01*
X560005Y42380D01*
X559895Y42440D01*
X559770Y42480D01*
X559645Y42490D01*
X559520Y42480D01*
X559395Y42440D01*
X559285Y42380D01*
X559185Y42300D01*
X559105Y42200D01*
X559045Y42090D01*
X559005Y41965D01*
X558995Y41840D01*
Y39410D01*
X558965Y39380D01*
X558865Y39240D01*
X558845Y39200D01*
X558830Y39165D01*
X558810Y39125D01*
X558795Y39085D01*
X558785Y39045D01*
X558770Y39000D01*
X558765Y38960D01*
X558755Y38920D01*
X558750Y38875D01*
Y38835D01*
X558745Y38790D01*
X558750Y38745D01*
Y38705D01*
X558755Y38660D01*
X558765Y38620D01*
X558770Y38580D01*
X558785Y38535D01*
X558795Y38495D01*
X558810Y38455D01*
X558830Y38415D01*
X558845Y38380D01*
X558865Y38340D01*
X558965Y38200D01*
X558995Y38170D01*
Y36040D01*
X559005Y35915D01*
X559045Y35790D01*
X559105Y35680D01*
X559185Y35580D01*
X559285Y35500D01*
X559395Y35440D01*
X559520Y35400D01*
X559645Y35390D01*
G37*
G36*
G01X587992D02*
X588117Y35400D01*
X588242Y35440D01*
X588352Y35500D01*
X588452Y35580D01*
X588532Y35680D01*
X588592Y35790D01*
X588632Y35915D01*
X588642Y36040D01*
Y38165D01*
X588672Y38195D01*
X588697Y38230D01*
X588727Y38265D01*
X588747Y38300D01*
X588772Y38335D01*
X588812Y38415D01*
X588857Y38535D01*
X588867Y38575D01*
X588877Y38620D01*
X588882Y38660D01*
X588892Y38705D01*
Y38875D01*
X588882Y38920D01*
X588877Y38960D01*
X588867Y39005D01*
X588857Y39045D01*
X588812Y39165D01*
X588772Y39245D01*
X588747Y39280D01*
X588727Y39315D01*
X588697Y39350D01*
X588672Y39385D01*
X588642Y39415D01*
Y41840D01*
X588632Y41965D01*
X588592Y42090D01*
X588532Y42200D01*
X588452Y42300D01*
X588352Y42380D01*
X588242Y42440D01*
X588117Y42480D01*
X587992Y42490D01*
X587867Y42480D01*
X587742Y42440D01*
X587632Y42380D01*
X587532Y42300D01*
X587452Y42200D01*
X587392Y42090D01*
X587352Y41965D01*
X587342Y41840D01*
Y39410D01*
X587312Y39380D01*
X587212Y39240D01*
X587192Y39200D01*
X587177Y39165D01*
X587157Y39125D01*
X587142Y39085D01*
X587132Y39045D01*
X587117Y39000D01*
X587112Y38960D01*
X587102Y38920D01*
X587097Y38875D01*
Y38835D01*
X587092Y38790D01*
X587097Y38745D01*
Y38705D01*
X587102Y38660D01*
X587112Y38620D01*
X587117Y38580D01*
X587132Y38535D01*
X587142Y38495D01*
X587157Y38455D01*
X587177Y38415D01*
X587192Y38380D01*
X587212Y38340D01*
X587312Y38200D01*
X587342Y38170D01*
Y36040D01*
X587352Y35915D01*
X587392Y35790D01*
X587452Y35680D01*
X587532Y35580D01*
X587632Y35500D01*
X587742Y35440D01*
X587867Y35400D01*
X587992Y35390D01*
G37*
G36*
G01X583267D02*
X583392Y35400D01*
X583517Y35440D01*
X583627Y35500D01*
X583727Y35580D01*
X583807Y35680D01*
X583867Y35790D01*
X583907Y35915D01*
X583917Y36040D01*
Y38165D01*
X583947Y38195D01*
X583972Y38230D01*
X584002Y38265D01*
X584022Y38300D01*
X584047Y38335D01*
X584087Y38415D01*
X584132Y38535D01*
X584142Y38575D01*
X584152Y38620D01*
X584157Y38660D01*
X584167Y38705D01*
Y38875D01*
X584157Y38920D01*
X584152Y38960D01*
X584142Y39005D01*
X584132Y39045D01*
X584087Y39165D01*
X584047Y39245D01*
X584022Y39280D01*
X584002Y39315D01*
X583972Y39350D01*
X583947Y39385D01*
X583917Y39415D01*
Y41840D01*
X583907Y41965D01*
X583867Y42090D01*
X583807Y42200D01*
X583727Y42300D01*
X583627Y42380D01*
X583517Y42440D01*
X583392Y42480D01*
X583267Y42490D01*
X583142Y42480D01*
X583017Y42440D01*
X582907Y42380D01*
X582807Y42300D01*
X582727Y42200D01*
X582667Y42090D01*
X582627Y41965D01*
X582617Y41840D01*
Y39410D01*
X582587Y39380D01*
X582487Y39240D01*
X582467Y39200D01*
X582452Y39165D01*
X582432Y39125D01*
X582417Y39085D01*
X582407Y39045D01*
X582392Y39000D01*
X582387Y38960D01*
X582377Y38920D01*
X582372Y38875D01*
Y38835D01*
X582367Y38790D01*
X582372Y38745D01*
Y38705D01*
X582377Y38660D01*
X582387Y38620D01*
X582392Y38580D01*
X582407Y38535D01*
X582417Y38495D01*
X582432Y38455D01*
X582452Y38415D01*
X582467Y38380D01*
X582487Y38340D01*
X582587Y38200D01*
X582617Y38170D01*
Y36040D01*
X582627Y35915D01*
X582667Y35790D01*
X582727Y35680D01*
X582807Y35580D01*
X582907Y35500D01*
X583017Y35440D01*
X583142Y35400D01*
X583267Y35390D01*
G37*
G36*
G01X578543D02*
X578668Y35400D01*
X578793Y35440D01*
X578903Y35500D01*
X579003Y35580D01*
X579083Y35680D01*
X579143Y35790D01*
X579183Y35915D01*
X579193Y36040D01*
Y38165D01*
X579223Y38195D01*
X579248Y38230D01*
X579278Y38265D01*
X579298Y38300D01*
X579323Y38335D01*
X579363Y38415D01*
X579408Y38535D01*
X579418Y38575D01*
X579428Y38620D01*
X579433Y38660D01*
X579443Y38705D01*
Y38875D01*
X579433Y38920D01*
X579428Y38960D01*
X579418Y39005D01*
X579408Y39045D01*
X579363Y39165D01*
X579323Y39245D01*
X579298Y39280D01*
X579278Y39315D01*
X579248Y39350D01*
X579223Y39385D01*
X579193Y39415D01*
Y41840D01*
X579183Y41965D01*
X579143Y42090D01*
X579083Y42200D01*
X579003Y42300D01*
X578903Y42380D01*
X578793Y42440D01*
X578668Y42480D01*
X578543Y42490D01*
X578418Y42480D01*
X578293Y42440D01*
X578183Y42380D01*
X578083Y42300D01*
X578003Y42200D01*
X577943Y42090D01*
X577903Y41965D01*
X577893Y41840D01*
Y39410D01*
X577863Y39380D01*
X577763Y39240D01*
X577743Y39200D01*
X577728Y39165D01*
X577708Y39125D01*
X577693Y39085D01*
X577683Y39045D01*
X577668Y39000D01*
X577663Y38960D01*
X577653Y38920D01*
X577648Y38875D01*
Y38835D01*
X577643Y38790D01*
X577648Y38745D01*
Y38705D01*
X577653Y38660D01*
X577663Y38620D01*
X577668Y38580D01*
X577683Y38535D01*
X577693Y38495D01*
X577708Y38455D01*
X577728Y38415D01*
X577743Y38380D01*
X577763Y38340D01*
X577863Y38200D01*
X577893Y38170D01*
Y36040D01*
X577903Y35915D01*
X577943Y35790D01*
X578003Y35680D01*
X578083Y35580D01*
X578183Y35500D01*
X578293Y35440D01*
X578418Y35400D01*
X578543Y35390D01*
G37*
G36*
G01X573819D02*
X573944Y35400D01*
X574069Y35440D01*
X574179Y35500D01*
X574279Y35580D01*
X574359Y35680D01*
X574419Y35790D01*
X574459Y35915D01*
X574469Y36040D01*
Y38165D01*
X574499Y38195D01*
X574524Y38230D01*
X574554Y38265D01*
X574574Y38300D01*
X574599Y38335D01*
X574639Y38415D01*
X574684Y38535D01*
X574694Y38575D01*
X574704Y38620D01*
X574709Y38660D01*
X574719Y38705D01*
Y38875D01*
X574709Y38920D01*
X574704Y38960D01*
X574694Y39005D01*
X574684Y39045D01*
X574639Y39165D01*
X574599Y39245D01*
X574574Y39280D01*
X574554Y39315D01*
X574524Y39350D01*
X574499Y39385D01*
X574469Y39415D01*
Y41840D01*
X574459Y41965D01*
X574419Y42090D01*
X574359Y42200D01*
X574279Y42300D01*
X574179Y42380D01*
X574069Y42440D01*
X573944Y42480D01*
X573819Y42490D01*
X573694Y42480D01*
X573569Y42440D01*
X573459Y42380D01*
X573359Y42300D01*
X573279Y42200D01*
X573219Y42090D01*
X573179Y41965D01*
X573169Y41840D01*
Y39410D01*
X573139Y39380D01*
X573039Y39240D01*
X573019Y39200D01*
X573004Y39165D01*
X572984Y39125D01*
X572969Y39085D01*
X572959Y39045D01*
X572944Y39000D01*
X572939Y38960D01*
X572929Y38920D01*
X572924Y38875D01*
Y38835D01*
X572919Y38790D01*
X572924Y38745D01*
Y38705D01*
X572929Y38660D01*
X572939Y38620D01*
X572944Y38580D01*
X572959Y38535D01*
X572969Y38495D01*
X572984Y38455D01*
X573004Y38415D01*
X573019Y38380D01*
X573039Y38340D01*
X573139Y38200D01*
X573169Y38170D01*
Y36040D01*
X573179Y35915D01*
X573219Y35790D01*
X573279Y35680D01*
X573359Y35580D01*
X573459Y35500D01*
X573569Y35440D01*
X573694Y35400D01*
X573819Y35390D01*
G37*
G36*
G01X602165D02*
X602290Y35400D01*
X602415Y35440D01*
X602525Y35500D01*
X602625Y35580D01*
X602705Y35680D01*
X602765Y35790D01*
X602805Y35915D01*
X602815Y36040D01*
Y38165D01*
X602845Y38195D01*
X602870Y38230D01*
X602900Y38265D01*
X602920Y38300D01*
X602945Y38335D01*
X602985Y38415D01*
X603030Y38535D01*
X603040Y38575D01*
X603050Y38620D01*
X603055Y38660D01*
X603065Y38705D01*
Y38875D01*
X603055Y38920D01*
X603050Y38960D01*
X603040Y39005D01*
X603030Y39045D01*
X602985Y39165D01*
X602945Y39245D01*
X602920Y39280D01*
X602900Y39315D01*
X602870Y39350D01*
X602845Y39385D01*
X602815Y39415D01*
Y41840D01*
X602805Y41965D01*
X602765Y42090D01*
X602705Y42200D01*
X602625Y42300D01*
X602525Y42380D01*
X602415Y42440D01*
X602290Y42480D01*
X602165Y42490D01*
X602040Y42480D01*
X601915Y42440D01*
X601805Y42380D01*
X601705Y42300D01*
X601625Y42200D01*
X601565Y42090D01*
X601525Y41965D01*
X601515Y41840D01*
Y39410D01*
X601485Y39380D01*
X601385Y39240D01*
X601365Y39200D01*
X601350Y39165D01*
X601330Y39125D01*
X601315Y39085D01*
X601305Y39045D01*
X601290Y39000D01*
X601285Y38960D01*
X601275Y38920D01*
X601270Y38875D01*
Y38835D01*
X601265Y38790D01*
X601270Y38745D01*
Y38705D01*
X601275Y38660D01*
X601285Y38620D01*
X601290Y38580D01*
X601305Y38535D01*
X601315Y38495D01*
X601330Y38455D01*
X601350Y38415D01*
X601365Y38380D01*
X601385Y38340D01*
X601485Y38200D01*
X601515Y38170D01*
Y36040D01*
X601525Y35915D01*
X601565Y35790D01*
X601625Y35680D01*
X601705Y35580D01*
X601805Y35500D01*
X601915Y35440D01*
X602040Y35400D01*
X602165Y35390D01*
G37*
G36*
G01X616338D02*
X616463Y35400D01*
X616588Y35440D01*
X616698Y35500D01*
X616798Y35580D01*
X616878Y35680D01*
X616938Y35790D01*
X616978Y35915D01*
X616988Y36040D01*
Y38165D01*
X617018Y38195D01*
X617043Y38230D01*
X617073Y38265D01*
X617093Y38300D01*
X617118Y38335D01*
X617158Y38415D01*
X617203Y38535D01*
X617213Y38575D01*
X617223Y38620D01*
X617228Y38660D01*
X617238Y38705D01*
Y38875D01*
X617228Y38920D01*
X617223Y38960D01*
X617213Y39005D01*
X617203Y39045D01*
X617158Y39165D01*
X617118Y39245D01*
X617093Y39280D01*
X617073Y39315D01*
X617043Y39350D01*
X617018Y39385D01*
X616988Y39415D01*
Y41840D01*
X616978Y41965D01*
X616938Y42090D01*
X616878Y42200D01*
X616798Y42300D01*
X616698Y42380D01*
X616588Y42440D01*
X616463Y42480D01*
X616338Y42490D01*
X616213Y42480D01*
X616088Y42440D01*
X615978Y42380D01*
X615878Y42300D01*
X615798Y42200D01*
X615738Y42090D01*
X615698Y41965D01*
X615688Y41840D01*
Y39410D01*
X615658Y39380D01*
X615558Y39240D01*
X615538Y39200D01*
X615523Y39165D01*
X615503Y39125D01*
X615488Y39085D01*
X615478Y39045D01*
X615463Y39000D01*
X615458Y38960D01*
X615448Y38920D01*
X615443Y38875D01*
Y38835D01*
X615438Y38790D01*
X615443Y38745D01*
Y38705D01*
X615448Y38660D01*
X615458Y38620D01*
X615463Y38580D01*
X615478Y38535D01*
X615488Y38495D01*
X615503Y38455D01*
X615523Y38415D01*
X615538Y38380D01*
X615558Y38340D01*
X615658Y38200D01*
X615688Y38170D01*
Y36040D01*
X615698Y35915D01*
X615738Y35790D01*
X615798Y35680D01*
X615878Y35580D01*
X615978Y35500D01*
X616088Y35440D01*
X616213Y35400D01*
X616338Y35390D01*
G37*
G36*
G01X611614D02*
X611739Y35400D01*
X611864Y35440D01*
X611974Y35500D01*
X612074Y35580D01*
X612154Y35680D01*
X612214Y35790D01*
X612254Y35915D01*
X612264Y36040D01*
Y38165D01*
X612294Y38195D01*
X612319Y38230D01*
X612349Y38265D01*
X612369Y38300D01*
X612394Y38335D01*
X612434Y38415D01*
X612479Y38535D01*
X612489Y38575D01*
X612499Y38620D01*
X612504Y38660D01*
X612514Y38705D01*
Y38875D01*
X612504Y38920D01*
X612499Y38960D01*
X612489Y39005D01*
X612479Y39045D01*
X612434Y39165D01*
X612394Y39245D01*
X612369Y39280D01*
X612349Y39315D01*
X612319Y39350D01*
X612294Y39385D01*
X612264Y39415D01*
Y41840D01*
X612254Y41965D01*
X612214Y42090D01*
X612154Y42200D01*
X612074Y42300D01*
X611974Y42380D01*
X611864Y42440D01*
X611739Y42480D01*
X611614Y42490D01*
X611489Y42480D01*
X611364Y42440D01*
X611254Y42380D01*
X611154Y42300D01*
X611074Y42200D01*
X611014Y42090D01*
X610974Y41965D01*
X610964Y41840D01*
Y39410D01*
X610934Y39380D01*
X610834Y39240D01*
X610814Y39200D01*
X610799Y39165D01*
X610779Y39125D01*
X610764Y39085D01*
X610754Y39045D01*
X610739Y39000D01*
X610734Y38960D01*
X610724Y38920D01*
X610719Y38875D01*
Y38835D01*
X610714Y38790D01*
X610719Y38745D01*
Y38705D01*
X610724Y38660D01*
X610734Y38620D01*
X610739Y38580D01*
X610754Y38535D01*
X610764Y38495D01*
X610779Y38455D01*
X610799Y38415D01*
X610814Y38380D01*
X610834Y38340D01*
X610934Y38200D01*
X610964Y38170D01*
Y36040D01*
X610974Y35915D01*
X611014Y35790D01*
X611074Y35680D01*
X611154Y35580D01*
X611254Y35500D01*
X611364Y35440D01*
X611489Y35400D01*
X611614Y35390D01*
G37*
G36*
G01X606890D02*
X607015Y35400D01*
X607140Y35440D01*
X607250Y35500D01*
X607350Y35580D01*
X607430Y35680D01*
X607490Y35790D01*
X607530Y35915D01*
X607540Y36040D01*
Y38165D01*
X607570Y38195D01*
X607595Y38230D01*
X607625Y38265D01*
X607645Y38300D01*
X607670Y38335D01*
X607710Y38415D01*
X607755Y38535D01*
X607765Y38575D01*
X607775Y38620D01*
X607780Y38660D01*
X607790Y38705D01*
Y38875D01*
X607780Y38920D01*
X607775Y38960D01*
X607765Y39005D01*
X607755Y39045D01*
X607710Y39165D01*
X607670Y39245D01*
X607645Y39280D01*
X607625Y39315D01*
X607595Y39350D01*
X607570Y39385D01*
X607540Y39415D01*
Y41840D01*
X607530Y41965D01*
X607490Y42090D01*
X607430Y42200D01*
X607350Y42300D01*
X607250Y42380D01*
X607140Y42440D01*
X607015Y42480D01*
X606890Y42490D01*
X606765Y42480D01*
X606640Y42440D01*
X606530Y42380D01*
X606430Y42300D01*
X606350Y42200D01*
X606290Y42090D01*
X606250Y41965D01*
X606240Y41840D01*
Y39410D01*
X606210Y39380D01*
X606110Y39240D01*
X606090Y39200D01*
X606075Y39165D01*
X606055Y39125D01*
X606040Y39085D01*
X606030Y39045D01*
X606015Y39000D01*
X606010Y38960D01*
X606000Y38920D01*
X605995Y38875D01*
Y38835D01*
X605990Y38790D01*
X605995Y38745D01*
Y38705D01*
X606000Y38660D01*
X606010Y38620D01*
X606015Y38580D01*
X606030Y38535D01*
X606040Y38495D01*
X606055Y38455D01*
X606075Y38415D01*
X606090Y38380D01*
X606110Y38340D01*
X606210Y38200D01*
X606240Y38170D01*
Y36040D01*
X606250Y35915D01*
X606290Y35790D01*
X606350Y35680D01*
X606430Y35580D01*
X606530Y35500D01*
X606640Y35440D01*
X606765Y35400D01*
X606890Y35390D01*
G37*
G36*
G01X630512D02*
X630637Y35400D01*
X630762Y35440D01*
X630872Y35500D01*
X630972Y35580D01*
X631052Y35680D01*
X631112Y35790D01*
X631152Y35915D01*
X631162Y36040D01*
Y38165D01*
X631192Y38195D01*
X631217Y38230D01*
X631247Y38265D01*
X631267Y38300D01*
X631292Y38335D01*
X631332Y38415D01*
X631377Y38535D01*
X631387Y38575D01*
X631397Y38620D01*
X631402Y38660D01*
X631412Y38705D01*
Y38875D01*
X631402Y38920D01*
X631397Y38960D01*
X631387Y39005D01*
X631377Y39045D01*
X631332Y39165D01*
X631292Y39245D01*
X631267Y39280D01*
X631247Y39315D01*
X631217Y39350D01*
X631192Y39385D01*
X631162Y39415D01*
Y41840D01*
X631152Y41965D01*
X631112Y42090D01*
X631052Y42200D01*
X630972Y42300D01*
X630872Y42380D01*
X630762Y42440D01*
X630637Y42480D01*
X630512Y42490D01*
X630387Y42480D01*
X630262Y42440D01*
X630152Y42380D01*
X630052Y42300D01*
X629972Y42200D01*
X629912Y42090D01*
X629872Y41965D01*
X629862Y41840D01*
Y39410D01*
X629832Y39380D01*
X629732Y39240D01*
X629712Y39200D01*
X629697Y39165D01*
X629677Y39125D01*
X629662Y39085D01*
X629652Y39045D01*
X629637Y39000D01*
X629632Y38960D01*
X629622Y38920D01*
X629617Y38875D01*
Y38835D01*
X629612Y38790D01*
X629617Y38745D01*
Y38705D01*
X629622Y38660D01*
X629632Y38620D01*
X629637Y38580D01*
X629652Y38535D01*
X629662Y38495D01*
X629677Y38455D01*
X629697Y38415D01*
X629712Y38380D01*
X629732Y38340D01*
X629832Y38200D01*
X629862Y38170D01*
Y36040D01*
X629872Y35915D01*
X629912Y35790D01*
X629972Y35680D01*
X630052Y35580D01*
X630152Y35500D01*
X630262Y35440D01*
X630387Y35400D01*
X630512Y35390D01*
G37*
G36*
G01X625787D02*
X625912Y35400D01*
X626037Y35440D01*
X626147Y35500D01*
X626247Y35580D01*
X626327Y35680D01*
X626387Y35790D01*
X626427Y35915D01*
X626437Y36040D01*
Y38165D01*
X626467Y38195D01*
X626492Y38230D01*
X626522Y38265D01*
X626542Y38300D01*
X626567Y38335D01*
X626607Y38415D01*
X626652Y38535D01*
X626662Y38575D01*
X626672Y38620D01*
X626677Y38660D01*
X626687Y38705D01*
Y38875D01*
X626677Y38920D01*
X626672Y38960D01*
X626662Y39005D01*
X626652Y39045D01*
X626607Y39165D01*
X626567Y39245D01*
X626542Y39280D01*
X626522Y39315D01*
X626492Y39350D01*
X626467Y39385D01*
X626437Y39415D01*
Y41840D01*
X626427Y41965D01*
X626387Y42090D01*
X626327Y42200D01*
X626247Y42300D01*
X626147Y42380D01*
X626037Y42440D01*
X625912Y42480D01*
X625787Y42490D01*
X625662Y42480D01*
X625537Y42440D01*
X625427Y42380D01*
X625327Y42300D01*
X625247Y42200D01*
X625187Y42090D01*
X625147Y41965D01*
X625137Y41840D01*
Y39410D01*
X625107Y39380D01*
X625007Y39240D01*
X624987Y39200D01*
X624972Y39165D01*
X624952Y39125D01*
X624937Y39085D01*
X624927Y39045D01*
X624912Y39000D01*
X624907Y38960D01*
X624897Y38920D01*
X624892Y38875D01*
Y38835D01*
X624887Y38790D01*
X624892Y38745D01*
Y38705D01*
X624897Y38660D01*
X624907Y38620D01*
X624912Y38580D01*
X624927Y38535D01*
X624937Y38495D01*
X624952Y38455D01*
X624972Y38415D01*
X624987Y38380D01*
X625007Y38340D01*
X625107Y38200D01*
X625137Y38170D01*
Y36040D01*
X625147Y35915D01*
X625187Y35790D01*
X625247Y35680D01*
X625327Y35580D01*
X625427Y35500D01*
X625537Y35440D01*
X625662Y35400D01*
X625787Y35390D01*
G37*
G36*
G01X621063D02*
X621188Y35400D01*
X621313Y35440D01*
X621423Y35500D01*
X621523Y35580D01*
X621603Y35680D01*
X621663Y35790D01*
X621703Y35915D01*
X621713Y36040D01*
Y38165D01*
X621743Y38195D01*
X621768Y38230D01*
X621798Y38265D01*
X621818Y38300D01*
X621843Y38335D01*
X621883Y38415D01*
X621928Y38535D01*
X621938Y38575D01*
X621948Y38620D01*
X621953Y38660D01*
X621963Y38705D01*
Y38875D01*
X621953Y38920D01*
X621948Y38960D01*
X621938Y39005D01*
X621928Y39045D01*
X621883Y39165D01*
X621843Y39245D01*
X621818Y39280D01*
X621798Y39315D01*
X621768Y39350D01*
X621743Y39385D01*
X621713Y39415D01*
Y41840D01*
X621703Y41965D01*
X621663Y42090D01*
X621603Y42200D01*
X621523Y42300D01*
X621423Y42380D01*
X621313Y42440D01*
X621188Y42480D01*
X621063Y42490D01*
X620938Y42480D01*
X620813Y42440D01*
X620703Y42380D01*
X620603Y42300D01*
X620523Y42200D01*
X620463Y42090D01*
X620423Y41965D01*
X620413Y41840D01*
Y39410D01*
X620383Y39380D01*
X620283Y39240D01*
X620263Y39200D01*
X620248Y39165D01*
X620228Y39125D01*
X620213Y39085D01*
X620203Y39045D01*
X620188Y39000D01*
X620183Y38960D01*
X620173Y38920D01*
X620168Y38875D01*
Y38835D01*
X620163Y38790D01*
X620168Y38745D01*
Y38705D01*
X620173Y38660D01*
X620183Y38620D01*
X620188Y38580D01*
X620203Y38535D01*
X620213Y38495D01*
X620228Y38455D01*
X620248Y38415D01*
X620263Y38380D01*
X620283Y38340D01*
X620383Y38200D01*
X620413Y38170D01*
Y36040D01*
X620423Y35915D01*
X620463Y35790D01*
X620523Y35680D01*
X620603Y35580D01*
X620703Y35500D01*
X620813Y35440D01*
X620938Y35400D01*
X621063Y35390D01*
G37*
G36*
G01X649409D02*
X649534Y35400D01*
X649659Y35440D01*
X649769Y35500D01*
X649869Y35580D01*
X649949Y35680D01*
X650009Y35790D01*
X650049Y35915D01*
X650059Y36040D01*
Y38165D01*
X650089Y38195D01*
X650114Y38230D01*
X650144Y38265D01*
X650164Y38300D01*
X650189Y38335D01*
X650229Y38415D01*
X650274Y38535D01*
X650284Y38575D01*
X650294Y38620D01*
X650299Y38660D01*
X650309Y38705D01*
Y38875D01*
X650299Y38920D01*
X650294Y38960D01*
X650284Y39005D01*
X650274Y39045D01*
X650229Y39165D01*
X650189Y39245D01*
X650164Y39280D01*
X650144Y39315D01*
X650114Y39350D01*
X650089Y39385D01*
X650059Y39415D01*
Y41840D01*
X650049Y41965D01*
X650009Y42090D01*
X649949Y42200D01*
X649869Y42300D01*
X649769Y42380D01*
X649659Y42440D01*
X649534Y42480D01*
X649409Y42490D01*
X649284Y42480D01*
X649159Y42440D01*
X649049Y42380D01*
X648949Y42300D01*
X648869Y42200D01*
X648809Y42090D01*
X648769Y41965D01*
X648759Y41840D01*
Y39410D01*
X648729Y39380D01*
X648629Y39240D01*
X648609Y39200D01*
X648594Y39165D01*
X648574Y39125D01*
X648559Y39085D01*
X648549Y39045D01*
X648534Y39000D01*
X648529Y38960D01*
X648519Y38920D01*
X648514Y38875D01*
Y38835D01*
X648509Y38790D01*
X648514Y38745D01*
Y38705D01*
X648519Y38660D01*
X648529Y38620D01*
X648534Y38580D01*
X648549Y38535D01*
X648559Y38495D01*
X648574Y38455D01*
X648594Y38415D01*
X648609Y38380D01*
X648629Y38340D01*
X648729Y38200D01*
X648759Y38170D01*
Y36040D01*
X648769Y35915D01*
X648809Y35790D01*
X648869Y35680D01*
X648949Y35580D01*
X649049Y35500D01*
X649159Y35440D01*
X649284Y35400D01*
X649409Y35390D01*
G37*
G36*
G01X644685D02*
X644810Y35400D01*
X644935Y35440D01*
X645045Y35500D01*
X645145Y35580D01*
X645225Y35680D01*
X645285Y35790D01*
X645325Y35915D01*
X645335Y36040D01*
Y38165D01*
X645365Y38195D01*
X645390Y38230D01*
X645420Y38265D01*
X645440Y38300D01*
X645465Y38335D01*
X645505Y38415D01*
X645550Y38535D01*
X645560Y38575D01*
X645570Y38620D01*
X645575Y38660D01*
X645585Y38705D01*
Y38875D01*
X645575Y38920D01*
X645570Y38960D01*
X645560Y39005D01*
X645550Y39045D01*
X645505Y39165D01*
X645465Y39245D01*
X645440Y39280D01*
X645420Y39315D01*
X645390Y39350D01*
X645365Y39385D01*
X645335Y39415D01*
Y41840D01*
X645325Y41965D01*
X645285Y42090D01*
X645225Y42200D01*
X645145Y42300D01*
X645045Y42380D01*
X644935Y42440D01*
X644810Y42480D01*
X644685Y42490D01*
X644560Y42480D01*
X644435Y42440D01*
X644325Y42380D01*
X644225Y42300D01*
X644145Y42200D01*
X644085Y42090D01*
X644045Y41965D01*
X644035Y41840D01*
Y39410D01*
X644005Y39380D01*
X643905Y39240D01*
X643885Y39200D01*
X643870Y39165D01*
X643850Y39125D01*
X643835Y39085D01*
X643825Y39045D01*
X643810Y39000D01*
X643805Y38960D01*
X643795Y38920D01*
X643790Y38875D01*
Y38835D01*
X643785Y38790D01*
X643790Y38745D01*
Y38705D01*
X643795Y38660D01*
X643805Y38620D01*
X643810Y38580D01*
X643825Y38535D01*
X643835Y38495D01*
X643850Y38455D01*
X643870Y38415D01*
X643885Y38380D01*
X643905Y38340D01*
X644005Y38200D01*
X644035Y38170D01*
Y36040D01*
X644045Y35915D01*
X644085Y35790D01*
X644145Y35680D01*
X644225Y35580D01*
X644325Y35500D01*
X644435Y35440D01*
X644560Y35400D01*
X644685Y35390D01*
G37*
G36*
G01X639960D02*
X640085Y35400D01*
X640210Y35440D01*
X640320Y35500D01*
X640420Y35580D01*
X640500Y35680D01*
X640560Y35790D01*
X640600Y35915D01*
X640610Y36040D01*
Y38165D01*
X640640Y38195D01*
X640665Y38230D01*
X640695Y38265D01*
X640715Y38300D01*
X640740Y38335D01*
X640780Y38415D01*
X640825Y38535D01*
X640835Y38575D01*
X640845Y38620D01*
X640850Y38660D01*
X640860Y38705D01*
Y38875D01*
X640850Y38920D01*
X640845Y38960D01*
X640835Y39005D01*
X640825Y39045D01*
X640780Y39165D01*
X640740Y39245D01*
X640715Y39280D01*
X640695Y39315D01*
X640665Y39350D01*
X640640Y39385D01*
X640610Y39415D01*
Y41840D01*
X640600Y41965D01*
X640560Y42090D01*
X640500Y42200D01*
X640420Y42300D01*
X640320Y42380D01*
X640210Y42440D01*
X640085Y42480D01*
X639960Y42490D01*
X639835Y42480D01*
X639710Y42440D01*
X639600Y42380D01*
X639500Y42300D01*
X639420Y42200D01*
X639360Y42090D01*
X639320Y41965D01*
X639310Y41840D01*
Y39410D01*
X639280Y39380D01*
X639180Y39240D01*
X639160Y39200D01*
X639145Y39165D01*
X639125Y39125D01*
X639110Y39085D01*
X639100Y39045D01*
X639085Y39000D01*
X639080Y38960D01*
X639070Y38920D01*
X639065Y38875D01*
Y38835D01*
X639060Y38790D01*
X639065Y38745D01*
Y38705D01*
X639070Y38660D01*
X639080Y38620D01*
X639085Y38580D01*
X639100Y38535D01*
X639110Y38495D01*
X639125Y38455D01*
X639145Y38415D01*
X639160Y38380D01*
X639180Y38340D01*
X639280Y38200D01*
X639310Y38170D01*
Y36040D01*
X639320Y35915D01*
X639360Y35790D01*
X639420Y35680D01*
X639500Y35580D01*
X639600Y35500D01*
X639710Y35440D01*
X639835Y35400D01*
X639960Y35390D01*
G37*
G36*
G01X635236D02*
X635361Y35400D01*
X635486Y35440D01*
X635596Y35500D01*
X635696Y35580D01*
X635776Y35680D01*
X635836Y35790D01*
X635876Y35915D01*
X635886Y36040D01*
Y38165D01*
X635916Y38195D01*
X635941Y38230D01*
X635971Y38265D01*
X635991Y38300D01*
X636016Y38335D01*
X636056Y38415D01*
X636101Y38535D01*
X636111Y38575D01*
X636121Y38620D01*
X636126Y38660D01*
X636136Y38705D01*
Y38875D01*
X636126Y38920D01*
X636121Y38960D01*
X636111Y39005D01*
X636101Y39045D01*
X636056Y39165D01*
X636016Y39245D01*
X635991Y39280D01*
X635971Y39315D01*
X635941Y39350D01*
X635916Y39385D01*
X635886Y39415D01*
Y41840D01*
X635876Y41965D01*
X635836Y42090D01*
X635776Y42200D01*
X635696Y42300D01*
X635596Y42380D01*
X635486Y42440D01*
X635361Y42480D01*
X635236Y42490D01*
X635111Y42480D01*
X634986Y42440D01*
X634876Y42380D01*
X634776Y42300D01*
X634696Y42200D01*
X634636Y42090D01*
X634596Y41965D01*
X634586Y41840D01*
Y39410D01*
X634556Y39380D01*
X634456Y39240D01*
X634436Y39200D01*
X634421Y39165D01*
X634401Y39125D01*
X634386Y39085D01*
X634376Y39045D01*
X634361Y39000D01*
X634356Y38960D01*
X634346Y38920D01*
X634341Y38875D01*
Y38835D01*
X634336Y38790D01*
X634341Y38745D01*
Y38705D01*
X634346Y38660D01*
X634356Y38620D01*
X634361Y38580D01*
X634376Y38535D01*
X634386Y38495D01*
X634401Y38455D01*
X634421Y38415D01*
X634436Y38380D01*
X634456Y38340D01*
X634556Y38200D01*
X634586Y38170D01*
Y36040D01*
X634596Y35915D01*
X634636Y35790D01*
X634696Y35680D01*
X634776Y35580D01*
X634876Y35500D01*
X634986Y35440D01*
X635111Y35400D01*
X635236Y35390D01*
G37*
G36*
G01X663582D02*
X663707Y35400D01*
X663832Y35440D01*
X663942Y35500D01*
X664042Y35580D01*
X664122Y35680D01*
X664182Y35790D01*
X664222Y35915D01*
X664232Y36040D01*
Y38165D01*
X664262Y38195D01*
X664287Y38230D01*
X664317Y38265D01*
X664337Y38300D01*
X664362Y38335D01*
X664402Y38415D01*
X664447Y38535D01*
X664457Y38575D01*
X664467Y38620D01*
X664472Y38660D01*
X664482Y38705D01*
Y38875D01*
X664472Y38920D01*
X664467Y38960D01*
X664457Y39005D01*
X664447Y39045D01*
X664402Y39165D01*
X664362Y39245D01*
X664337Y39280D01*
X664317Y39315D01*
X664287Y39350D01*
X664262Y39385D01*
X664232Y39415D01*
Y41840D01*
X664222Y41965D01*
X664182Y42090D01*
X664122Y42200D01*
X664042Y42300D01*
X663942Y42380D01*
X663832Y42440D01*
X663707Y42480D01*
X663582Y42490D01*
X663457Y42480D01*
X663332Y42440D01*
X663222Y42380D01*
X663122Y42300D01*
X663042Y42200D01*
X662982Y42090D01*
X662942Y41965D01*
X662932Y41840D01*
Y39410D01*
X662902Y39380D01*
X662802Y39240D01*
X662782Y39200D01*
X662767Y39165D01*
X662747Y39125D01*
X662732Y39085D01*
X662722Y39045D01*
X662707Y39000D01*
X662702Y38960D01*
X662692Y38920D01*
X662687Y38875D01*
Y38835D01*
X662682Y38790D01*
X662687Y38745D01*
Y38705D01*
X662692Y38660D01*
X662702Y38620D01*
X662707Y38580D01*
X662722Y38535D01*
X662732Y38495D01*
X662747Y38455D01*
X662767Y38415D01*
X662782Y38380D01*
X662802Y38340D01*
X662902Y38200D01*
X662932Y38170D01*
Y36040D01*
X662942Y35915D01*
X662982Y35790D01*
X663042Y35680D01*
X663122Y35580D01*
X663222Y35500D01*
X663332Y35440D01*
X663457Y35400D01*
X663582Y35390D01*
G37*
G36*
G01X658858D02*
X658983Y35400D01*
X659108Y35440D01*
X659218Y35500D01*
X659318Y35580D01*
X659398Y35680D01*
X659458Y35790D01*
X659498Y35915D01*
X659508Y36040D01*
Y38165D01*
X659538Y38195D01*
X659563Y38230D01*
X659593Y38265D01*
X659613Y38300D01*
X659638Y38335D01*
X659678Y38415D01*
X659723Y38535D01*
X659733Y38575D01*
X659743Y38620D01*
X659748Y38660D01*
X659758Y38705D01*
Y38875D01*
X659748Y38920D01*
X659743Y38960D01*
X659733Y39005D01*
X659723Y39045D01*
X659678Y39165D01*
X659638Y39245D01*
X659613Y39280D01*
X659593Y39315D01*
X659563Y39350D01*
X659538Y39385D01*
X659508Y39415D01*
Y41840D01*
X659498Y41965D01*
X659458Y42090D01*
X659398Y42200D01*
X659318Y42300D01*
X659218Y42380D01*
X659108Y42440D01*
X658983Y42480D01*
X658858Y42490D01*
X658733Y42480D01*
X658608Y42440D01*
X658498Y42380D01*
X658398Y42300D01*
X658318Y42200D01*
X658258Y42090D01*
X658218Y41965D01*
X658208Y41840D01*
Y39410D01*
X658178Y39380D01*
X658078Y39240D01*
X658058Y39200D01*
X658043Y39165D01*
X658023Y39125D01*
X658008Y39085D01*
X657998Y39045D01*
X657983Y39000D01*
X657978Y38960D01*
X657968Y38920D01*
X657963Y38875D01*
Y38835D01*
X657958Y38790D01*
X657963Y38745D01*
Y38705D01*
X657968Y38660D01*
X657978Y38620D01*
X657983Y38580D01*
X657998Y38535D01*
X658008Y38495D01*
X658023Y38455D01*
X658043Y38415D01*
X658058Y38380D01*
X658078Y38340D01*
X658178Y38200D01*
X658208Y38170D01*
Y36040D01*
X658218Y35915D01*
X658258Y35790D01*
X658318Y35680D01*
X658398Y35580D01*
X658498Y35500D01*
X658608Y35440D01*
X658733Y35400D01*
X658858Y35390D01*
G37*
G36*
G01X654134D02*
X654259Y35400D01*
X654384Y35440D01*
X654494Y35500D01*
X654594Y35580D01*
X654674Y35680D01*
X654734Y35790D01*
X654774Y35915D01*
X654784Y36040D01*
Y38165D01*
X654814Y38195D01*
X654839Y38230D01*
X654869Y38265D01*
X654889Y38300D01*
X654914Y38335D01*
X654954Y38415D01*
X654999Y38535D01*
X655009Y38575D01*
X655019Y38620D01*
X655024Y38660D01*
X655034Y38705D01*
Y38875D01*
X655024Y38920D01*
X655019Y38960D01*
X655009Y39005D01*
X654999Y39045D01*
X654954Y39165D01*
X654914Y39245D01*
X654889Y39280D01*
X654869Y39315D01*
X654839Y39350D01*
X654814Y39385D01*
X654784Y39415D01*
Y41840D01*
X654774Y41965D01*
X654734Y42090D01*
X654674Y42200D01*
X654594Y42300D01*
X654494Y42380D01*
X654384Y42440D01*
X654259Y42480D01*
X654134Y42490D01*
X654009Y42480D01*
X653884Y42440D01*
X653774Y42380D01*
X653674Y42300D01*
X653594Y42200D01*
X653534Y42090D01*
X653494Y41965D01*
X653484Y41840D01*
Y39410D01*
X653454Y39380D01*
X653354Y39240D01*
X653334Y39200D01*
X653319Y39165D01*
X653299Y39125D01*
X653284Y39085D01*
X653274Y39045D01*
X653259Y39000D01*
X653254Y38960D01*
X653244Y38920D01*
X653239Y38875D01*
Y38835D01*
X653234Y38790D01*
X653239Y38745D01*
Y38705D01*
X653244Y38660D01*
X653254Y38620D01*
X653259Y38580D01*
X653274Y38535D01*
X653284Y38495D01*
X653299Y38455D01*
X653319Y38415D01*
X653334Y38380D01*
X653354Y38340D01*
X653454Y38200D01*
X653484Y38170D01*
Y36040D01*
X653494Y35915D01*
X653534Y35790D01*
X653594Y35680D01*
X653674Y35580D01*
X653774Y35500D01*
X653884Y35440D01*
X654009Y35400D01*
X654134Y35390D01*
G37*
G36*
G01X677756D02*
X677881Y35400D01*
X678006Y35440D01*
X678116Y35500D01*
X678216Y35580D01*
X678296Y35680D01*
X678356Y35790D01*
X678396Y35915D01*
X678406Y36040D01*
Y38165D01*
X678436Y38195D01*
X678461Y38230D01*
X678491Y38265D01*
X678511Y38300D01*
X678536Y38335D01*
X678576Y38415D01*
X678621Y38535D01*
X678631Y38575D01*
X678641Y38620D01*
X678646Y38660D01*
X678656Y38705D01*
Y38875D01*
X678646Y38920D01*
X678641Y38960D01*
X678631Y39005D01*
X678621Y39045D01*
X678576Y39165D01*
X678536Y39245D01*
X678511Y39280D01*
X678491Y39315D01*
X678461Y39350D01*
X678436Y39385D01*
X678406Y39415D01*
Y41840D01*
X678396Y41965D01*
X678356Y42090D01*
X678296Y42200D01*
X678216Y42300D01*
X678116Y42380D01*
X678006Y42440D01*
X677881Y42480D01*
X677756Y42490D01*
X677631Y42480D01*
X677506Y42440D01*
X677396Y42380D01*
X677296Y42300D01*
X677216Y42200D01*
X677156Y42090D01*
X677116Y41965D01*
X677106Y41840D01*
Y39410D01*
X677076Y39380D01*
X676976Y39240D01*
X676956Y39200D01*
X676941Y39165D01*
X676921Y39125D01*
X676906Y39085D01*
X676896Y39045D01*
X676881Y39000D01*
X676876Y38960D01*
X676866Y38920D01*
X676861Y38875D01*
Y38835D01*
X676856Y38790D01*
X676861Y38745D01*
Y38705D01*
X676866Y38660D01*
X676876Y38620D01*
X676881Y38580D01*
X676896Y38535D01*
X676906Y38495D01*
X676921Y38455D01*
X676941Y38415D01*
X676956Y38380D01*
X676976Y38340D01*
X677076Y38200D01*
X677106Y38170D01*
Y36040D01*
X677116Y35915D01*
X677156Y35790D01*
X677216Y35680D01*
X677296Y35580D01*
X677396Y35500D01*
X677506Y35440D01*
X677631Y35400D01*
X677756Y35390D01*
G37*
G36*
G01X673031D02*
X673156Y35400D01*
X673281Y35440D01*
X673391Y35500D01*
X673491Y35580D01*
X673571Y35680D01*
X673631Y35790D01*
X673671Y35915D01*
X673681Y36040D01*
Y38165D01*
X673711Y38195D01*
X673736Y38230D01*
X673766Y38265D01*
X673786Y38300D01*
X673811Y38335D01*
X673851Y38415D01*
X673896Y38535D01*
X673906Y38575D01*
X673916Y38620D01*
X673921Y38660D01*
X673931Y38705D01*
Y38875D01*
X673921Y38920D01*
X673916Y38960D01*
X673906Y39005D01*
X673896Y39045D01*
X673851Y39165D01*
X673811Y39245D01*
X673786Y39280D01*
X673766Y39315D01*
X673736Y39350D01*
X673711Y39385D01*
X673681Y39415D01*
Y41840D01*
X673671Y41965D01*
X673631Y42090D01*
X673571Y42200D01*
X673491Y42300D01*
X673391Y42380D01*
X673281Y42440D01*
X673156Y42480D01*
X673031Y42490D01*
X672906Y42480D01*
X672781Y42440D01*
X672671Y42380D01*
X672571Y42300D01*
X672491Y42200D01*
X672431Y42090D01*
X672391Y41965D01*
X672381Y41840D01*
Y39410D01*
X672351Y39380D01*
X672251Y39240D01*
X672231Y39200D01*
X672216Y39165D01*
X672196Y39125D01*
X672181Y39085D01*
X672171Y39045D01*
X672156Y39000D01*
X672151Y38960D01*
X672141Y38920D01*
X672136Y38875D01*
Y38835D01*
X672131Y38790D01*
X672136Y38745D01*
Y38705D01*
X672141Y38660D01*
X672151Y38620D01*
X672156Y38580D01*
X672171Y38535D01*
X672181Y38495D01*
X672196Y38455D01*
X672216Y38415D01*
X672231Y38380D01*
X672251Y38340D01*
X672351Y38200D01*
X672381Y38170D01*
Y36040D01*
X672391Y35915D01*
X672431Y35790D01*
X672491Y35680D01*
X672571Y35580D01*
X672671Y35500D01*
X672781Y35440D01*
X672906Y35400D01*
X673031Y35390D01*
G37*
G36*
G01X668307D02*
X668432Y35400D01*
X668557Y35440D01*
X668667Y35500D01*
X668767Y35580D01*
X668847Y35680D01*
X668907Y35790D01*
X668947Y35915D01*
X668957Y36040D01*
Y38165D01*
X668987Y38195D01*
X669012Y38230D01*
X669042Y38265D01*
X669062Y38300D01*
X669087Y38335D01*
X669127Y38415D01*
X669172Y38535D01*
X669182Y38575D01*
X669192Y38620D01*
X669197Y38660D01*
X669207Y38705D01*
Y38875D01*
X669197Y38920D01*
X669192Y38960D01*
X669182Y39005D01*
X669172Y39045D01*
X669127Y39165D01*
X669087Y39245D01*
X669062Y39280D01*
X669042Y39315D01*
X669012Y39350D01*
X668987Y39385D01*
X668957Y39415D01*
Y41840D01*
X668947Y41965D01*
X668907Y42090D01*
X668847Y42200D01*
X668767Y42300D01*
X668667Y42380D01*
X668557Y42440D01*
X668432Y42480D01*
X668307Y42490D01*
X668182Y42480D01*
X668057Y42440D01*
X667947Y42380D01*
X667847Y42300D01*
X667767Y42200D01*
X667707Y42090D01*
X667667Y41965D01*
X667657Y41840D01*
Y39410D01*
X667627Y39380D01*
X667527Y39240D01*
X667507Y39200D01*
X667492Y39165D01*
X667472Y39125D01*
X667457Y39085D01*
X667447Y39045D01*
X667432Y39000D01*
X667427Y38960D01*
X667417Y38920D01*
X667412Y38875D01*
Y38835D01*
X667407Y38790D01*
X667412Y38745D01*
Y38705D01*
X667417Y38660D01*
X667427Y38620D01*
X667432Y38580D01*
X667447Y38535D01*
X667457Y38495D01*
X667472Y38455D01*
X667492Y38415D01*
X667507Y38380D01*
X667527Y38340D01*
X667627Y38200D01*
X667657Y38170D01*
Y36040D01*
X667667Y35915D01*
X667707Y35790D01*
X667767Y35680D01*
X667847Y35580D01*
X667947Y35500D01*
X668057Y35440D01*
X668182Y35400D01*
X668307Y35390D01*
G37*
G36*
G01X691929D02*
X692054Y35400D01*
X692179Y35440D01*
X692289Y35500D01*
X692389Y35580D01*
X692469Y35680D01*
X692529Y35790D01*
X692569Y35915D01*
X692579Y36040D01*
Y38165D01*
X692609Y38195D01*
X692634Y38230D01*
X692664Y38265D01*
X692684Y38300D01*
X692709Y38335D01*
X692749Y38415D01*
X692794Y38535D01*
X692804Y38575D01*
X692814Y38620D01*
X692819Y38660D01*
X692829Y38705D01*
Y38875D01*
X692819Y38920D01*
X692814Y38960D01*
X692804Y39005D01*
X692794Y39045D01*
X692749Y39165D01*
X692709Y39245D01*
X692684Y39280D01*
X692664Y39315D01*
X692634Y39350D01*
X692609Y39385D01*
X692579Y39415D01*
Y41840D01*
X692569Y41965D01*
X692529Y42090D01*
X692469Y42200D01*
X692389Y42300D01*
X692289Y42380D01*
X692179Y42440D01*
X692054Y42480D01*
X691929Y42490D01*
X691804Y42480D01*
X691679Y42440D01*
X691569Y42380D01*
X691469Y42300D01*
X691389Y42200D01*
X691329Y42090D01*
X691289Y41965D01*
X691279Y41840D01*
Y39410D01*
X691249Y39380D01*
X691149Y39240D01*
X691129Y39200D01*
X691114Y39165D01*
X691094Y39125D01*
X691079Y39085D01*
X691069Y39045D01*
X691054Y39000D01*
X691049Y38960D01*
X691039Y38920D01*
X691034Y38875D01*
Y38835D01*
X691029Y38790D01*
X691034Y38745D01*
Y38705D01*
X691039Y38660D01*
X691049Y38620D01*
X691054Y38580D01*
X691069Y38535D01*
X691079Y38495D01*
X691094Y38455D01*
X691114Y38415D01*
X691129Y38380D01*
X691149Y38340D01*
X691249Y38200D01*
X691279Y38170D01*
Y36040D01*
X691289Y35915D01*
X691329Y35790D01*
X691389Y35680D01*
X691469Y35580D01*
X691569Y35500D01*
X691679Y35440D01*
X691804Y35400D01*
X691929Y35390D01*
G37*
G36*
G01X687204D02*
X687329Y35400D01*
X687454Y35440D01*
X687564Y35500D01*
X687664Y35580D01*
X687744Y35680D01*
X687804Y35790D01*
X687844Y35915D01*
X687854Y36040D01*
Y38165D01*
X687884Y38195D01*
X687909Y38230D01*
X687939Y38265D01*
X687959Y38300D01*
X687984Y38335D01*
X688024Y38415D01*
X688069Y38535D01*
X688079Y38575D01*
X688089Y38620D01*
X688094Y38660D01*
X688104Y38705D01*
Y38875D01*
X688094Y38920D01*
X688089Y38960D01*
X688079Y39005D01*
X688069Y39045D01*
X688024Y39165D01*
X687984Y39245D01*
X687959Y39280D01*
X687939Y39315D01*
X687909Y39350D01*
X687884Y39385D01*
X687854Y39415D01*
Y41840D01*
X687844Y41965D01*
X687804Y42090D01*
X687744Y42200D01*
X687664Y42300D01*
X687564Y42380D01*
X687454Y42440D01*
X687329Y42480D01*
X687204Y42490D01*
X687079Y42480D01*
X686954Y42440D01*
X686844Y42380D01*
X686744Y42300D01*
X686664Y42200D01*
X686604Y42090D01*
X686564Y41965D01*
X686554Y41840D01*
Y39410D01*
X686524Y39380D01*
X686424Y39240D01*
X686404Y39200D01*
X686389Y39165D01*
X686369Y39125D01*
X686354Y39085D01*
X686344Y39045D01*
X686329Y39000D01*
X686324Y38960D01*
X686314Y38920D01*
X686309Y38875D01*
Y38835D01*
X686304Y38790D01*
X686309Y38745D01*
Y38705D01*
X686314Y38660D01*
X686324Y38620D01*
X686329Y38580D01*
X686344Y38535D01*
X686354Y38495D01*
X686369Y38455D01*
X686389Y38415D01*
X686404Y38380D01*
X686424Y38340D01*
X686524Y38200D01*
X686554Y38170D01*
Y36040D01*
X686564Y35915D01*
X686604Y35790D01*
X686664Y35680D01*
X686744Y35580D01*
X686844Y35500D01*
X686954Y35440D01*
X687079Y35400D01*
X687204Y35390D01*
G37*
G36*
G01X682480D02*
X682605Y35400D01*
X682730Y35440D01*
X682840Y35500D01*
X682940Y35580D01*
X683020Y35680D01*
X683080Y35790D01*
X683120Y35915D01*
X683130Y36040D01*
Y38165D01*
X683160Y38195D01*
X683185Y38230D01*
X683215Y38265D01*
X683235Y38300D01*
X683260Y38335D01*
X683300Y38415D01*
X683345Y38535D01*
X683355Y38575D01*
X683365Y38620D01*
X683370Y38660D01*
X683380Y38705D01*
Y38875D01*
X683370Y38920D01*
X683365Y38960D01*
X683355Y39005D01*
X683345Y39045D01*
X683300Y39165D01*
X683260Y39245D01*
X683235Y39280D01*
X683215Y39315D01*
X683185Y39350D01*
X683160Y39385D01*
X683130Y39415D01*
Y41840D01*
X683120Y41965D01*
X683080Y42090D01*
X683020Y42200D01*
X682940Y42300D01*
X682840Y42380D01*
X682730Y42440D01*
X682605Y42480D01*
X682480Y42490D01*
X682355Y42480D01*
X682230Y42440D01*
X682120Y42380D01*
X682020Y42300D01*
X681940Y42200D01*
X681880Y42090D01*
X681840Y41965D01*
X681830Y41840D01*
Y39410D01*
X681800Y39380D01*
X681700Y39240D01*
X681680Y39200D01*
X681665Y39165D01*
X681645Y39125D01*
X681630Y39085D01*
X681620Y39045D01*
X681605Y39000D01*
X681600Y38960D01*
X681590Y38920D01*
X681585Y38875D01*
Y38835D01*
X681580Y38790D01*
X681585Y38745D01*
Y38705D01*
X681590Y38660D01*
X681600Y38620D01*
X681605Y38580D01*
X681620Y38535D01*
X681630Y38495D01*
X681645Y38455D01*
X681665Y38415D01*
X681680Y38380D01*
X681700Y38340D01*
X681800Y38200D01*
X681830Y38170D01*
Y36040D01*
X681840Y35915D01*
X681880Y35790D01*
X681940Y35680D01*
X682020Y35580D01*
X682120Y35500D01*
X682230Y35440D01*
X682355Y35400D01*
X682480Y35390D01*
G37*
G36*
G01X710827D02*
X710952Y35400D01*
X711077Y35440D01*
X711187Y35500D01*
X711287Y35580D01*
X711367Y35680D01*
X711427Y35790D01*
X711467Y35915D01*
X711477Y36040D01*
Y38165D01*
X711507Y38195D01*
X711532Y38230D01*
X711562Y38265D01*
X711582Y38300D01*
X711607Y38335D01*
X711647Y38415D01*
X711692Y38535D01*
X711702Y38575D01*
X711712Y38620D01*
X711717Y38660D01*
X711727Y38705D01*
Y38875D01*
X711717Y38920D01*
X711712Y38960D01*
X711702Y39005D01*
X711692Y39045D01*
X711647Y39165D01*
X711607Y39245D01*
X711582Y39280D01*
X711562Y39315D01*
X711532Y39350D01*
X711507Y39385D01*
X711477Y39415D01*
Y41840D01*
X711467Y41965D01*
X711427Y42090D01*
X711367Y42200D01*
X711287Y42300D01*
X711187Y42380D01*
X711077Y42440D01*
X710952Y42480D01*
X710827Y42490D01*
X710702Y42480D01*
X710577Y42440D01*
X710467Y42380D01*
X710367Y42300D01*
X710287Y42200D01*
X710227Y42090D01*
X710187Y41965D01*
X710177Y41840D01*
Y39410D01*
X710147Y39380D01*
X710047Y39240D01*
X710027Y39200D01*
X710012Y39165D01*
X709992Y39125D01*
X709977Y39085D01*
X709967Y39045D01*
X709952Y39000D01*
X709947Y38960D01*
X709937Y38920D01*
X709932Y38875D01*
Y38835D01*
X709927Y38790D01*
X709932Y38745D01*
Y38705D01*
X709937Y38660D01*
X709947Y38620D01*
X709952Y38580D01*
X709967Y38535D01*
X709977Y38495D01*
X709992Y38455D01*
X710012Y38415D01*
X710027Y38380D01*
X710047Y38340D01*
X710147Y38200D01*
X710177Y38170D01*
Y36040D01*
X710187Y35915D01*
X710227Y35790D01*
X710287Y35680D01*
X710367Y35580D01*
X710467Y35500D01*
X710577Y35440D01*
X710702Y35400D01*
X710827Y35390D01*
G37*
G36*
G01X706102D02*
X706227Y35400D01*
X706352Y35440D01*
X706462Y35500D01*
X706562Y35580D01*
X706642Y35680D01*
X706702Y35790D01*
X706742Y35915D01*
X706752Y36040D01*
Y38165D01*
X706782Y38195D01*
X706807Y38230D01*
X706837Y38265D01*
X706857Y38300D01*
X706882Y38335D01*
X706922Y38415D01*
X706967Y38535D01*
X706977Y38575D01*
X706987Y38620D01*
X706992Y38660D01*
X707002Y38705D01*
Y38875D01*
X706992Y38920D01*
X706987Y38960D01*
X706977Y39005D01*
X706967Y39045D01*
X706922Y39165D01*
X706882Y39245D01*
X706857Y39280D01*
X706837Y39315D01*
X706807Y39350D01*
X706782Y39385D01*
X706752Y39415D01*
Y41840D01*
X706742Y41965D01*
X706702Y42090D01*
X706642Y42200D01*
X706562Y42300D01*
X706462Y42380D01*
X706352Y42440D01*
X706227Y42480D01*
X706102Y42490D01*
X705977Y42480D01*
X705852Y42440D01*
X705742Y42380D01*
X705642Y42300D01*
X705562Y42200D01*
X705502Y42090D01*
X705462Y41965D01*
X705452Y41840D01*
Y39410D01*
X705422Y39380D01*
X705322Y39240D01*
X705302Y39200D01*
X705287Y39165D01*
X705267Y39125D01*
X705252Y39085D01*
X705242Y39045D01*
X705227Y39000D01*
X705222Y38960D01*
X705212Y38920D01*
X705207Y38875D01*
Y38835D01*
X705202Y38790D01*
X705207Y38745D01*
Y38705D01*
X705212Y38660D01*
X705222Y38620D01*
X705227Y38580D01*
X705242Y38535D01*
X705252Y38495D01*
X705267Y38455D01*
X705287Y38415D01*
X705302Y38380D01*
X705322Y38340D01*
X705422Y38200D01*
X705452Y38170D01*
Y36040D01*
X705462Y35915D01*
X705502Y35790D01*
X705562Y35680D01*
X705642Y35580D01*
X705742Y35500D01*
X705852Y35440D01*
X705977Y35400D01*
X706102Y35390D01*
G37*
G36*
G01X701378D02*
X701503Y35400D01*
X701628Y35440D01*
X701738Y35500D01*
X701838Y35580D01*
X701918Y35680D01*
X701978Y35790D01*
X702018Y35915D01*
X702028Y36040D01*
Y38165D01*
X702058Y38195D01*
X702083Y38230D01*
X702113Y38265D01*
X702133Y38300D01*
X702158Y38335D01*
X702198Y38415D01*
X702243Y38535D01*
X702253Y38575D01*
X702263Y38620D01*
X702268Y38660D01*
X702278Y38705D01*
Y38875D01*
X702268Y38920D01*
X702263Y38960D01*
X702253Y39005D01*
X702243Y39045D01*
X702198Y39165D01*
X702158Y39245D01*
X702133Y39280D01*
X702113Y39315D01*
X702083Y39350D01*
X702058Y39385D01*
X702028Y39415D01*
Y41840D01*
X702018Y41965D01*
X701978Y42090D01*
X701918Y42200D01*
X701838Y42300D01*
X701738Y42380D01*
X701628Y42440D01*
X701503Y42480D01*
X701378Y42490D01*
X701253Y42480D01*
X701128Y42440D01*
X701018Y42380D01*
X700918Y42300D01*
X700838Y42200D01*
X700778Y42090D01*
X700738Y41965D01*
X700728Y41840D01*
Y39410D01*
X700698Y39380D01*
X700598Y39240D01*
X700578Y39200D01*
X700563Y39165D01*
X700543Y39125D01*
X700528Y39085D01*
X700518Y39045D01*
X700503Y39000D01*
X700498Y38960D01*
X700488Y38920D01*
X700483Y38875D01*
Y38835D01*
X700478Y38790D01*
X700483Y38745D01*
Y38705D01*
X700488Y38660D01*
X700498Y38620D01*
X700503Y38580D01*
X700518Y38535D01*
X700528Y38495D01*
X700543Y38455D01*
X700563Y38415D01*
X700578Y38380D01*
X700598Y38340D01*
X700698Y38200D01*
X700728Y38170D01*
Y36040D01*
X700738Y35915D01*
X700778Y35790D01*
X700838Y35680D01*
X700918Y35580D01*
X701018Y35500D01*
X701128Y35440D01*
X701253Y35400D01*
X701378Y35390D01*
G37*
G36*
G01X696653D02*
X696778Y35400D01*
X696903Y35440D01*
X697013Y35500D01*
X697113Y35580D01*
X697193Y35680D01*
X697253Y35790D01*
X697293Y35915D01*
X697303Y36040D01*
Y38165D01*
X697333Y38195D01*
X697358Y38230D01*
X697388Y38265D01*
X697408Y38300D01*
X697433Y38335D01*
X697473Y38415D01*
X697518Y38535D01*
X697528Y38575D01*
X697538Y38620D01*
X697543Y38660D01*
X697553Y38705D01*
Y38875D01*
X697543Y38920D01*
X697538Y38960D01*
X697528Y39005D01*
X697518Y39045D01*
X697473Y39165D01*
X697433Y39245D01*
X697408Y39280D01*
X697388Y39315D01*
X697358Y39350D01*
X697333Y39385D01*
X697303Y39415D01*
Y41840D01*
X697293Y41965D01*
X697253Y42090D01*
X697193Y42200D01*
X697113Y42300D01*
X697013Y42380D01*
X696903Y42440D01*
X696778Y42480D01*
X696653Y42490D01*
X696528Y42480D01*
X696403Y42440D01*
X696293Y42380D01*
X696193Y42300D01*
X696113Y42200D01*
X696053Y42090D01*
X696013Y41965D01*
X696003Y41840D01*
Y39410D01*
X695973Y39380D01*
X695873Y39240D01*
X695853Y39200D01*
X695838Y39165D01*
X695818Y39125D01*
X695803Y39085D01*
X695793Y39045D01*
X695778Y39000D01*
X695773Y38960D01*
X695763Y38920D01*
X695758Y38875D01*
Y38835D01*
X695753Y38790D01*
X695758Y38745D01*
Y38705D01*
X695763Y38660D01*
X695773Y38620D01*
X695778Y38580D01*
X695793Y38535D01*
X695803Y38495D01*
X695818Y38455D01*
X695838Y38415D01*
X695853Y38380D01*
X695873Y38340D01*
X695973Y38200D01*
X696003Y38170D01*
Y36040D01*
X696013Y35915D01*
X696053Y35790D01*
X696113Y35680D01*
X696193Y35580D01*
X696293Y35500D01*
X696403Y35440D01*
X696528Y35400D01*
X696653Y35390D01*
G37*
G36*
G01X725000D02*
X725125Y35400D01*
X725250Y35440D01*
X725360Y35500D01*
X725460Y35580D01*
X725540Y35680D01*
X725600Y35790D01*
X725640Y35915D01*
X725650Y36040D01*
Y38165D01*
X725680Y38195D01*
X725705Y38230D01*
X725735Y38265D01*
X725755Y38300D01*
X725780Y38335D01*
X725820Y38415D01*
X725865Y38535D01*
X725875Y38575D01*
X725885Y38620D01*
X725890Y38660D01*
X725900Y38705D01*
Y38875D01*
X725890Y38920D01*
X725885Y38960D01*
X725875Y39005D01*
X725865Y39045D01*
X725820Y39165D01*
X725780Y39245D01*
X725755Y39280D01*
X725735Y39315D01*
X725705Y39350D01*
X725680Y39385D01*
X725650Y39415D01*
Y41840D01*
X725640Y41965D01*
X725600Y42090D01*
X725540Y42200D01*
X725460Y42300D01*
X725360Y42380D01*
X725250Y42440D01*
X725125Y42480D01*
X725000Y42490D01*
X724875Y42480D01*
X724750Y42440D01*
X724640Y42380D01*
X724540Y42300D01*
X724460Y42200D01*
X724400Y42090D01*
X724360Y41965D01*
X724350Y41840D01*
Y39410D01*
X724320Y39380D01*
X724220Y39240D01*
X724200Y39200D01*
X724185Y39165D01*
X724165Y39125D01*
X724150Y39085D01*
X724140Y39045D01*
X724125Y39000D01*
X724120Y38960D01*
X724110Y38920D01*
X724105Y38875D01*
Y38835D01*
X724100Y38790D01*
X724105Y38745D01*
Y38705D01*
X724110Y38660D01*
X724120Y38620D01*
X724125Y38580D01*
X724140Y38535D01*
X724150Y38495D01*
X724165Y38455D01*
X724185Y38415D01*
X724200Y38380D01*
X724220Y38340D01*
X724320Y38200D01*
X724350Y38170D01*
Y36040D01*
X724360Y35915D01*
X724400Y35790D01*
X724460Y35680D01*
X724540Y35580D01*
X724640Y35500D01*
X724750Y35440D01*
X724875Y35400D01*
X725000Y35390D01*
G37*
G36*
G01X720275D02*
X720400Y35400D01*
X720525Y35440D01*
X720635Y35500D01*
X720735Y35580D01*
X720815Y35680D01*
X720875Y35790D01*
X720915Y35915D01*
X720925Y36040D01*
Y38165D01*
X720955Y38195D01*
X720980Y38230D01*
X721010Y38265D01*
X721030Y38300D01*
X721055Y38335D01*
X721095Y38415D01*
X721140Y38535D01*
X721150Y38575D01*
X721160Y38620D01*
X721165Y38660D01*
X721175Y38705D01*
Y38875D01*
X721165Y38920D01*
X721160Y38960D01*
X721150Y39005D01*
X721140Y39045D01*
X721095Y39165D01*
X721055Y39245D01*
X721030Y39280D01*
X721010Y39315D01*
X720980Y39350D01*
X720955Y39385D01*
X720925Y39415D01*
Y41840D01*
X720915Y41965D01*
X720875Y42090D01*
X720815Y42200D01*
X720735Y42300D01*
X720635Y42380D01*
X720525Y42440D01*
X720400Y42480D01*
X720275Y42490D01*
X720150Y42480D01*
X720025Y42440D01*
X719915Y42380D01*
X719815Y42300D01*
X719735Y42200D01*
X719675Y42090D01*
X719635Y41965D01*
X719625Y41840D01*
Y39410D01*
X719595Y39380D01*
X719495Y39240D01*
X719475Y39200D01*
X719460Y39165D01*
X719440Y39125D01*
X719425Y39085D01*
X719415Y39045D01*
X719400Y39000D01*
X719395Y38960D01*
X719385Y38920D01*
X719380Y38875D01*
Y38835D01*
X719375Y38790D01*
X719380Y38745D01*
Y38705D01*
X719385Y38660D01*
X719395Y38620D01*
X719400Y38580D01*
X719415Y38535D01*
X719425Y38495D01*
X719440Y38455D01*
X719460Y38415D01*
X719475Y38380D01*
X719495Y38340D01*
X719595Y38200D01*
X719625Y38170D01*
Y36040D01*
X719635Y35915D01*
X719675Y35790D01*
X719735Y35680D01*
X719815Y35580D01*
X719915Y35500D01*
X720025Y35440D01*
X720150Y35400D01*
X720275Y35390D01*
G37*
G36*
G01X715551D02*
X715676Y35400D01*
X715801Y35440D01*
X715911Y35500D01*
X716011Y35580D01*
X716091Y35680D01*
X716151Y35790D01*
X716191Y35915D01*
X716201Y36040D01*
Y38165D01*
X716231Y38195D01*
X716256Y38230D01*
X716286Y38265D01*
X716306Y38300D01*
X716331Y38335D01*
X716371Y38415D01*
X716416Y38535D01*
X716426Y38575D01*
X716436Y38620D01*
X716441Y38660D01*
X716451Y38705D01*
Y38875D01*
X716441Y38920D01*
X716436Y38960D01*
X716426Y39005D01*
X716416Y39045D01*
X716371Y39165D01*
X716331Y39245D01*
X716306Y39280D01*
X716286Y39315D01*
X716256Y39350D01*
X716231Y39385D01*
X716201Y39415D01*
Y41840D01*
X716191Y41965D01*
X716151Y42090D01*
X716091Y42200D01*
X716011Y42300D01*
X715911Y42380D01*
X715801Y42440D01*
X715676Y42480D01*
X715551Y42490D01*
X715426Y42480D01*
X715301Y42440D01*
X715191Y42380D01*
X715091Y42300D01*
X715011Y42200D01*
X714951Y42090D01*
X714911Y41965D01*
X714901Y41840D01*
Y39410D01*
X714871Y39380D01*
X714771Y39240D01*
X714751Y39200D01*
X714736Y39165D01*
X714716Y39125D01*
X714701Y39085D01*
X714691Y39045D01*
X714676Y39000D01*
X714671Y38960D01*
X714661Y38920D01*
X714656Y38875D01*
Y38835D01*
X714651Y38790D01*
X714656Y38745D01*
Y38705D01*
X714661Y38660D01*
X714671Y38620D01*
X714676Y38580D01*
X714691Y38535D01*
X714701Y38495D01*
X714716Y38455D01*
X714736Y38415D01*
X714751Y38380D01*
X714771Y38340D01*
X714871Y38200D01*
X714901Y38170D01*
Y36040D01*
X714911Y35915D01*
X714951Y35790D01*
X715011Y35680D01*
X715091Y35580D01*
X715191Y35500D01*
X715301Y35440D01*
X715426Y35400D01*
X715551Y35390D01*
G37*
G36*
G01X739173D02*
X739298Y35400D01*
X739423Y35440D01*
X739533Y35500D01*
X739633Y35580D01*
X739713Y35680D01*
X739773Y35790D01*
X739813Y35915D01*
X739823Y36040D01*
Y38165D01*
X739853Y38195D01*
X739878Y38230D01*
X739908Y38265D01*
X739928Y38300D01*
X739953Y38335D01*
X739993Y38415D01*
X740038Y38535D01*
X740048Y38575D01*
X740058Y38620D01*
X740063Y38660D01*
X740073Y38705D01*
Y38875D01*
X740063Y38920D01*
X740058Y38960D01*
X740048Y39005D01*
X740038Y39045D01*
X739993Y39165D01*
X739953Y39245D01*
X739928Y39280D01*
X739908Y39315D01*
X739878Y39350D01*
X739853Y39385D01*
X739823Y39415D01*
Y41840D01*
X739813Y41965D01*
X739773Y42090D01*
X739713Y42200D01*
X739633Y42300D01*
X739533Y42380D01*
X739423Y42440D01*
X739298Y42480D01*
X739173Y42490D01*
X739048Y42480D01*
X738923Y42440D01*
X738813Y42380D01*
X738713Y42300D01*
X738633Y42200D01*
X738573Y42090D01*
X738533Y41965D01*
X738523Y41840D01*
Y39410D01*
X738493Y39380D01*
X738393Y39240D01*
X738373Y39200D01*
X738358Y39165D01*
X738338Y39125D01*
X738323Y39085D01*
X738313Y39045D01*
X738298Y39000D01*
X738293Y38960D01*
X738283Y38920D01*
X738278Y38875D01*
Y38835D01*
X738273Y38790D01*
X738278Y38745D01*
Y38705D01*
X738283Y38660D01*
X738293Y38620D01*
X738298Y38580D01*
X738313Y38535D01*
X738323Y38495D01*
X738338Y38455D01*
X738358Y38415D01*
X738373Y38380D01*
X738393Y38340D01*
X738493Y38200D01*
X738523Y38170D01*
Y36040D01*
X738533Y35915D01*
X738573Y35790D01*
X738633Y35680D01*
X738713Y35580D01*
X738813Y35500D01*
X738923Y35440D01*
X739048Y35400D01*
X739173Y35390D01*
G37*
G36*
G01X734449D02*
X734574Y35400D01*
X734699Y35440D01*
X734809Y35500D01*
X734909Y35580D01*
X734989Y35680D01*
X735049Y35790D01*
X735089Y35915D01*
X735099Y36040D01*
Y38165D01*
X735129Y38195D01*
X735154Y38230D01*
X735184Y38265D01*
X735204Y38300D01*
X735229Y38335D01*
X735269Y38415D01*
X735314Y38535D01*
X735324Y38575D01*
X735334Y38620D01*
X735339Y38660D01*
X735349Y38705D01*
Y38875D01*
X735339Y38920D01*
X735334Y38960D01*
X735324Y39005D01*
X735314Y39045D01*
X735269Y39165D01*
X735229Y39245D01*
X735204Y39280D01*
X735184Y39315D01*
X735154Y39350D01*
X735129Y39385D01*
X735099Y39415D01*
Y41840D01*
X735089Y41965D01*
X735049Y42090D01*
X734989Y42200D01*
X734909Y42300D01*
X734809Y42380D01*
X734699Y42440D01*
X734574Y42480D01*
X734449Y42490D01*
X734324Y42480D01*
X734199Y42440D01*
X734089Y42380D01*
X733989Y42300D01*
X733909Y42200D01*
X733849Y42090D01*
X733809Y41965D01*
X733799Y41840D01*
Y39410D01*
X733769Y39380D01*
X733669Y39240D01*
X733649Y39200D01*
X733634Y39165D01*
X733614Y39125D01*
X733599Y39085D01*
X733589Y39045D01*
X733574Y39000D01*
X733569Y38960D01*
X733559Y38920D01*
X733554Y38875D01*
Y38835D01*
X733549Y38790D01*
X733554Y38745D01*
Y38705D01*
X733559Y38660D01*
X733569Y38620D01*
X733574Y38580D01*
X733589Y38535D01*
X733599Y38495D01*
X733614Y38455D01*
X733634Y38415D01*
X733649Y38380D01*
X733669Y38340D01*
X733769Y38200D01*
X733799Y38170D01*
Y36040D01*
X733809Y35915D01*
X733849Y35790D01*
X733909Y35680D01*
X733989Y35580D01*
X734089Y35500D01*
X734199Y35440D01*
X734324Y35400D01*
X734449Y35390D01*
G37*
G36*
G01X729724D02*
X729849Y35400D01*
X729974Y35440D01*
X730084Y35500D01*
X730184Y35580D01*
X730264Y35680D01*
X730324Y35790D01*
X730364Y35915D01*
X730374Y36040D01*
Y38165D01*
X730404Y38195D01*
X730429Y38230D01*
X730459Y38265D01*
X730479Y38300D01*
X730504Y38335D01*
X730544Y38415D01*
X730589Y38535D01*
X730599Y38575D01*
X730609Y38620D01*
X730614Y38660D01*
X730624Y38705D01*
Y38875D01*
X730614Y38920D01*
X730609Y38960D01*
X730599Y39005D01*
X730589Y39045D01*
X730544Y39165D01*
X730504Y39245D01*
X730479Y39280D01*
X730459Y39315D01*
X730429Y39350D01*
X730404Y39385D01*
X730374Y39415D01*
Y41840D01*
X730364Y41965D01*
X730324Y42090D01*
X730264Y42200D01*
X730184Y42300D01*
X730084Y42380D01*
X729974Y42440D01*
X729849Y42480D01*
X729724Y42490D01*
X729599Y42480D01*
X729474Y42440D01*
X729364Y42380D01*
X729264Y42300D01*
X729184Y42200D01*
X729124Y42090D01*
X729084Y41965D01*
X729074Y41840D01*
Y39410D01*
X729044Y39380D01*
X728944Y39240D01*
X728924Y39200D01*
X728909Y39165D01*
X728889Y39125D01*
X728874Y39085D01*
X728864Y39045D01*
X728849Y39000D01*
X728844Y38960D01*
X728834Y38920D01*
X728829Y38875D01*
Y38835D01*
X728824Y38790D01*
X728829Y38745D01*
Y38705D01*
X728834Y38660D01*
X728844Y38620D01*
X728849Y38580D01*
X728864Y38535D01*
X728874Y38495D01*
X728889Y38455D01*
X728909Y38415D01*
X728924Y38380D01*
X728944Y38340D01*
X729044Y38200D01*
X729074Y38170D01*
Y36040D01*
X729084Y35915D01*
X729124Y35790D01*
X729184Y35680D01*
X729264Y35580D01*
X729364Y35500D01*
X729474Y35440D01*
X729599Y35400D01*
X729724Y35390D01*
G37*
G36*
G01X753346D02*
X753471Y35400D01*
X753596Y35440D01*
X753706Y35500D01*
X753806Y35580D01*
X753886Y35680D01*
X753946Y35790D01*
X753986Y35915D01*
X753996Y36040D01*
Y38165D01*
X754026Y38195D01*
X754051Y38230D01*
X754081Y38265D01*
X754101Y38300D01*
X754126Y38335D01*
X754166Y38415D01*
X754211Y38535D01*
X754221Y38575D01*
X754231Y38620D01*
X754236Y38660D01*
X754246Y38705D01*
Y38875D01*
X754236Y38920D01*
X754231Y38960D01*
X754221Y39005D01*
X754211Y39045D01*
X754166Y39165D01*
X754126Y39245D01*
X754101Y39280D01*
X754081Y39315D01*
X754051Y39350D01*
X754026Y39385D01*
X753996Y39415D01*
Y41840D01*
X753986Y41965D01*
X753946Y42090D01*
X753886Y42200D01*
X753806Y42300D01*
X753706Y42380D01*
X753596Y42440D01*
X753471Y42480D01*
X753346Y42490D01*
X753221Y42480D01*
X753096Y42440D01*
X752986Y42380D01*
X752886Y42300D01*
X752806Y42200D01*
X752746Y42090D01*
X752706Y41965D01*
X752696Y41840D01*
Y39410D01*
X752666Y39380D01*
X752566Y39240D01*
X752546Y39200D01*
X752531Y39165D01*
X752511Y39125D01*
X752496Y39085D01*
X752486Y39045D01*
X752471Y39000D01*
X752466Y38960D01*
X752456Y38920D01*
X752451Y38875D01*
Y38835D01*
X752446Y38790D01*
X752451Y38745D01*
Y38705D01*
X752456Y38660D01*
X752466Y38620D01*
X752471Y38580D01*
X752486Y38535D01*
X752496Y38495D01*
X752511Y38455D01*
X752531Y38415D01*
X752546Y38380D01*
X752566Y38340D01*
X752666Y38200D01*
X752696Y38170D01*
Y36040D01*
X752706Y35915D01*
X752746Y35790D01*
X752806Y35680D01*
X752886Y35580D01*
X752986Y35500D01*
X753096Y35440D01*
X753221Y35400D01*
X753346Y35390D01*
G37*
G36*
G01X748622D02*
X748747Y35400D01*
X748872Y35440D01*
X748982Y35500D01*
X749082Y35580D01*
X749162Y35680D01*
X749222Y35790D01*
X749262Y35915D01*
X749272Y36040D01*
Y38165D01*
X749302Y38195D01*
X749327Y38230D01*
X749357Y38265D01*
X749377Y38300D01*
X749402Y38335D01*
X749442Y38415D01*
X749487Y38535D01*
X749497Y38575D01*
X749507Y38620D01*
X749512Y38660D01*
X749522Y38705D01*
Y38875D01*
X749512Y38920D01*
X749507Y38960D01*
X749497Y39005D01*
X749487Y39045D01*
X749442Y39165D01*
X749402Y39245D01*
X749377Y39280D01*
X749357Y39315D01*
X749327Y39350D01*
X749302Y39385D01*
X749272Y39415D01*
Y41840D01*
X749262Y41965D01*
X749222Y42090D01*
X749162Y42200D01*
X749082Y42300D01*
X748982Y42380D01*
X748872Y42440D01*
X748747Y42480D01*
X748622Y42490D01*
X748497Y42480D01*
X748372Y42440D01*
X748262Y42380D01*
X748162Y42300D01*
X748082Y42200D01*
X748022Y42090D01*
X747982Y41965D01*
X747972Y41840D01*
Y39410D01*
X747942Y39380D01*
X747842Y39240D01*
X747822Y39200D01*
X747807Y39165D01*
X747787Y39125D01*
X747772Y39085D01*
X747762Y39045D01*
X747747Y39000D01*
X747742Y38960D01*
X747732Y38920D01*
X747727Y38875D01*
Y38835D01*
X747722Y38790D01*
X747727Y38745D01*
Y38705D01*
X747732Y38660D01*
X747742Y38620D01*
X747747Y38580D01*
X747762Y38535D01*
X747772Y38495D01*
X747787Y38455D01*
X747807Y38415D01*
X747822Y38380D01*
X747842Y38340D01*
X747942Y38200D01*
X747972Y38170D01*
Y36040D01*
X747982Y35915D01*
X748022Y35790D01*
X748082Y35680D01*
X748162Y35580D01*
X748262Y35500D01*
X748372Y35440D01*
X748497Y35400D01*
X748622Y35390D01*
G37*
G36*
G01X743897D02*
X744022Y35400D01*
X744147Y35440D01*
X744257Y35500D01*
X744357Y35580D01*
X744437Y35680D01*
X744497Y35790D01*
X744537Y35915D01*
X744547Y36040D01*
Y38165D01*
X744577Y38195D01*
X744602Y38230D01*
X744632Y38265D01*
X744652Y38300D01*
X744677Y38335D01*
X744717Y38415D01*
X744762Y38535D01*
X744772Y38575D01*
X744782Y38620D01*
X744787Y38660D01*
X744797Y38705D01*
Y38875D01*
X744787Y38920D01*
X744782Y38960D01*
X744772Y39005D01*
X744762Y39045D01*
X744717Y39165D01*
X744677Y39245D01*
X744652Y39280D01*
X744632Y39315D01*
X744602Y39350D01*
X744577Y39385D01*
X744547Y39415D01*
Y41840D01*
X744537Y41965D01*
X744497Y42090D01*
X744437Y42200D01*
X744357Y42300D01*
X744257Y42380D01*
X744147Y42440D01*
X744022Y42480D01*
X743897Y42490D01*
X743772Y42480D01*
X743647Y42440D01*
X743537Y42380D01*
X743437Y42300D01*
X743357Y42200D01*
X743297Y42090D01*
X743257Y41965D01*
X743247Y41840D01*
Y39410D01*
X743217Y39380D01*
X743117Y39240D01*
X743097Y39200D01*
X743082Y39165D01*
X743062Y39125D01*
X743047Y39085D01*
X743037Y39045D01*
X743022Y39000D01*
X743017Y38960D01*
X743007Y38920D01*
X743002Y38875D01*
Y38835D01*
X742997Y38790D01*
X743002Y38745D01*
Y38705D01*
X743007Y38660D01*
X743017Y38620D01*
X743022Y38580D01*
X743037Y38535D01*
X743047Y38495D01*
X743062Y38455D01*
X743082Y38415D01*
X743097Y38380D01*
X743117Y38340D01*
X743217Y38200D01*
X743247Y38170D01*
Y36040D01*
X743257Y35915D01*
X743297Y35790D01*
X743357Y35680D01*
X743437Y35580D01*
X743537Y35500D01*
X743647Y35440D01*
X743772Y35400D01*
X743897Y35390D01*
G37*
G54D18*
X26000Y124800D03*
Y128200D03*
X61500Y268900D03*
Y272300D03*
X75500Y253300D03*
Y256700D03*
X78500Y253300D03*
Y256700D03*
X120800Y128900D03*
Y132300D03*
X124000Y209300D03*
Y212700D03*
X140500Y78800D03*
Y82200D03*
X143500Y85800D03*
Y89200D03*
X160000Y60900D03*
Y64300D03*
X157000Y60900D03*
Y64300D03*
X170800Y64400D03*
Y67800D03*
X163000Y164800D03*
Y168200D03*
X186500Y60900D03*
Y64300D03*
X173800Y64400D03*
Y67800D03*
X178600Y109800D03*
Y113200D03*
X181600Y109800D03*
Y113200D03*
X189500Y60900D03*
Y64300D03*
X207400Y84500D03*
Y87900D03*
X257800Y86800D03*
Y90200D03*
Y80200D03*
Y83600D03*
X277000Y49300D03*
Y52700D03*
X271000Y180300D03*
Y183700D03*
X277500Y208800D03*
Y212200D03*
X269500Y240800D03*
Y244200D03*
X278700Y237800D03*
Y241200D03*
X283100Y88100D03*
Y91500D03*
X290200Y151000D03*
Y154400D03*
X309000Y91400D03*
Y94800D03*
X304500Y144300D03*
Y147700D03*
X298500Y241800D03*
Y245200D03*
X324500Y94800D03*
Y98200D03*
X321500Y94800D03*
Y98200D03*
X315000Y91400D03*
Y94800D03*
X312000Y91400D03*
Y94800D03*
X319000Y257300D03*
X322500D03*
X315500D03*
X319000Y260700D03*
X322500D03*
X315500D03*
X339500Y247300D03*
Y250700D03*
X344840Y100940D03*
Y104340D03*
X341840Y100940D03*
Y104340D03*
X347500Y135900D03*
X350000Y129300D03*
Y132700D03*
X347500Y139300D03*
X348000Y180300D03*
Y183700D03*
X363500Y51300D03*
Y54700D03*
X377500Y143300D03*
Y146700D03*
X393500Y84600D03*
Y88000D03*
X396496Y105863D03*
Y109263D03*
X395000Y256800D03*
Y260200D03*
X398000Y267300D03*
Y270700D03*
X403000Y263300D03*
Y266700D03*
X414500Y60800D03*
Y64200D03*
X403500Y105863D03*
Y109263D03*
X434000Y50800D03*
Y54200D03*
X479000Y269000D03*
Y272400D03*
X475500Y269000D03*
Y272400D03*
X510000Y234300D03*
Y237700D03*
X520000Y234300D03*
Y237700D03*
X701000Y165800D03*
Y169200D03*
X726200Y102100D03*
Y105500D03*
X729400Y102100D03*
Y105500D03*
X735000Y123100D03*
Y126500D03*
X751500Y108300D03*
Y111700D03*
X748500Y108300D03*
Y111700D03*
G54D63*
X402150Y254500D03*
G54D27*
X58500Y188000D03*
X61500D03*
X79500Y48500D03*
X67500Y188000D03*
X64500D03*
X68000Y235000D03*
X82500Y48500D03*
X88500D03*
X85500D03*
X85200Y239000D03*
X103250Y48500D03*
X100250D03*
X105500Y192000D03*
X119000Y48500D03*
X116000D03*
X134800D03*
X131800D03*
X132700Y186600D03*
X150515Y48500D03*
X147515D03*
X166263D03*
X163263D03*
X160100Y184000D03*
X182000Y48500D03*
X179000D03*
X178000Y164500D03*
X201500Y65500D03*
X204500D03*
X237000Y57300D03*
X268000Y52000D03*
X271000D03*
X275500Y241500D03*
X272500D03*
X290000Y52000D03*
X287000D03*
X286100Y77700D03*
X305000Y51500D03*
X308000D03*
X310500Y60500D03*
X304500Y219000D03*
X302000Y242100D03*
X305000D03*
X316000Y51500D03*
X319000D03*
X334000Y55500D03*
X354000Y63000D03*
X353000Y140500D03*
X364500Y128500D03*
X370300Y131500D03*
X365000Y146500D03*
X359000Y140000D03*
Y174000D03*
X377500Y131500D03*
X374500D03*
X386500Y168500D03*
X378220Y170540D03*
X395500Y75000D03*
X392000D03*
X393496Y106063D03*
X389500Y156263D03*
X390000Y162100D03*
Y168500D03*
X398000Y253000D03*
X410000Y106063D03*
X407000D03*
X416000D03*
X413000D03*
X406000Y263500D03*
X422000Y106063D03*
X419000D03*
X421142Y181024D03*
X436000Y107563D03*
X434900Y146500D03*
X441000Y140000D03*
X601100Y233500D03*
X617800Y233400D03*
X613200Y233100D03*
X610200D03*
X620800Y233400D03*
X623800D03*
X744500Y236000D03*
G54D19*
X23000Y138500D03*
X61000Y251500D03*
Y254500D03*
Y261700D03*
Y264800D03*
X72100Y241700D03*
X122500Y175000D03*
X129000Y172000D03*
X150500Y168000D03*
X257800Y76200D03*
X269000Y126300D03*
X278400Y153200D03*
X280000Y138500D03*
X326000Y85000D03*
X315500Y88300D03*
X353650Y131700D03*
Y134700D03*
X367000Y103000D03*
Y100000D03*
Y106000D03*
X362100Y121500D03*
X363500Y118500D03*
X371000Y146000D03*
X358400Y151900D03*
X376500Y77500D03*
X380500Y139500D03*
X383500Y152500D03*
X373280Y184610D03*
X400000Y131063D03*
X401542Y169124D03*
X405000Y134063D03*
X405012Y140238D03*
X405000Y137063D03*
X405200Y176063D03*
Y173063D03*
X411000Y208000D03*
X434000Y188500D03*
X441000Y114563D03*
Y111563D03*
X434500Y200063D03*
X463500Y24000D03*
X510000Y50507D03*
X512000Y126000D03*
Y122500D03*
X525000Y125500D03*
X541500Y179000D03*
X543000Y96000D03*
Y93000D03*
X567000Y92500D03*
X588000Y179000D03*
X596000Y142000D03*
X641500Y285000D03*
X719000Y116500D03*
X733200Y111900D03*
X733300Y108700D03*
X734900Y130900D03*
X734800Y137100D03*
X802000Y121500D03*
Y125000D03*
X802200Y155300D03*
X802900Y166700D03*
G54D37*
X157545Y73450D03*
X159515D03*
X161485D03*
X163455D03*
X165425D03*
X167395D03*
X169365D03*
X171335D03*
X169365Y101750D03*
X167395D03*
X165425D03*
X163455D03*
X161485D03*
X159515D03*
X157545D03*
X171335D03*
X173305Y73450D03*
X175275D03*
X177245D03*
X179215D03*
X181185D03*
X183155D03*
X185125D03*
X187095D03*
Y101750D03*
X185125D03*
X183155D03*
X181185D03*
X179215D03*
X177245D03*
X175275D03*
X173305D03*
X191035Y73450D03*
X193005D03*
X194975D03*
X196945D03*
X198915D03*
X200885D03*
X189065D03*
X200885Y101750D03*
X198915D03*
X196945D03*
X194975D03*
X193005D03*
X191035D03*
X189065D03*
X202855Y73450D03*
Y101750D03*
G54D64*
X404850Y254500D03*
G54D82*
X782046Y280709D03*
G54D28*
X70760Y174791D03*
X78240D03*
X74500Y183209D03*
X268260Y168291D03*
X275740D03*
X272000Y176709D03*
X456760Y259791D03*
X464240D03*
X460500Y268209D03*
G54D55*
X331500Y244900D03*
X335500D03*
X333500Y250100D03*
G36*
G01X510039Y35390D02*
X510164Y35400D01*
X510289Y35440D01*
X510399Y35500D01*
X510499Y35580D01*
X510579Y35680D01*
X510639Y35790D01*
X510679Y35915D01*
X510689Y36040D01*
Y37170D01*
X510719Y37200D01*
X510819Y37340D01*
X510839Y37380D01*
X510854Y37415D01*
X510874Y37455D01*
X510889Y37495D01*
X510899Y37535D01*
X510914Y37580D01*
X510919Y37620D01*
X510929Y37660D01*
X510934Y37705D01*
Y37745D01*
X510939Y37790D01*
X510934Y37835D01*
Y37875D01*
X510929Y37920D01*
X510919Y37960D01*
X510914Y38000D01*
X510899Y38045D01*
X510889Y38085D01*
X510874Y38125D01*
X510854Y38165D01*
X510839Y38200D01*
X510819Y38240D01*
X510719Y38380D01*
X510689Y38410D01*
Y41840D01*
X510679Y41965D01*
X510639Y42090D01*
X510579Y42200D01*
X510499Y42300D01*
X510399Y42380D01*
X510289Y42440D01*
X510164Y42480D01*
X510039Y42490D01*
X509914Y42480D01*
X509789Y42440D01*
X509679Y42380D01*
X509579Y42300D01*
X509499Y42200D01*
X509439Y42090D01*
X509399Y41965D01*
X509389Y41840D01*
Y38410D01*
X509359Y38380D01*
X509259Y38240D01*
X509239Y38200D01*
X509224Y38165D01*
X509204Y38125D01*
X509189Y38085D01*
X509179Y38045D01*
X509164Y38000D01*
X509159Y37960D01*
X509149Y37920D01*
X509144Y37875D01*
Y37835D01*
X509139Y37790D01*
X509144Y37745D01*
Y37705D01*
X509149Y37660D01*
X509159Y37620D01*
X509164Y37580D01*
X509179Y37535D01*
X509189Y37495D01*
X509204Y37455D01*
X509224Y37415D01*
X509239Y37380D01*
X509259Y37340D01*
X509359Y37200D01*
X509389Y37170D01*
Y36040D01*
X509399Y35915D01*
X509439Y35790D01*
X509499Y35680D01*
X509579Y35580D01*
X509679Y35500D01*
X509789Y35440D01*
X509914Y35400D01*
X510039Y35390D01*
G37*
G36*
G01X505315D02*
X505440Y35400D01*
X505565Y35440D01*
X505675Y35500D01*
X505775Y35580D01*
X505855Y35680D01*
X505915Y35790D01*
X505955Y35915D01*
X505965Y36040D01*
Y37170D01*
X505995Y37200D01*
X506095Y37340D01*
X506115Y37380D01*
X506130Y37415D01*
X506150Y37455D01*
X506165Y37495D01*
X506175Y37535D01*
X506190Y37580D01*
X506195Y37620D01*
X506205Y37660D01*
X506210Y37705D01*
Y37745D01*
X506215Y37790D01*
X506210Y37835D01*
Y37875D01*
X506205Y37920D01*
X506195Y37960D01*
X506190Y38000D01*
X506175Y38045D01*
X506165Y38085D01*
X506150Y38125D01*
X506130Y38165D01*
X506115Y38200D01*
X506095Y38240D01*
X505995Y38380D01*
X505965Y38410D01*
Y41840D01*
X505955Y41965D01*
X505915Y42090D01*
X505855Y42200D01*
X505775Y42300D01*
X505675Y42380D01*
X505565Y42440D01*
X505440Y42480D01*
X505315Y42490D01*
X505190Y42480D01*
X505065Y42440D01*
X504955Y42380D01*
X504855Y42300D01*
X504775Y42200D01*
X504715Y42090D01*
X504675Y41965D01*
X504665Y41840D01*
Y38410D01*
X504635Y38380D01*
X504535Y38240D01*
X504515Y38200D01*
X504500Y38165D01*
X504480Y38125D01*
X504465Y38085D01*
X504455Y38045D01*
X504440Y38000D01*
X504435Y37960D01*
X504425Y37920D01*
X504420Y37875D01*
Y37835D01*
X504415Y37790D01*
X504420Y37745D01*
Y37705D01*
X504425Y37660D01*
X504435Y37620D01*
X504440Y37580D01*
X504455Y37535D01*
X504465Y37495D01*
X504480Y37455D01*
X504500Y37415D01*
X504515Y37380D01*
X504535Y37340D01*
X504635Y37200D01*
X504665Y37170D01*
Y36040D01*
X504675Y35915D01*
X504715Y35790D01*
X504775Y35680D01*
X504855Y35580D01*
X504955Y35500D01*
X505065Y35440D01*
X505190Y35400D01*
X505315Y35390D01*
G37*
G36*
G01X524212D02*
X524337Y35400D01*
X524462Y35440D01*
X524572Y35500D01*
X524672Y35580D01*
X524752Y35680D01*
X524812Y35790D01*
X524852Y35915D01*
X524862Y36040D01*
Y37170D01*
X524892Y37200D01*
X524992Y37340D01*
X525012Y37380D01*
X525027Y37415D01*
X525047Y37455D01*
X525062Y37495D01*
X525072Y37535D01*
X525087Y37580D01*
X525092Y37620D01*
X525102Y37660D01*
X525107Y37705D01*
Y37745D01*
X525112Y37790D01*
X525107Y37835D01*
Y37875D01*
X525102Y37920D01*
X525092Y37960D01*
X525087Y38000D01*
X525072Y38045D01*
X525062Y38085D01*
X525047Y38125D01*
X525027Y38165D01*
X525012Y38200D01*
X524992Y38240D01*
X524892Y38380D01*
X524862Y38410D01*
Y41840D01*
X524852Y41965D01*
X524812Y42090D01*
X524752Y42200D01*
X524672Y42300D01*
X524572Y42380D01*
X524462Y42440D01*
X524337Y42480D01*
X524212Y42490D01*
X524087Y42480D01*
X523962Y42440D01*
X523852Y42380D01*
X523752Y42300D01*
X523672Y42200D01*
X523612Y42090D01*
X523572Y41965D01*
X523562Y41840D01*
Y38410D01*
X523532Y38380D01*
X523432Y38240D01*
X523412Y38200D01*
X523397Y38165D01*
X523377Y38125D01*
X523362Y38085D01*
X523352Y38045D01*
X523337Y38000D01*
X523332Y37960D01*
X523322Y37920D01*
X523317Y37875D01*
Y37835D01*
X523312Y37790D01*
X523317Y37745D01*
Y37705D01*
X523322Y37660D01*
X523332Y37620D01*
X523337Y37580D01*
X523352Y37535D01*
X523362Y37495D01*
X523377Y37455D01*
X523397Y37415D01*
X523412Y37380D01*
X523432Y37340D01*
X523532Y37200D01*
X523562Y37170D01*
Y36040D01*
X523572Y35915D01*
X523612Y35790D01*
X523672Y35680D01*
X523752Y35580D01*
X523852Y35500D01*
X523962Y35440D01*
X524087Y35400D01*
X524212Y35390D01*
G37*
G36*
G01X519488D02*
X519613Y35400D01*
X519738Y35440D01*
X519848Y35500D01*
X519948Y35580D01*
X520028Y35680D01*
X520088Y35790D01*
X520128Y35915D01*
X520138Y36040D01*
Y37170D01*
X520168Y37200D01*
X520268Y37340D01*
X520288Y37380D01*
X520303Y37415D01*
X520323Y37455D01*
X520338Y37495D01*
X520348Y37535D01*
X520363Y37580D01*
X520368Y37620D01*
X520378Y37660D01*
X520383Y37705D01*
Y37745D01*
X520388Y37790D01*
X520383Y37835D01*
Y37875D01*
X520378Y37920D01*
X520368Y37960D01*
X520363Y38000D01*
X520348Y38045D01*
X520338Y38085D01*
X520323Y38125D01*
X520303Y38165D01*
X520288Y38200D01*
X520268Y38240D01*
X520168Y38380D01*
X520138Y38410D01*
Y41840D01*
X520128Y41965D01*
X520088Y42090D01*
X520028Y42200D01*
X519948Y42300D01*
X519848Y42380D01*
X519738Y42440D01*
X519613Y42480D01*
X519488Y42490D01*
X519363Y42480D01*
X519238Y42440D01*
X519128Y42380D01*
X519028Y42300D01*
X518948Y42200D01*
X518888Y42090D01*
X518848Y41965D01*
X518838Y41840D01*
Y38410D01*
X518808Y38380D01*
X518708Y38240D01*
X518688Y38200D01*
X518673Y38165D01*
X518653Y38125D01*
X518638Y38085D01*
X518628Y38045D01*
X518613Y38000D01*
X518608Y37960D01*
X518598Y37920D01*
X518593Y37875D01*
Y37835D01*
X518588Y37790D01*
X518593Y37745D01*
Y37705D01*
X518598Y37660D01*
X518608Y37620D01*
X518613Y37580D01*
X518628Y37535D01*
X518638Y37495D01*
X518653Y37455D01*
X518673Y37415D01*
X518688Y37380D01*
X518708Y37340D01*
X518808Y37200D01*
X518838Y37170D01*
Y36040D01*
X518848Y35915D01*
X518888Y35790D01*
X518948Y35680D01*
X519028Y35580D01*
X519128Y35500D01*
X519238Y35440D01*
X519363Y35400D01*
X519488Y35390D01*
G37*
G36*
G01X514764D02*
X514889Y35400D01*
X515014Y35440D01*
X515124Y35500D01*
X515224Y35580D01*
X515304Y35680D01*
X515364Y35790D01*
X515404Y35915D01*
X515414Y36040D01*
Y37170D01*
X515444Y37200D01*
X515544Y37340D01*
X515564Y37380D01*
X515579Y37415D01*
X515599Y37455D01*
X515614Y37495D01*
X515624Y37535D01*
X515639Y37580D01*
X515644Y37620D01*
X515654Y37660D01*
X515659Y37705D01*
Y37745D01*
X515664Y37790D01*
X515659Y37835D01*
Y37875D01*
X515654Y37920D01*
X515644Y37960D01*
X515639Y38000D01*
X515624Y38045D01*
X515614Y38085D01*
X515599Y38125D01*
X515579Y38165D01*
X515564Y38200D01*
X515544Y38240D01*
X515444Y38380D01*
X515414Y38410D01*
Y41840D01*
X515404Y41965D01*
X515364Y42090D01*
X515304Y42200D01*
X515224Y42300D01*
X515124Y42380D01*
X515014Y42440D01*
X514889Y42480D01*
X514764Y42490D01*
X514639Y42480D01*
X514514Y42440D01*
X514404Y42380D01*
X514304Y42300D01*
X514224Y42200D01*
X514164Y42090D01*
X514124Y41965D01*
X514114Y41840D01*
Y38410D01*
X514084Y38380D01*
X513984Y38240D01*
X513964Y38200D01*
X513949Y38165D01*
X513929Y38125D01*
X513914Y38085D01*
X513904Y38045D01*
X513889Y38000D01*
X513884Y37960D01*
X513874Y37920D01*
X513869Y37875D01*
Y37835D01*
X513864Y37790D01*
X513869Y37745D01*
Y37705D01*
X513874Y37660D01*
X513884Y37620D01*
X513889Y37580D01*
X513904Y37535D01*
X513914Y37495D01*
X513929Y37455D01*
X513949Y37415D01*
X513964Y37380D01*
X513984Y37340D01*
X514084Y37200D01*
X514114Y37170D01*
Y36040D01*
X514124Y35915D01*
X514164Y35790D01*
X514224Y35680D01*
X514304Y35580D01*
X514404Y35500D01*
X514514Y35440D01*
X514639Y35400D01*
X514764Y35390D01*
G37*
G36*
G01X538386D02*
X538511Y35400D01*
X538636Y35440D01*
X538746Y35500D01*
X538846Y35580D01*
X538926Y35680D01*
X538986Y35790D01*
X539026Y35915D01*
X539036Y36040D01*
Y37170D01*
X539066Y37200D01*
X539166Y37340D01*
X539186Y37380D01*
X539201Y37415D01*
X539221Y37455D01*
X539236Y37495D01*
X539246Y37535D01*
X539261Y37580D01*
X539266Y37620D01*
X539276Y37660D01*
X539281Y37705D01*
Y37745D01*
X539286Y37790D01*
X539281Y37835D01*
Y37875D01*
X539276Y37920D01*
X539266Y37960D01*
X539261Y38000D01*
X539246Y38045D01*
X539236Y38085D01*
X539221Y38125D01*
X539201Y38165D01*
X539186Y38200D01*
X539166Y38240D01*
X539066Y38380D01*
X539036Y38410D01*
Y41840D01*
X539026Y41965D01*
X538986Y42090D01*
X538926Y42200D01*
X538846Y42300D01*
X538746Y42380D01*
X538636Y42440D01*
X538511Y42480D01*
X538386Y42490D01*
X538261Y42480D01*
X538136Y42440D01*
X538026Y42380D01*
X537926Y42300D01*
X537846Y42200D01*
X537786Y42090D01*
X537746Y41965D01*
X537736Y41840D01*
Y38410D01*
X537706Y38380D01*
X537606Y38240D01*
X537586Y38200D01*
X537571Y38165D01*
X537551Y38125D01*
X537536Y38085D01*
X537526Y38045D01*
X537511Y38000D01*
X537506Y37960D01*
X537496Y37920D01*
X537491Y37875D01*
Y37835D01*
X537486Y37790D01*
X537491Y37745D01*
Y37705D01*
X537496Y37660D01*
X537506Y37620D01*
X537511Y37580D01*
X537526Y37535D01*
X537536Y37495D01*
X537551Y37455D01*
X537571Y37415D01*
X537586Y37380D01*
X537606Y37340D01*
X537706Y37200D01*
X537736Y37170D01*
Y36040D01*
X537746Y35915D01*
X537786Y35790D01*
X537846Y35680D01*
X537926Y35580D01*
X538026Y35500D01*
X538136Y35440D01*
X538261Y35400D01*
X538386Y35390D01*
G37*
G36*
G01X533661D02*
X533786Y35400D01*
X533911Y35440D01*
X534021Y35500D01*
X534121Y35580D01*
X534201Y35680D01*
X534261Y35790D01*
X534301Y35915D01*
X534311Y36040D01*
Y37170D01*
X534341Y37200D01*
X534441Y37340D01*
X534461Y37380D01*
X534476Y37415D01*
X534496Y37455D01*
X534511Y37495D01*
X534521Y37535D01*
X534536Y37580D01*
X534541Y37620D01*
X534551Y37660D01*
X534556Y37705D01*
Y37745D01*
X534561Y37790D01*
X534556Y37835D01*
Y37875D01*
X534551Y37920D01*
X534541Y37960D01*
X534536Y38000D01*
X534521Y38045D01*
X534511Y38085D01*
X534496Y38125D01*
X534476Y38165D01*
X534461Y38200D01*
X534441Y38240D01*
X534341Y38380D01*
X534311Y38410D01*
Y41840D01*
X534301Y41965D01*
X534261Y42090D01*
X534201Y42200D01*
X534121Y42300D01*
X534021Y42380D01*
X533911Y42440D01*
X533786Y42480D01*
X533661Y42490D01*
X533536Y42480D01*
X533411Y42440D01*
X533301Y42380D01*
X533201Y42300D01*
X533121Y42200D01*
X533061Y42090D01*
X533021Y41965D01*
X533011Y41840D01*
Y38410D01*
X532981Y38380D01*
X532881Y38240D01*
X532861Y38200D01*
X532846Y38165D01*
X532826Y38125D01*
X532811Y38085D01*
X532801Y38045D01*
X532786Y38000D01*
X532781Y37960D01*
X532771Y37920D01*
X532766Y37875D01*
Y37835D01*
X532761Y37790D01*
X532766Y37745D01*
Y37705D01*
X532771Y37660D01*
X532781Y37620D01*
X532786Y37580D01*
X532801Y37535D01*
X532811Y37495D01*
X532826Y37455D01*
X532846Y37415D01*
X532861Y37380D01*
X532881Y37340D01*
X532981Y37200D01*
X533011Y37170D01*
Y36040D01*
X533021Y35915D01*
X533061Y35790D01*
X533121Y35680D01*
X533201Y35580D01*
X533301Y35500D01*
X533411Y35440D01*
X533536Y35400D01*
X533661Y35390D01*
G37*
G36*
G01X528937D02*
X529062Y35400D01*
X529187Y35440D01*
X529297Y35500D01*
X529397Y35580D01*
X529477Y35680D01*
X529537Y35790D01*
X529577Y35915D01*
X529587Y36040D01*
Y37170D01*
X529617Y37200D01*
X529717Y37340D01*
X529737Y37380D01*
X529752Y37415D01*
X529772Y37455D01*
X529787Y37495D01*
X529797Y37535D01*
X529812Y37580D01*
X529817Y37620D01*
X529827Y37660D01*
X529832Y37705D01*
Y37745D01*
X529837Y37790D01*
X529832Y37835D01*
Y37875D01*
X529827Y37920D01*
X529817Y37960D01*
X529812Y38000D01*
X529797Y38045D01*
X529787Y38085D01*
X529772Y38125D01*
X529752Y38165D01*
X529737Y38200D01*
X529717Y38240D01*
X529617Y38380D01*
X529587Y38410D01*
Y41840D01*
X529577Y41965D01*
X529537Y42090D01*
X529477Y42200D01*
X529397Y42300D01*
X529297Y42380D01*
X529187Y42440D01*
X529062Y42480D01*
X528937Y42490D01*
X528812Y42480D01*
X528687Y42440D01*
X528577Y42380D01*
X528477Y42300D01*
X528397Y42200D01*
X528337Y42090D01*
X528297Y41965D01*
X528287Y41840D01*
Y38410D01*
X528257Y38380D01*
X528157Y38240D01*
X528137Y38200D01*
X528122Y38165D01*
X528102Y38125D01*
X528087Y38085D01*
X528077Y38045D01*
X528062Y38000D01*
X528057Y37960D01*
X528047Y37920D01*
X528042Y37875D01*
Y37835D01*
X528037Y37790D01*
X528042Y37745D01*
Y37705D01*
X528047Y37660D01*
X528057Y37620D01*
X528062Y37580D01*
X528077Y37535D01*
X528087Y37495D01*
X528102Y37455D01*
X528122Y37415D01*
X528137Y37380D01*
X528157Y37340D01*
X528257Y37200D01*
X528287Y37170D01*
Y36040D01*
X528297Y35915D01*
X528337Y35790D01*
X528397Y35680D01*
X528477Y35580D01*
X528577Y35500D01*
X528687Y35440D01*
X528812Y35400D01*
X528937Y35390D01*
G37*
G36*
G01X557283D02*
X557408Y35400D01*
X557533Y35440D01*
X557643Y35500D01*
X557743Y35580D01*
X557823Y35680D01*
X557883Y35790D01*
X557923Y35915D01*
X557933Y36040D01*
Y37170D01*
X557963Y37200D01*
X558063Y37340D01*
X558083Y37380D01*
X558098Y37415D01*
X558118Y37455D01*
X558133Y37495D01*
X558143Y37535D01*
X558158Y37580D01*
X558163Y37620D01*
X558173Y37660D01*
X558178Y37705D01*
Y37745D01*
X558183Y37790D01*
X558178Y37835D01*
Y37875D01*
X558173Y37920D01*
X558163Y37960D01*
X558158Y38000D01*
X558143Y38045D01*
X558133Y38085D01*
X558118Y38125D01*
X558098Y38165D01*
X558083Y38200D01*
X558063Y38240D01*
X557963Y38380D01*
X557933Y38410D01*
Y41840D01*
X557923Y41965D01*
X557883Y42090D01*
X557823Y42200D01*
X557743Y42300D01*
X557643Y42380D01*
X557533Y42440D01*
X557408Y42480D01*
X557283Y42490D01*
X557158Y42480D01*
X557033Y42440D01*
X556923Y42380D01*
X556823Y42300D01*
X556743Y42200D01*
X556683Y42090D01*
X556643Y41965D01*
X556633Y41840D01*
Y38410D01*
X556603Y38380D01*
X556503Y38240D01*
X556483Y38200D01*
X556468Y38165D01*
X556448Y38125D01*
X556433Y38085D01*
X556423Y38045D01*
X556408Y38000D01*
X556403Y37960D01*
X556393Y37920D01*
X556388Y37875D01*
Y37835D01*
X556383Y37790D01*
X556388Y37745D01*
Y37705D01*
X556393Y37660D01*
X556403Y37620D01*
X556408Y37580D01*
X556423Y37535D01*
X556433Y37495D01*
X556448Y37455D01*
X556468Y37415D01*
X556483Y37380D01*
X556503Y37340D01*
X556603Y37200D01*
X556633Y37170D01*
Y36040D01*
X556643Y35915D01*
X556683Y35790D01*
X556743Y35680D01*
X556823Y35580D01*
X556923Y35500D01*
X557033Y35440D01*
X557158Y35400D01*
X557283Y35390D01*
G37*
G36*
G01X552559D02*
X552684Y35400D01*
X552809Y35440D01*
X552919Y35500D01*
X553019Y35580D01*
X553099Y35680D01*
X553159Y35790D01*
X553199Y35915D01*
X553209Y36040D01*
Y37170D01*
X553239Y37200D01*
X553339Y37340D01*
X553359Y37380D01*
X553374Y37415D01*
X553394Y37455D01*
X553409Y37495D01*
X553419Y37535D01*
X553434Y37580D01*
X553439Y37620D01*
X553449Y37660D01*
X553454Y37705D01*
Y37745D01*
X553459Y37790D01*
X553454Y37835D01*
Y37875D01*
X553449Y37920D01*
X553439Y37960D01*
X553434Y38000D01*
X553419Y38045D01*
X553409Y38085D01*
X553394Y38125D01*
X553374Y38165D01*
X553359Y38200D01*
X553339Y38240D01*
X553239Y38380D01*
X553209Y38410D01*
Y41840D01*
X553199Y41965D01*
X553159Y42090D01*
X553099Y42200D01*
X553019Y42300D01*
X552919Y42380D01*
X552809Y42440D01*
X552684Y42480D01*
X552559Y42490D01*
X552434Y42480D01*
X552309Y42440D01*
X552199Y42380D01*
X552099Y42300D01*
X552019Y42200D01*
X551959Y42090D01*
X551919Y41965D01*
X551909Y41840D01*
Y38410D01*
X551879Y38380D01*
X551779Y38240D01*
X551759Y38200D01*
X551744Y38165D01*
X551724Y38125D01*
X551709Y38085D01*
X551699Y38045D01*
X551684Y38000D01*
X551679Y37960D01*
X551669Y37920D01*
X551664Y37875D01*
Y37835D01*
X551659Y37790D01*
X551664Y37745D01*
Y37705D01*
X551669Y37660D01*
X551679Y37620D01*
X551684Y37580D01*
X551699Y37535D01*
X551709Y37495D01*
X551724Y37455D01*
X551744Y37415D01*
X551759Y37380D01*
X551779Y37340D01*
X551879Y37200D01*
X551909Y37170D01*
Y36040D01*
X551919Y35915D01*
X551959Y35790D01*
X552019Y35680D01*
X552099Y35580D01*
X552199Y35500D01*
X552309Y35440D01*
X552434Y35400D01*
X552559Y35390D01*
G37*
G36*
G01X547834D02*
X547959Y35400D01*
X548084Y35440D01*
X548194Y35500D01*
X548294Y35580D01*
X548374Y35680D01*
X548434Y35790D01*
X548474Y35915D01*
X548484Y36040D01*
Y37170D01*
X548514Y37200D01*
X548614Y37340D01*
X548634Y37380D01*
X548649Y37415D01*
X548669Y37455D01*
X548684Y37495D01*
X548694Y37535D01*
X548709Y37580D01*
X548714Y37620D01*
X548724Y37660D01*
X548729Y37705D01*
Y37745D01*
X548734Y37790D01*
X548729Y37835D01*
Y37875D01*
X548724Y37920D01*
X548714Y37960D01*
X548709Y38000D01*
X548694Y38045D01*
X548684Y38085D01*
X548669Y38125D01*
X548649Y38165D01*
X548634Y38200D01*
X548614Y38240D01*
X548514Y38380D01*
X548484Y38410D01*
Y41840D01*
X548474Y41965D01*
X548434Y42090D01*
X548374Y42200D01*
X548294Y42300D01*
X548194Y42380D01*
X548084Y42440D01*
X547959Y42480D01*
X547834Y42490D01*
X547709Y42480D01*
X547584Y42440D01*
X547474Y42380D01*
X547374Y42300D01*
X547294Y42200D01*
X547234Y42090D01*
X547194Y41965D01*
X547184Y41840D01*
Y38410D01*
X547154Y38380D01*
X547054Y38240D01*
X547034Y38200D01*
X547019Y38165D01*
X546999Y38125D01*
X546984Y38085D01*
X546974Y38045D01*
X546959Y38000D01*
X546954Y37960D01*
X546944Y37920D01*
X546939Y37875D01*
Y37835D01*
X546934Y37790D01*
X546939Y37745D01*
Y37705D01*
X546944Y37660D01*
X546954Y37620D01*
X546959Y37580D01*
X546974Y37535D01*
X546984Y37495D01*
X546999Y37455D01*
X547019Y37415D01*
X547034Y37380D01*
X547054Y37340D01*
X547154Y37200D01*
X547184Y37170D01*
Y36040D01*
X547194Y35915D01*
X547234Y35790D01*
X547294Y35680D01*
X547374Y35580D01*
X547474Y35500D01*
X547584Y35440D01*
X547709Y35400D01*
X547834Y35390D01*
G37*
G36*
G01X543110D02*
X543235Y35400D01*
X543360Y35440D01*
X543470Y35500D01*
X543570Y35580D01*
X543650Y35680D01*
X543710Y35790D01*
X543750Y35915D01*
X543760Y36040D01*
Y37170D01*
X543790Y37200D01*
X543890Y37340D01*
X543910Y37380D01*
X543925Y37415D01*
X543945Y37455D01*
X543960Y37495D01*
X543970Y37535D01*
X543985Y37580D01*
X543990Y37620D01*
X544000Y37660D01*
X544005Y37705D01*
Y37745D01*
X544010Y37790D01*
X544005Y37835D01*
Y37875D01*
X544000Y37920D01*
X543990Y37960D01*
X543985Y38000D01*
X543970Y38045D01*
X543960Y38085D01*
X543945Y38125D01*
X543925Y38165D01*
X543910Y38200D01*
X543890Y38240D01*
X543790Y38380D01*
X543760Y38410D01*
Y41840D01*
X543750Y41965D01*
X543710Y42090D01*
X543650Y42200D01*
X543570Y42300D01*
X543470Y42380D01*
X543360Y42440D01*
X543235Y42480D01*
X543110Y42490D01*
X542985Y42480D01*
X542860Y42440D01*
X542750Y42380D01*
X542650Y42300D01*
X542570Y42200D01*
X542510Y42090D01*
X542470Y41965D01*
X542460Y41840D01*
Y38410D01*
X542430Y38380D01*
X542330Y38240D01*
X542310Y38200D01*
X542295Y38165D01*
X542275Y38125D01*
X542260Y38085D01*
X542250Y38045D01*
X542235Y38000D01*
X542230Y37960D01*
X542220Y37920D01*
X542215Y37875D01*
Y37835D01*
X542210Y37790D01*
X542215Y37745D01*
Y37705D01*
X542220Y37660D01*
X542230Y37620D01*
X542235Y37580D01*
X542250Y37535D01*
X542260Y37495D01*
X542275Y37455D01*
X542295Y37415D01*
X542310Y37380D01*
X542330Y37340D01*
X542430Y37200D01*
X542460Y37170D01*
Y36040D01*
X542470Y35915D01*
X542510Y35790D01*
X542570Y35680D01*
X542650Y35580D01*
X542750Y35500D01*
X542860Y35440D01*
X542985Y35400D01*
X543110Y35390D01*
G37*
G36*
G01X571456D02*
X571581Y35400D01*
X571706Y35440D01*
X571816Y35500D01*
X571916Y35580D01*
X571996Y35680D01*
X572056Y35790D01*
X572096Y35915D01*
X572106Y36040D01*
Y37170D01*
X572136Y37200D01*
X572236Y37340D01*
X572256Y37380D01*
X572271Y37415D01*
X572291Y37455D01*
X572306Y37495D01*
X572316Y37535D01*
X572331Y37580D01*
X572336Y37620D01*
X572346Y37660D01*
X572351Y37705D01*
Y37745D01*
X572356Y37790D01*
X572351Y37835D01*
Y37875D01*
X572346Y37920D01*
X572336Y37960D01*
X572331Y38000D01*
X572316Y38045D01*
X572306Y38085D01*
X572291Y38125D01*
X572271Y38165D01*
X572256Y38200D01*
X572236Y38240D01*
X572136Y38380D01*
X572106Y38410D01*
Y41840D01*
X572096Y41965D01*
X572056Y42090D01*
X571996Y42200D01*
X571916Y42300D01*
X571816Y42380D01*
X571706Y42440D01*
X571581Y42480D01*
X571456Y42490D01*
X571331Y42480D01*
X571206Y42440D01*
X571096Y42380D01*
X570996Y42300D01*
X570916Y42200D01*
X570856Y42090D01*
X570816Y41965D01*
X570806Y41840D01*
Y38410D01*
X570776Y38380D01*
X570676Y38240D01*
X570656Y38200D01*
X570641Y38165D01*
X570621Y38125D01*
X570606Y38085D01*
X570596Y38045D01*
X570581Y38000D01*
X570576Y37960D01*
X570566Y37920D01*
X570561Y37875D01*
Y37835D01*
X570556Y37790D01*
X570561Y37745D01*
Y37705D01*
X570566Y37660D01*
X570576Y37620D01*
X570581Y37580D01*
X570596Y37535D01*
X570606Y37495D01*
X570621Y37455D01*
X570641Y37415D01*
X570656Y37380D01*
X570676Y37340D01*
X570776Y37200D01*
X570806Y37170D01*
Y36040D01*
X570816Y35915D01*
X570856Y35790D01*
X570916Y35680D01*
X570996Y35580D01*
X571096Y35500D01*
X571206Y35440D01*
X571331Y35400D01*
X571456Y35390D01*
G37*
G36*
G01X566732D02*
X566857Y35400D01*
X566982Y35440D01*
X567092Y35500D01*
X567192Y35580D01*
X567272Y35680D01*
X567332Y35790D01*
X567372Y35915D01*
X567382Y36040D01*
Y37170D01*
X567412Y37200D01*
X567512Y37340D01*
X567532Y37380D01*
X567547Y37415D01*
X567567Y37455D01*
X567582Y37495D01*
X567592Y37535D01*
X567607Y37580D01*
X567612Y37620D01*
X567622Y37660D01*
X567627Y37705D01*
Y37745D01*
X567632Y37790D01*
X567627Y37835D01*
Y37875D01*
X567622Y37920D01*
X567612Y37960D01*
X567607Y38000D01*
X567592Y38045D01*
X567582Y38085D01*
X567567Y38125D01*
X567547Y38165D01*
X567532Y38200D01*
X567512Y38240D01*
X567412Y38380D01*
X567382Y38410D01*
Y41840D01*
X567372Y41965D01*
X567332Y42090D01*
X567272Y42200D01*
X567192Y42300D01*
X567092Y42380D01*
X566982Y42440D01*
X566857Y42480D01*
X566732Y42490D01*
X566607Y42480D01*
X566482Y42440D01*
X566372Y42380D01*
X566272Y42300D01*
X566192Y42200D01*
X566132Y42090D01*
X566092Y41965D01*
X566082Y41840D01*
Y38410D01*
X566052Y38380D01*
X565952Y38240D01*
X565932Y38200D01*
X565917Y38165D01*
X565897Y38125D01*
X565882Y38085D01*
X565872Y38045D01*
X565857Y38000D01*
X565852Y37960D01*
X565842Y37920D01*
X565837Y37875D01*
Y37835D01*
X565832Y37790D01*
X565837Y37745D01*
Y37705D01*
X565842Y37660D01*
X565852Y37620D01*
X565857Y37580D01*
X565872Y37535D01*
X565882Y37495D01*
X565897Y37455D01*
X565917Y37415D01*
X565932Y37380D01*
X565952Y37340D01*
X566052Y37200D01*
X566082Y37170D01*
Y36040D01*
X566092Y35915D01*
X566132Y35790D01*
X566192Y35680D01*
X566272Y35580D01*
X566372Y35500D01*
X566482Y35440D01*
X566607Y35400D01*
X566732Y35390D01*
G37*
G36*
G01X562008D02*
X562133Y35400D01*
X562258Y35440D01*
X562368Y35500D01*
X562468Y35580D01*
X562548Y35680D01*
X562608Y35790D01*
X562648Y35915D01*
X562658Y36040D01*
Y37170D01*
X562688Y37200D01*
X562788Y37340D01*
X562808Y37380D01*
X562823Y37415D01*
X562843Y37455D01*
X562858Y37495D01*
X562868Y37535D01*
X562883Y37580D01*
X562888Y37620D01*
X562898Y37660D01*
X562903Y37705D01*
Y37745D01*
X562908Y37790D01*
X562903Y37835D01*
Y37875D01*
X562898Y37920D01*
X562888Y37960D01*
X562883Y38000D01*
X562868Y38045D01*
X562858Y38085D01*
X562843Y38125D01*
X562823Y38165D01*
X562808Y38200D01*
X562788Y38240D01*
X562688Y38380D01*
X562658Y38410D01*
Y41840D01*
X562648Y41965D01*
X562608Y42090D01*
X562548Y42200D01*
X562468Y42300D01*
X562368Y42380D01*
X562258Y42440D01*
X562133Y42480D01*
X562008Y42490D01*
X561883Y42480D01*
X561758Y42440D01*
X561648Y42380D01*
X561548Y42300D01*
X561468Y42200D01*
X561408Y42090D01*
X561368Y41965D01*
X561358Y41840D01*
Y38410D01*
X561328Y38380D01*
X561228Y38240D01*
X561208Y38200D01*
X561193Y38165D01*
X561173Y38125D01*
X561158Y38085D01*
X561148Y38045D01*
X561133Y38000D01*
X561128Y37960D01*
X561118Y37920D01*
X561113Y37875D01*
Y37835D01*
X561108Y37790D01*
X561113Y37745D01*
Y37705D01*
X561118Y37660D01*
X561128Y37620D01*
X561133Y37580D01*
X561148Y37535D01*
X561158Y37495D01*
X561173Y37455D01*
X561193Y37415D01*
X561208Y37380D01*
X561228Y37340D01*
X561328Y37200D01*
X561358Y37170D01*
Y36040D01*
X561368Y35915D01*
X561408Y35790D01*
X561468Y35680D01*
X561548Y35580D01*
X561648Y35500D01*
X561758Y35440D01*
X561883Y35400D01*
X562008Y35390D01*
G37*
G36*
G01X585630D02*
X585755Y35400D01*
X585880Y35440D01*
X585990Y35500D01*
X586090Y35580D01*
X586170Y35680D01*
X586230Y35790D01*
X586270Y35915D01*
X586280Y36040D01*
Y37170D01*
X586310Y37200D01*
X586410Y37340D01*
X586430Y37380D01*
X586445Y37415D01*
X586465Y37455D01*
X586480Y37495D01*
X586490Y37535D01*
X586505Y37580D01*
X586510Y37620D01*
X586520Y37660D01*
X586525Y37705D01*
Y37745D01*
X586530Y37790D01*
X586525Y37835D01*
Y37875D01*
X586520Y37920D01*
X586510Y37960D01*
X586505Y38000D01*
X586490Y38045D01*
X586480Y38085D01*
X586465Y38125D01*
X586445Y38165D01*
X586430Y38200D01*
X586410Y38240D01*
X586310Y38380D01*
X586280Y38410D01*
Y41840D01*
X586270Y41965D01*
X586230Y42090D01*
X586170Y42200D01*
X586090Y42300D01*
X585990Y42380D01*
X585880Y42440D01*
X585755Y42480D01*
X585630Y42490D01*
X585505Y42480D01*
X585380Y42440D01*
X585270Y42380D01*
X585170Y42300D01*
X585090Y42200D01*
X585030Y42090D01*
X584990Y41965D01*
X584980Y41840D01*
Y38410D01*
X584950Y38380D01*
X584850Y38240D01*
X584830Y38200D01*
X584815Y38165D01*
X584795Y38125D01*
X584780Y38085D01*
X584770Y38045D01*
X584755Y38000D01*
X584750Y37960D01*
X584740Y37920D01*
X584735Y37875D01*
Y37835D01*
X584730Y37790D01*
X584735Y37745D01*
Y37705D01*
X584740Y37660D01*
X584750Y37620D01*
X584755Y37580D01*
X584770Y37535D01*
X584780Y37495D01*
X584795Y37455D01*
X584815Y37415D01*
X584830Y37380D01*
X584850Y37340D01*
X584950Y37200D01*
X584980Y37170D01*
Y36040D01*
X584990Y35915D01*
X585030Y35790D01*
X585090Y35680D01*
X585170Y35580D01*
X585270Y35500D01*
X585380Y35440D01*
X585505Y35400D01*
X585630Y35390D01*
G37*
G36*
G01X580905D02*
X581030Y35400D01*
X581155Y35440D01*
X581265Y35500D01*
X581365Y35580D01*
X581445Y35680D01*
X581505Y35790D01*
X581545Y35915D01*
X581555Y36040D01*
Y37170D01*
X581585Y37200D01*
X581685Y37340D01*
X581705Y37380D01*
X581720Y37415D01*
X581740Y37455D01*
X581755Y37495D01*
X581765Y37535D01*
X581780Y37580D01*
X581785Y37620D01*
X581795Y37660D01*
X581800Y37705D01*
Y37745D01*
X581805Y37790D01*
X581800Y37835D01*
Y37875D01*
X581795Y37920D01*
X581785Y37960D01*
X581780Y38000D01*
X581765Y38045D01*
X581755Y38085D01*
X581740Y38125D01*
X581720Y38165D01*
X581705Y38200D01*
X581685Y38240D01*
X581585Y38380D01*
X581555Y38410D01*
Y41840D01*
X581545Y41965D01*
X581505Y42090D01*
X581445Y42200D01*
X581365Y42300D01*
X581265Y42380D01*
X581155Y42440D01*
X581030Y42480D01*
X580905Y42490D01*
X580780Y42480D01*
X580655Y42440D01*
X580545Y42380D01*
X580445Y42300D01*
X580365Y42200D01*
X580305Y42090D01*
X580265Y41965D01*
X580255Y41840D01*
Y38410D01*
X580225Y38380D01*
X580125Y38240D01*
X580105Y38200D01*
X580090Y38165D01*
X580070Y38125D01*
X580055Y38085D01*
X580045Y38045D01*
X580030Y38000D01*
X580025Y37960D01*
X580015Y37920D01*
X580010Y37875D01*
Y37835D01*
X580005Y37790D01*
X580010Y37745D01*
Y37705D01*
X580015Y37660D01*
X580025Y37620D01*
X580030Y37580D01*
X580045Y37535D01*
X580055Y37495D01*
X580070Y37455D01*
X580090Y37415D01*
X580105Y37380D01*
X580125Y37340D01*
X580225Y37200D01*
X580255Y37170D01*
Y36040D01*
X580265Y35915D01*
X580305Y35790D01*
X580365Y35680D01*
X580445Y35580D01*
X580545Y35500D01*
X580655Y35440D01*
X580780Y35400D01*
X580905Y35390D01*
G37*
G36*
G01X576181D02*
X576306Y35400D01*
X576431Y35440D01*
X576541Y35500D01*
X576641Y35580D01*
X576721Y35680D01*
X576781Y35790D01*
X576821Y35915D01*
X576831Y36040D01*
Y37170D01*
X576861Y37200D01*
X576961Y37340D01*
X576981Y37380D01*
X576996Y37415D01*
X577016Y37455D01*
X577031Y37495D01*
X577041Y37535D01*
X577056Y37580D01*
X577061Y37620D01*
X577071Y37660D01*
X577076Y37705D01*
Y37745D01*
X577081Y37790D01*
X577076Y37835D01*
Y37875D01*
X577071Y37920D01*
X577061Y37960D01*
X577056Y38000D01*
X577041Y38045D01*
X577031Y38085D01*
X577016Y38125D01*
X576996Y38165D01*
X576981Y38200D01*
X576961Y38240D01*
X576861Y38380D01*
X576831Y38410D01*
Y41840D01*
X576821Y41965D01*
X576781Y42090D01*
X576721Y42200D01*
X576641Y42300D01*
X576541Y42380D01*
X576431Y42440D01*
X576306Y42480D01*
X576181Y42490D01*
X576056Y42480D01*
X575931Y42440D01*
X575821Y42380D01*
X575721Y42300D01*
X575641Y42200D01*
X575581Y42090D01*
X575541Y41965D01*
X575531Y41840D01*
Y38410D01*
X575501Y38380D01*
X575401Y38240D01*
X575381Y38200D01*
X575366Y38165D01*
X575346Y38125D01*
X575331Y38085D01*
X575321Y38045D01*
X575306Y38000D01*
X575301Y37960D01*
X575291Y37920D01*
X575286Y37875D01*
Y37835D01*
X575281Y37790D01*
X575286Y37745D01*
Y37705D01*
X575291Y37660D01*
X575301Y37620D01*
X575306Y37580D01*
X575321Y37535D01*
X575331Y37495D01*
X575346Y37455D01*
X575366Y37415D01*
X575381Y37380D01*
X575401Y37340D01*
X575501Y37200D01*
X575531Y37170D01*
Y36040D01*
X575541Y35915D01*
X575581Y35790D01*
X575641Y35680D01*
X575721Y35580D01*
X575821Y35500D01*
X575931Y35440D01*
X576056Y35400D01*
X576181Y35390D01*
G37*
G36*
G01X599803D02*
X599928Y35400D01*
X600053Y35440D01*
X600163Y35500D01*
X600263Y35580D01*
X600343Y35680D01*
X600403Y35790D01*
X600443Y35915D01*
X600453Y36040D01*
Y37170D01*
X600483Y37200D01*
X600583Y37340D01*
X600603Y37380D01*
X600618Y37415D01*
X600638Y37455D01*
X600653Y37495D01*
X600663Y37535D01*
X600678Y37580D01*
X600683Y37620D01*
X600693Y37660D01*
X600698Y37705D01*
Y37745D01*
X600703Y37790D01*
X600698Y37835D01*
Y37875D01*
X600693Y37920D01*
X600683Y37960D01*
X600678Y38000D01*
X600663Y38045D01*
X600653Y38085D01*
X600638Y38125D01*
X600618Y38165D01*
X600603Y38200D01*
X600583Y38240D01*
X600483Y38380D01*
X600453Y38410D01*
Y41840D01*
X600443Y41965D01*
X600403Y42090D01*
X600343Y42200D01*
X600263Y42300D01*
X600163Y42380D01*
X600053Y42440D01*
X599928Y42480D01*
X599803Y42490D01*
X599678Y42480D01*
X599553Y42440D01*
X599443Y42380D01*
X599343Y42300D01*
X599263Y42200D01*
X599203Y42090D01*
X599163Y41965D01*
X599153Y41840D01*
Y38410D01*
X599123Y38380D01*
X599023Y38240D01*
X599003Y38200D01*
X598988Y38165D01*
X598968Y38125D01*
X598953Y38085D01*
X598943Y38045D01*
X598928Y38000D01*
X598923Y37960D01*
X598913Y37920D01*
X598908Y37875D01*
Y37835D01*
X598903Y37790D01*
X598908Y37745D01*
Y37705D01*
X598913Y37660D01*
X598923Y37620D01*
X598928Y37580D01*
X598943Y37535D01*
X598953Y37495D01*
X598968Y37455D01*
X598988Y37415D01*
X599003Y37380D01*
X599023Y37340D01*
X599123Y37200D01*
X599153Y37170D01*
Y36040D01*
X599163Y35915D01*
X599203Y35790D01*
X599263Y35680D01*
X599343Y35580D01*
X599443Y35500D01*
X599553Y35440D01*
X599678Y35400D01*
X599803Y35390D01*
G37*
G36*
G01X618701D02*
X618826Y35400D01*
X618951Y35440D01*
X619061Y35500D01*
X619161Y35580D01*
X619241Y35680D01*
X619301Y35790D01*
X619341Y35915D01*
X619351Y36040D01*
Y37170D01*
X619381Y37200D01*
X619481Y37340D01*
X619501Y37380D01*
X619516Y37415D01*
X619536Y37455D01*
X619551Y37495D01*
X619561Y37535D01*
X619576Y37580D01*
X619581Y37620D01*
X619591Y37660D01*
X619596Y37705D01*
Y37745D01*
X619601Y37790D01*
X619596Y37835D01*
Y37875D01*
X619591Y37920D01*
X619581Y37960D01*
X619576Y38000D01*
X619561Y38045D01*
X619551Y38085D01*
X619536Y38125D01*
X619516Y38165D01*
X619501Y38200D01*
X619481Y38240D01*
X619381Y38380D01*
X619351Y38410D01*
Y41840D01*
X619341Y41965D01*
X619301Y42090D01*
X619241Y42200D01*
X619161Y42300D01*
X619061Y42380D01*
X618951Y42440D01*
X618826Y42480D01*
X618701Y42490D01*
X618576Y42480D01*
X618451Y42440D01*
X618341Y42380D01*
X618241Y42300D01*
X618161Y42200D01*
X618101Y42090D01*
X618061Y41965D01*
X618051Y41840D01*
Y38410D01*
X618021Y38380D01*
X617921Y38240D01*
X617901Y38200D01*
X617886Y38165D01*
X617866Y38125D01*
X617851Y38085D01*
X617841Y38045D01*
X617826Y38000D01*
X617821Y37960D01*
X617811Y37920D01*
X617806Y37875D01*
Y37835D01*
X617801Y37790D01*
X617806Y37745D01*
Y37705D01*
X617811Y37660D01*
X617821Y37620D01*
X617826Y37580D01*
X617841Y37535D01*
X617851Y37495D01*
X617866Y37455D01*
X617886Y37415D01*
X617901Y37380D01*
X617921Y37340D01*
X618021Y37200D01*
X618051Y37170D01*
Y36040D01*
X618061Y35915D01*
X618101Y35790D01*
X618161Y35680D01*
X618241Y35580D01*
X618341Y35500D01*
X618451Y35440D01*
X618576Y35400D01*
X618701Y35390D01*
G37*
G36*
G01X613976D02*
X614101Y35400D01*
X614226Y35440D01*
X614336Y35500D01*
X614436Y35580D01*
X614516Y35680D01*
X614576Y35790D01*
X614616Y35915D01*
X614626Y36040D01*
Y37170D01*
X614656Y37200D01*
X614756Y37340D01*
X614776Y37380D01*
X614791Y37415D01*
X614811Y37455D01*
X614826Y37495D01*
X614836Y37535D01*
X614851Y37580D01*
X614856Y37620D01*
X614866Y37660D01*
X614871Y37705D01*
Y37745D01*
X614876Y37790D01*
X614871Y37835D01*
Y37875D01*
X614866Y37920D01*
X614856Y37960D01*
X614851Y38000D01*
X614836Y38045D01*
X614826Y38085D01*
X614811Y38125D01*
X614791Y38165D01*
X614776Y38200D01*
X614756Y38240D01*
X614656Y38380D01*
X614626Y38410D01*
Y41840D01*
X614616Y41965D01*
X614576Y42090D01*
X614516Y42200D01*
X614436Y42300D01*
X614336Y42380D01*
X614226Y42440D01*
X614101Y42480D01*
X613976Y42490D01*
X613851Y42480D01*
X613726Y42440D01*
X613616Y42380D01*
X613516Y42300D01*
X613436Y42200D01*
X613376Y42090D01*
X613336Y41965D01*
X613326Y41840D01*
Y38410D01*
X613296Y38380D01*
X613196Y38240D01*
X613176Y38200D01*
X613161Y38165D01*
X613141Y38125D01*
X613126Y38085D01*
X613116Y38045D01*
X613101Y38000D01*
X613096Y37960D01*
X613086Y37920D01*
X613081Y37875D01*
Y37835D01*
X613076Y37790D01*
X613081Y37745D01*
Y37705D01*
X613086Y37660D01*
X613096Y37620D01*
X613101Y37580D01*
X613116Y37535D01*
X613126Y37495D01*
X613141Y37455D01*
X613161Y37415D01*
X613176Y37380D01*
X613196Y37340D01*
X613296Y37200D01*
X613326Y37170D01*
Y36040D01*
X613336Y35915D01*
X613376Y35790D01*
X613436Y35680D01*
X613516Y35580D01*
X613616Y35500D01*
X613726Y35440D01*
X613851Y35400D01*
X613976Y35390D01*
G37*
G36*
G01X609252D02*
X609377Y35400D01*
X609502Y35440D01*
X609612Y35500D01*
X609712Y35580D01*
X609792Y35680D01*
X609852Y35790D01*
X609892Y35915D01*
X609902Y36040D01*
Y37170D01*
X609932Y37200D01*
X610032Y37340D01*
X610052Y37380D01*
X610067Y37415D01*
X610087Y37455D01*
X610102Y37495D01*
X610112Y37535D01*
X610127Y37580D01*
X610132Y37620D01*
X610142Y37660D01*
X610147Y37705D01*
Y37745D01*
X610152Y37790D01*
X610147Y37835D01*
Y37875D01*
X610142Y37920D01*
X610132Y37960D01*
X610127Y38000D01*
X610112Y38045D01*
X610102Y38085D01*
X610087Y38125D01*
X610067Y38165D01*
X610052Y38200D01*
X610032Y38240D01*
X609932Y38380D01*
X609902Y38410D01*
Y41840D01*
X609892Y41965D01*
X609852Y42090D01*
X609792Y42200D01*
X609712Y42300D01*
X609612Y42380D01*
X609502Y42440D01*
X609377Y42480D01*
X609252Y42490D01*
X609127Y42480D01*
X609002Y42440D01*
X608892Y42380D01*
X608792Y42300D01*
X608712Y42200D01*
X608652Y42090D01*
X608612Y41965D01*
X608602Y41840D01*
Y38410D01*
X608572Y38380D01*
X608472Y38240D01*
X608452Y38200D01*
X608437Y38165D01*
X608417Y38125D01*
X608402Y38085D01*
X608392Y38045D01*
X608377Y38000D01*
X608372Y37960D01*
X608362Y37920D01*
X608357Y37875D01*
Y37835D01*
X608352Y37790D01*
X608357Y37745D01*
Y37705D01*
X608362Y37660D01*
X608372Y37620D01*
X608377Y37580D01*
X608392Y37535D01*
X608402Y37495D01*
X608417Y37455D01*
X608437Y37415D01*
X608452Y37380D01*
X608472Y37340D01*
X608572Y37200D01*
X608602Y37170D01*
Y36040D01*
X608612Y35915D01*
X608652Y35790D01*
X608712Y35680D01*
X608792Y35580D01*
X608892Y35500D01*
X609002Y35440D01*
X609127Y35400D01*
X609252Y35390D01*
G37*
G36*
G01X604527D02*
X604652Y35400D01*
X604777Y35440D01*
X604887Y35500D01*
X604987Y35580D01*
X605067Y35680D01*
X605127Y35790D01*
X605167Y35915D01*
X605177Y36040D01*
Y37170D01*
X605207Y37200D01*
X605307Y37340D01*
X605327Y37380D01*
X605342Y37415D01*
X605362Y37455D01*
X605377Y37495D01*
X605387Y37535D01*
X605402Y37580D01*
X605407Y37620D01*
X605417Y37660D01*
X605422Y37705D01*
Y37745D01*
X605427Y37790D01*
X605422Y37835D01*
Y37875D01*
X605417Y37920D01*
X605407Y37960D01*
X605402Y38000D01*
X605387Y38045D01*
X605377Y38085D01*
X605362Y38125D01*
X605342Y38165D01*
X605327Y38200D01*
X605307Y38240D01*
X605207Y38380D01*
X605177Y38410D01*
Y41840D01*
X605167Y41965D01*
X605127Y42090D01*
X605067Y42200D01*
X604987Y42300D01*
X604887Y42380D01*
X604777Y42440D01*
X604652Y42480D01*
X604527Y42490D01*
X604402Y42480D01*
X604277Y42440D01*
X604167Y42380D01*
X604067Y42300D01*
X603987Y42200D01*
X603927Y42090D01*
X603887Y41965D01*
X603877Y41840D01*
Y38410D01*
X603847Y38380D01*
X603747Y38240D01*
X603727Y38200D01*
X603712Y38165D01*
X603692Y38125D01*
X603677Y38085D01*
X603667Y38045D01*
X603652Y38000D01*
X603647Y37960D01*
X603637Y37920D01*
X603632Y37875D01*
Y37835D01*
X603627Y37790D01*
X603632Y37745D01*
Y37705D01*
X603637Y37660D01*
X603647Y37620D01*
X603652Y37580D01*
X603667Y37535D01*
X603677Y37495D01*
X603692Y37455D01*
X603712Y37415D01*
X603727Y37380D01*
X603747Y37340D01*
X603847Y37200D01*
X603877Y37170D01*
Y36040D01*
X603887Y35915D01*
X603927Y35790D01*
X603987Y35680D01*
X604067Y35580D01*
X604167Y35500D01*
X604277Y35440D01*
X604402Y35400D01*
X604527Y35390D01*
G37*
G36*
G01X632874D02*
X632999Y35400D01*
X633124Y35440D01*
X633234Y35500D01*
X633334Y35580D01*
X633414Y35680D01*
X633474Y35790D01*
X633514Y35915D01*
X633524Y36040D01*
Y37170D01*
X633554Y37200D01*
X633654Y37340D01*
X633674Y37380D01*
X633689Y37415D01*
X633709Y37455D01*
X633724Y37495D01*
X633734Y37535D01*
X633749Y37580D01*
X633754Y37620D01*
X633764Y37660D01*
X633769Y37705D01*
Y37745D01*
X633774Y37790D01*
X633769Y37835D01*
Y37875D01*
X633764Y37920D01*
X633754Y37960D01*
X633749Y38000D01*
X633734Y38045D01*
X633724Y38085D01*
X633709Y38125D01*
X633689Y38165D01*
X633674Y38200D01*
X633654Y38240D01*
X633554Y38380D01*
X633524Y38410D01*
Y41840D01*
X633514Y41965D01*
X633474Y42090D01*
X633414Y42200D01*
X633334Y42300D01*
X633234Y42380D01*
X633124Y42440D01*
X632999Y42480D01*
X632874Y42490D01*
X632749Y42480D01*
X632624Y42440D01*
X632514Y42380D01*
X632414Y42300D01*
X632334Y42200D01*
X632274Y42090D01*
X632234Y41965D01*
X632224Y41840D01*
Y38410D01*
X632194Y38380D01*
X632094Y38240D01*
X632074Y38200D01*
X632059Y38165D01*
X632039Y38125D01*
X632024Y38085D01*
X632014Y38045D01*
X631999Y38000D01*
X631994Y37960D01*
X631984Y37920D01*
X631979Y37875D01*
Y37835D01*
X631974Y37790D01*
X631979Y37745D01*
Y37705D01*
X631984Y37660D01*
X631994Y37620D01*
X631999Y37580D01*
X632014Y37535D01*
X632024Y37495D01*
X632039Y37455D01*
X632059Y37415D01*
X632074Y37380D01*
X632094Y37340D01*
X632194Y37200D01*
X632224Y37170D01*
Y36040D01*
X632234Y35915D01*
X632274Y35790D01*
X632334Y35680D01*
X632414Y35580D01*
X632514Y35500D01*
X632624Y35440D01*
X632749Y35400D01*
X632874Y35390D01*
G37*
G36*
G01X628149D02*
X628274Y35400D01*
X628399Y35440D01*
X628509Y35500D01*
X628609Y35580D01*
X628689Y35680D01*
X628749Y35790D01*
X628789Y35915D01*
X628799Y36040D01*
Y37170D01*
X628829Y37200D01*
X628929Y37340D01*
X628949Y37380D01*
X628964Y37415D01*
X628984Y37455D01*
X628999Y37495D01*
X629009Y37535D01*
X629024Y37580D01*
X629029Y37620D01*
X629039Y37660D01*
X629044Y37705D01*
Y37745D01*
X629049Y37790D01*
X629044Y37835D01*
Y37875D01*
X629039Y37920D01*
X629029Y37960D01*
X629024Y38000D01*
X629009Y38045D01*
X628999Y38085D01*
X628984Y38125D01*
X628964Y38165D01*
X628949Y38200D01*
X628929Y38240D01*
X628829Y38380D01*
X628799Y38410D01*
Y41840D01*
X628789Y41965D01*
X628749Y42090D01*
X628689Y42200D01*
X628609Y42300D01*
X628509Y42380D01*
X628399Y42440D01*
X628274Y42480D01*
X628149Y42490D01*
X628024Y42480D01*
X627899Y42440D01*
X627789Y42380D01*
X627689Y42300D01*
X627609Y42200D01*
X627549Y42090D01*
X627509Y41965D01*
X627499Y41840D01*
Y38410D01*
X627469Y38380D01*
X627369Y38240D01*
X627349Y38200D01*
X627334Y38165D01*
X627314Y38125D01*
X627299Y38085D01*
X627289Y38045D01*
X627274Y38000D01*
X627269Y37960D01*
X627259Y37920D01*
X627254Y37875D01*
Y37835D01*
X627249Y37790D01*
X627254Y37745D01*
Y37705D01*
X627259Y37660D01*
X627269Y37620D01*
X627274Y37580D01*
X627289Y37535D01*
X627299Y37495D01*
X627314Y37455D01*
X627334Y37415D01*
X627349Y37380D01*
X627369Y37340D01*
X627469Y37200D01*
X627499Y37170D01*
Y36040D01*
X627509Y35915D01*
X627549Y35790D01*
X627609Y35680D01*
X627689Y35580D01*
X627789Y35500D01*
X627899Y35440D01*
X628024Y35400D01*
X628149Y35390D01*
G37*
G36*
G01X623425D02*
X623550Y35400D01*
X623675Y35440D01*
X623785Y35500D01*
X623885Y35580D01*
X623965Y35680D01*
X624025Y35790D01*
X624065Y35915D01*
X624075Y36040D01*
Y37170D01*
X624105Y37200D01*
X624205Y37340D01*
X624225Y37380D01*
X624240Y37415D01*
X624260Y37455D01*
X624275Y37495D01*
X624285Y37535D01*
X624300Y37580D01*
X624305Y37620D01*
X624315Y37660D01*
X624320Y37705D01*
Y37745D01*
X624325Y37790D01*
X624320Y37835D01*
Y37875D01*
X624315Y37920D01*
X624305Y37960D01*
X624300Y38000D01*
X624285Y38045D01*
X624275Y38085D01*
X624260Y38125D01*
X624240Y38165D01*
X624225Y38200D01*
X624205Y38240D01*
X624105Y38380D01*
X624075Y38410D01*
Y41840D01*
X624065Y41965D01*
X624025Y42090D01*
X623965Y42200D01*
X623885Y42300D01*
X623785Y42380D01*
X623675Y42440D01*
X623550Y42480D01*
X623425Y42490D01*
X623300Y42480D01*
X623175Y42440D01*
X623065Y42380D01*
X622965Y42300D01*
X622885Y42200D01*
X622825Y42090D01*
X622785Y41965D01*
X622775Y41840D01*
Y38410D01*
X622745Y38380D01*
X622645Y38240D01*
X622625Y38200D01*
X622610Y38165D01*
X622590Y38125D01*
X622575Y38085D01*
X622565Y38045D01*
X622550Y38000D01*
X622545Y37960D01*
X622535Y37920D01*
X622530Y37875D01*
Y37835D01*
X622525Y37790D01*
X622530Y37745D01*
Y37705D01*
X622535Y37660D01*
X622545Y37620D01*
X622550Y37580D01*
X622565Y37535D01*
X622575Y37495D01*
X622590Y37455D01*
X622610Y37415D01*
X622625Y37380D01*
X622645Y37340D01*
X622745Y37200D01*
X622775Y37170D01*
Y36040D01*
X622785Y35915D01*
X622825Y35790D01*
X622885Y35680D01*
X622965Y35580D01*
X623065Y35500D01*
X623175Y35440D01*
X623300Y35400D01*
X623425Y35390D01*
G37*
G36*
G01X647047D02*
X647172Y35400D01*
X647297Y35440D01*
X647407Y35500D01*
X647507Y35580D01*
X647587Y35680D01*
X647647Y35790D01*
X647687Y35915D01*
X647697Y36040D01*
Y37170D01*
X647727Y37200D01*
X647827Y37340D01*
X647847Y37380D01*
X647862Y37415D01*
X647882Y37455D01*
X647897Y37495D01*
X647907Y37535D01*
X647922Y37580D01*
X647927Y37620D01*
X647937Y37660D01*
X647942Y37705D01*
Y37745D01*
X647947Y37790D01*
X647942Y37835D01*
Y37875D01*
X647937Y37920D01*
X647927Y37960D01*
X647922Y38000D01*
X647907Y38045D01*
X647897Y38085D01*
X647882Y38125D01*
X647862Y38165D01*
X647847Y38200D01*
X647827Y38240D01*
X647727Y38380D01*
X647697Y38410D01*
Y41840D01*
X647687Y41965D01*
X647647Y42090D01*
X647587Y42200D01*
X647507Y42300D01*
X647407Y42380D01*
X647297Y42440D01*
X647172Y42480D01*
X647047Y42490D01*
X646922Y42480D01*
X646797Y42440D01*
X646687Y42380D01*
X646587Y42300D01*
X646507Y42200D01*
X646447Y42090D01*
X646407Y41965D01*
X646397Y41840D01*
Y38410D01*
X646367Y38380D01*
X646267Y38240D01*
X646247Y38200D01*
X646232Y38165D01*
X646212Y38125D01*
X646197Y38085D01*
X646187Y38045D01*
X646172Y38000D01*
X646167Y37960D01*
X646157Y37920D01*
X646152Y37875D01*
Y37835D01*
X646147Y37790D01*
X646152Y37745D01*
Y37705D01*
X646157Y37660D01*
X646167Y37620D01*
X646172Y37580D01*
X646187Y37535D01*
X646197Y37495D01*
X646212Y37455D01*
X646232Y37415D01*
X646247Y37380D01*
X646267Y37340D01*
X646367Y37200D01*
X646397Y37170D01*
Y36040D01*
X646407Y35915D01*
X646447Y35790D01*
X646507Y35680D01*
X646587Y35580D01*
X646687Y35500D01*
X646797Y35440D01*
X646922Y35400D01*
X647047Y35390D01*
G37*
G36*
G01X642323D02*
X642448Y35400D01*
X642573Y35440D01*
X642683Y35500D01*
X642783Y35580D01*
X642863Y35680D01*
X642923Y35790D01*
X642963Y35915D01*
X642973Y36040D01*
Y37170D01*
X643003Y37200D01*
X643103Y37340D01*
X643123Y37380D01*
X643138Y37415D01*
X643158Y37455D01*
X643173Y37495D01*
X643183Y37535D01*
X643198Y37580D01*
X643203Y37620D01*
X643213Y37660D01*
X643218Y37705D01*
Y37745D01*
X643223Y37790D01*
X643218Y37835D01*
Y37875D01*
X643213Y37920D01*
X643203Y37960D01*
X643198Y38000D01*
X643183Y38045D01*
X643173Y38085D01*
X643158Y38125D01*
X643138Y38165D01*
X643123Y38200D01*
X643103Y38240D01*
X643003Y38380D01*
X642973Y38410D01*
Y41840D01*
X642963Y41965D01*
X642923Y42090D01*
X642863Y42200D01*
X642783Y42300D01*
X642683Y42380D01*
X642573Y42440D01*
X642448Y42480D01*
X642323Y42490D01*
X642198Y42480D01*
X642073Y42440D01*
X641963Y42380D01*
X641863Y42300D01*
X641783Y42200D01*
X641723Y42090D01*
X641683Y41965D01*
X641673Y41840D01*
Y38410D01*
X641643Y38380D01*
X641543Y38240D01*
X641523Y38200D01*
X641508Y38165D01*
X641488Y38125D01*
X641473Y38085D01*
X641463Y38045D01*
X641448Y38000D01*
X641443Y37960D01*
X641433Y37920D01*
X641428Y37875D01*
Y37835D01*
X641423Y37790D01*
X641428Y37745D01*
Y37705D01*
X641433Y37660D01*
X641443Y37620D01*
X641448Y37580D01*
X641463Y37535D01*
X641473Y37495D01*
X641488Y37455D01*
X641508Y37415D01*
X641523Y37380D01*
X641543Y37340D01*
X641643Y37200D01*
X641673Y37170D01*
Y36040D01*
X641683Y35915D01*
X641723Y35790D01*
X641783Y35680D01*
X641863Y35580D01*
X641963Y35500D01*
X642073Y35440D01*
X642198Y35400D01*
X642323Y35390D01*
G37*
G36*
G01X637598D02*
X637723Y35400D01*
X637848Y35440D01*
X637958Y35500D01*
X638058Y35580D01*
X638138Y35680D01*
X638198Y35790D01*
X638238Y35915D01*
X638248Y36040D01*
Y37170D01*
X638278Y37200D01*
X638378Y37340D01*
X638398Y37380D01*
X638413Y37415D01*
X638433Y37455D01*
X638448Y37495D01*
X638458Y37535D01*
X638473Y37580D01*
X638478Y37620D01*
X638488Y37660D01*
X638493Y37705D01*
Y37745D01*
X638498Y37790D01*
X638493Y37835D01*
Y37875D01*
X638488Y37920D01*
X638478Y37960D01*
X638473Y38000D01*
X638458Y38045D01*
X638448Y38085D01*
X638433Y38125D01*
X638413Y38165D01*
X638398Y38200D01*
X638378Y38240D01*
X638278Y38380D01*
X638248Y38410D01*
Y41840D01*
X638238Y41965D01*
X638198Y42090D01*
X638138Y42200D01*
X638058Y42300D01*
X637958Y42380D01*
X637848Y42440D01*
X637723Y42480D01*
X637598Y42490D01*
X637473Y42480D01*
X637348Y42440D01*
X637238Y42380D01*
X637138Y42300D01*
X637058Y42200D01*
X636998Y42090D01*
X636958Y41965D01*
X636948Y41840D01*
Y38410D01*
X636918Y38380D01*
X636818Y38240D01*
X636798Y38200D01*
X636783Y38165D01*
X636763Y38125D01*
X636748Y38085D01*
X636738Y38045D01*
X636723Y38000D01*
X636718Y37960D01*
X636708Y37920D01*
X636703Y37875D01*
Y37835D01*
X636698Y37790D01*
X636703Y37745D01*
Y37705D01*
X636708Y37660D01*
X636718Y37620D01*
X636723Y37580D01*
X636738Y37535D01*
X636748Y37495D01*
X636763Y37455D01*
X636783Y37415D01*
X636798Y37380D01*
X636818Y37340D01*
X636918Y37200D01*
X636948Y37170D01*
Y36040D01*
X636958Y35915D01*
X636998Y35790D01*
X637058Y35680D01*
X637138Y35580D01*
X637238Y35500D01*
X637348Y35440D01*
X637473Y35400D01*
X637598Y35390D01*
G37*
G36*
G01X661220D02*
X661345Y35400D01*
X661470Y35440D01*
X661580Y35500D01*
X661680Y35580D01*
X661760Y35680D01*
X661820Y35790D01*
X661860Y35915D01*
X661870Y36040D01*
Y37170D01*
X661900Y37200D01*
X662000Y37340D01*
X662020Y37380D01*
X662035Y37415D01*
X662055Y37455D01*
X662070Y37495D01*
X662080Y37535D01*
X662095Y37580D01*
X662100Y37620D01*
X662110Y37660D01*
X662115Y37705D01*
Y37745D01*
X662120Y37790D01*
X662115Y37835D01*
Y37875D01*
X662110Y37920D01*
X662100Y37960D01*
X662095Y38000D01*
X662080Y38045D01*
X662070Y38085D01*
X662055Y38125D01*
X662035Y38165D01*
X662020Y38200D01*
X662000Y38240D01*
X661900Y38380D01*
X661870Y38410D01*
Y41840D01*
X661860Y41965D01*
X661820Y42090D01*
X661760Y42200D01*
X661680Y42300D01*
X661580Y42380D01*
X661470Y42440D01*
X661345Y42480D01*
X661220Y42490D01*
X661095Y42480D01*
X660970Y42440D01*
X660860Y42380D01*
X660760Y42300D01*
X660680Y42200D01*
X660620Y42090D01*
X660580Y41965D01*
X660570Y41840D01*
Y38410D01*
X660540Y38380D01*
X660440Y38240D01*
X660420Y38200D01*
X660405Y38165D01*
X660385Y38125D01*
X660370Y38085D01*
X660360Y38045D01*
X660345Y38000D01*
X660340Y37960D01*
X660330Y37920D01*
X660325Y37875D01*
Y37835D01*
X660320Y37790D01*
X660325Y37745D01*
Y37705D01*
X660330Y37660D01*
X660340Y37620D01*
X660345Y37580D01*
X660360Y37535D01*
X660370Y37495D01*
X660385Y37455D01*
X660405Y37415D01*
X660420Y37380D01*
X660440Y37340D01*
X660540Y37200D01*
X660570Y37170D01*
Y36040D01*
X660580Y35915D01*
X660620Y35790D01*
X660680Y35680D01*
X660760Y35580D01*
X660860Y35500D01*
X660970Y35440D01*
X661095Y35400D01*
X661220Y35390D01*
G37*
G36*
G01X656496D02*
X656621Y35400D01*
X656746Y35440D01*
X656856Y35500D01*
X656956Y35580D01*
X657036Y35680D01*
X657096Y35790D01*
X657136Y35915D01*
X657146Y36040D01*
Y37170D01*
X657176Y37200D01*
X657276Y37340D01*
X657296Y37380D01*
X657311Y37415D01*
X657331Y37455D01*
X657346Y37495D01*
X657356Y37535D01*
X657371Y37580D01*
X657376Y37620D01*
X657386Y37660D01*
X657391Y37705D01*
Y37745D01*
X657396Y37790D01*
X657391Y37835D01*
Y37875D01*
X657386Y37920D01*
X657376Y37960D01*
X657371Y38000D01*
X657356Y38045D01*
X657346Y38085D01*
X657331Y38125D01*
X657311Y38165D01*
X657296Y38200D01*
X657276Y38240D01*
X657176Y38380D01*
X657146Y38410D01*
Y41840D01*
X657136Y41965D01*
X657096Y42090D01*
X657036Y42200D01*
X656956Y42300D01*
X656856Y42380D01*
X656746Y42440D01*
X656621Y42480D01*
X656496Y42490D01*
X656371Y42480D01*
X656246Y42440D01*
X656136Y42380D01*
X656036Y42300D01*
X655956Y42200D01*
X655896Y42090D01*
X655856Y41965D01*
X655846Y41840D01*
Y38410D01*
X655816Y38380D01*
X655716Y38240D01*
X655696Y38200D01*
X655681Y38165D01*
X655661Y38125D01*
X655646Y38085D01*
X655636Y38045D01*
X655621Y38000D01*
X655616Y37960D01*
X655606Y37920D01*
X655601Y37875D01*
Y37835D01*
X655596Y37790D01*
X655601Y37745D01*
Y37705D01*
X655606Y37660D01*
X655616Y37620D01*
X655621Y37580D01*
X655636Y37535D01*
X655646Y37495D01*
X655661Y37455D01*
X655681Y37415D01*
X655696Y37380D01*
X655716Y37340D01*
X655816Y37200D01*
X655846Y37170D01*
Y36040D01*
X655856Y35915D01*
X655896Y35790D01*
X655956Y35680D01*
X656036Y35580D01*
X656136Y35500D01*
X656246Y35440D01*
X656371Y35400D01*
X656496Y35390D01*
G37*
G36*
G01X651771D02*
X651896Y35400D01*
X652021Y35440D01*
X652131Y35500D01*
X652231Y35580D01*
X652311Y35680D01*
X652371Y35790D01*
X652411Y35915D01*
X652421Y36040D01*
Y37170D01*
X652451Y37200D01*
X652551Y37340D01*
X652571Y37380D01*
X652586Y37415D01*
X652606Y37455D01*
X652621Y37495D01*
X652631Y37535D01*
X652646Y37580D01*
X652651Y37620D01*
X652661Y37660D01*
X652666Y37705D01*
Y37745D01*
X652671Y37790D01*
X652666Y37835D01*
Y37875D01*
X652661Y37920D01*
X652651Y37960D01*
X652646Y38000D01*
X652631Y38045D01*
X652621Y38085D01*
X652606Y38125D01*
X652586Y38165D01*
X652571Y38200D01*
X652551Y38240D01*
X652451Y38380D01*
X652421Y38410D01*
Y41840D01*
X652411Y41965D01*
X652371Y42090D01*
X652311Y42200D01*
X652231Y42300D01*
X652131Y42380D01*
X652021Y42440D01*
X651896Y42480D01*
X651771Y42490D01*
X651646Y42480D01*
X651521Y42440D01*
X651411Y42380D01*
X651311Y42300D01*
X651231Y42200D01*
X651171Y42090D01*
X651131Y41965D01*
X651121Y41840D01*
Y38410D01*
X651091Y38380D01*
X650991Y38240D01*
X650971Y38200D01*
X650956Y38165D01*
X650936Y38125D01*
X650921Y38085D01*
X650911Y38045D01*
X650896Y38000D01*
X650891Y37960D01*
X650881Y37920D01*
X650876Y37875D01*
Y37835D01*
X650871Y37790D01*
X650876Y37745D01*
Y37705D01*
X650881Y37660D01*
X650891Y37620D01*
X650896Y37580D01*
X650911Y37535D01*
X650921Y37495D01*
X650936Y37455D01*
X650956Y37415D01*
X650971Y37380D01*
X650991Y37340D01*
X651091Y37200D01*
X651121Y37170D01*
Y36040D01*
X651131Y35915D01*
X651171Y35790D01*
X651231Y35680D01*
X651311Y35580D01*
X651411Y35500D01*
X651521Y35440D01*
X651646Y35400D01*
X651771Y35390D01*
G37*
G36*
G01X680118D02*
X680243Y35400D01*
X680368Y35440D01*
X680478Y35500D01*
X680578Y35580D01*
X680658Y35680D01*
X680718Y35790D01*
X680758Y35915D01*
X680768Y36040D01*
Y37170D01*
X680798Y37200D01*
X680898Y37340D01*
X680918Y37380D01*
X680933Y37415D01*
X680953Y37455D01*
X680968Y37495D01*
X680978Y37535D01*
X680993Y37580D01*
X680998Y37620D01*
X681008Y37660D01*
X681013Y37705D01*
Y37745D01*
X681018Y37790D01*
X681013Y37835D01*
Y37875D01*
X681008Y37920D01*
X680998Y37960D01*
X680993Y38000D01*
X680978Y38045D01*
X680968Y38085D01*
X680953Y38125D01*
X680933Y38165D01*
X680918Y38200D01*
X680898Y38240D01*
X680798Y38380D01*
X680768Y38410D01*
Y41840D01*
X680758Y41965D01*
X680718Y42090D01*
X680658Y42200D01*
X680578Y42300D01*
X680478Y42380D01*
X680368Y42440D01*
X680243Y42480D01*
X680118Y42490D01*
X679993Y42480D01*
X679868Y42440D01*
X679758Y42380D01*
X679658Y42300D01*
X679578Y42200D01*
X679518Y42090D01*
X679478Y41965D01*
X679468Y41840D01*
Y38410D01*
X679438Y38380D01*
X679338Y38240D01*
X679318Y38200D01*
X679303Y38165D01*
X679283Y38125D01*
X679268Y38085D01*
X679258Y38045D01*
X679243Y38000D01*
X679238Y37960D01*
X679228Y37920D01*
X679223Y37875D01*
Y37835D01*
X679218Y37790D01*
X679223Y37745D01*
Y37705D01*
X679228Y37660D01*
X679238Y37620D01*
X679243Y37580D01*
X679258Y37535D01*
X679268Y37495D01*
X679283Y37455D01*
X679303Y37415D01*
X679318Y37380D01*
X679338Y37340D01*
X679438Y37200D01*
X679468Y37170D01*
Y36040D01*
X679478Y35915D01*
X679518Y35790D01*
X679578Y35680D01*
X679658Y35580D01*
X679758Y35500D01*
X679868Y35440D01*
X679993Y35400D01*
X680118Y35390D01*
G37*
G36*
G01X675393D02*
X675518Y35400D01*
X675643Y35440D01*
X675753Y35500D01*
X675853Y35580D01*
X675933Y35680D01*
X675993Y35790D01*
X676033Y35915D01*
X676043Y36040D01*
Y37170D01*
X676073Y37200D01*
X676173Y37340D01*
X676193Y37380D01*
X676208Y37415D01*
X676228Y37455D01*
X676243Y37495D01*
X676253Y37535D01*
X676268Y37580D01*
X676273Y37620D01*
X676283Y37660D01*
X676288Y37705D01*
Y37745D01*
X676293Y37790D01*
X676288Y37835D01*
Y37875D01*
X676283Y37920D01*
X676273Y37960D01*
X676268Y38000D01*
X676253Y38045D01*
X676243Y38085D01*
X676228Y38125D01*
X676208Y38165D01*
X676193Y38200D01*
X676173Y38240D01*
X676073Y38380D01*
X676043Y38410D01*
Y41840D01*
X676033Y41965D01*
X675993Y42090D01*
X675933Y42200D01*
X675853Y42300D01*
X675753Y42380D01*
X675643Y42440D01*
X675518Y42480D01*
X675393Y42490D01*
X675268Y42480D01*
X675143Y42440D01*
X675033Y42380D01*
X674933Y42300D01*
X674853Y42200D01*
X674793Y42090D01*
X674753Y41965D01*
X674743Y41840D01*
Y38410D01*
X674713Y38380D01*
X674613Y38240D01*
X674593Y38200D01*
X674578Y38165D01*
X674558Y38125D01*
X674543Y38085D01*
X674533Y38045D01*
X674518Y38000D01*
X674513Y37960D01*
X674503Y37920D01*
X674498Y37875D01*
Y37835D01*
X674493Y37790D01*
X674498Y37745D01*
Y37705D01*
X674503Y37660D01*
X674513Y37620D01*
X674518Y37580D01*
X674533Y37535D01*
X674543Y37495D01*
X674558Y37455D01*
X674578Y37415D01*
X674593Y37380D01*
X674613Y37340D01*
X674713Y37200D01*
X674743Y37170D01*
Y36040D01*
X674753Y35915D01*
X674793Y35790D01*
X674853Y35680D01*
X674933Y35580D01*
X675033Y35500D01*
X675143Y35440D01*
X675268Y35400D01*
X675393Y35390D01*
G37*
G36*
G01X670669D02*
X670794Y35400D01*
X670919Y35440D01*
X671029Y35500D01*
X671129Y35580D01*
X671209Y35680D01*
X671269Y35790D01*
X671309Y35915D01*
X671319Y36040D01*
Y37170D01*
X671349Y37200D01*
X671449Y37340D01*
X671469Y37380D01*
X671484Y37415D01*
X671504Y37455D01*
X671519Y37495D01*
X671529Y37535D01*
X671544Y37580D01*
X671549Y37620D01*
X671559Y37660D01*
X671564Y37705D01*
Y37745D01*
X671569Y37790D01*
X671564Y37835D01*
Y37875D01*
X671559Y37920D01*
X671549Y37960D01*
X671544Y38000D01*
X671529Y38045D01*
X671519Y38085D01*
X671504Y38125D01*
X671484Y38165D01*
X671469Y38200D01*
X671449Y38240D01*
X671349Y38380D01*
X671319Y38410D01*
Y41840D01*
X671309Y41965D01*
X671269Y42090D01*
X671209Y42200D01*
X671129Y42300D01*
X671029Y42380D01*
X670919Y42440D01*
X670794Y42480D01*
X670669Y42490D01*
X670544Y42480D01*
X670419Y42440D01*
X670309Y42380D01*
X670209Y42300D01*
X670129Y42200D01*
X670069Y42090D01*
X670029Y41965D01*
X670019Y41840D01*
Y38410D01*
X669989Y38380D01*
X669889Y38240D01*
X669869Y38200D01*
X669854Y38165D01*
X669834Y38125D01*
X669819Y38085D01*
X669809Y38045D01*
X669794Y38000D01*
X669789Y37960D01*
X669779Y37920D01*
X669774Y37875D01*
Y37835D01*
X669769Y37790D01*
X669774Y37745D01*
Y37705D01*
X669779Y37660D01*
X669789Y37620D01*
X669794Y37580D01*
X669809Y37535D01*
X669819Y37495D01*
X669834Y37455D01*
X669854Y37415D01*
X669869Y37380D01*
X669889Y37340D01*
X669989Y37200D01*
X670019Y37170D01*
Y36040D01*
X670029Y35915D01*
X670069Y35790D01*
X670129Y35680D01*
X670209Y35580D01*
X670309Y35500D01*
X670419Y35440D01*
X670544Y35400D01*
X670669Y35390D01*
G37*
G36*
G01X665945D02*
X666070Y35400D01*
X666195Y35440D01*
X666305Y35500D01*
X666405Y35580D01*
X666485Y35680D01*
X666545Y35790D01*
X666585Y35915D01*
X666595Y36040D01*
Y37170D01*
X666625Y37200D01*
X666725Y37340D01*
X666745Y37380D01*
X666760Y37415D01*
X666780Y37455D01*
X666795Y37495D01*
X666805Y37535D01*
X666820Y37580D01*
X666825Y37620D01*
X666835Y37660D01*
X666840Y37705D01*
Y37745D01*
X666845Y37790D01*
X666840Y37835D01*
Y37875D01*
X666835Y37920D01*
X666825Y37960D01*
X666820Y38000D01*
X666805Y38045D01*
X666795Y38085D01*
X666780Y38125D01*
X666760Y38165D01*
X666745Y38200D01*
X666725Y38240D01*
X666625Y38380D01*
X666595Y38410D01*
Y41840D01*
X666585Y41965D01*
X666545Y42090D01*
X666485Y42200D01*
X666405Y42300D01*
X666305Y42380D01*
X666195Y42440D01*
X666070Y42480D01*
X665945Y42490D01*
X665820Y42480D01*
X665695Y42440D01*
X665585Y42380D01*
X665485Y42300D01*
X665405Y42200D01*
X665345Y42090D01*
X665305Y41965D01*
X665295Y41840D01*
Y38410D01*
X665265Y38380D01*
X665165Y38240D01*
X665145Y38200D01*
X665130Y38165D01*
X665110Y38125D01*
X665095Y38085D01*
X665085Y38045D01*
X665070Y38000D01*
X665065Y37960D01*
X665055Y37920D01*
X665050Y37875D01*
Y37835D01*
X665045Y37790D01*
X665050Y37745D01*
Y37705D01*
X665055Y37660D01*
X665065Y37620D01*
X665070Y37580D01*
X665085Y37535D01*
X665095Y37495D01*
X665110Y37455D01*
X665130Y37415D01*
X665145Y37380D01*
X665165Y37340D01*
X665265Y37200D01*
X665295Y37170D01*
Y36040D01*
X665305Y35915D01*
X665345Y35790D01*
X665405Y35680D01*
X665485Y35580D01*
X665585Y35500D01*
X665695Y35440D01*
X665820Y35400D01*
X665945Y35390D01*
G37*
G36*
G01X694291D02*
X694416Y35400D01*
X694541Y35440D01*
X694651Y35500D01*
X694751Y35580D01*
X694831Y35680D01*
X694891Y35790D01*
X694931Y35915D01*
X694941Y36040D01*
Y37170D01*
X694971Y37200D01*
X695071Y37340D01*
X695091Y37380D01*
X695106Y37415D01*
X695126Y37455D01*
X695141Y37495D01*
X695151Y37535D01*
X695166Y37580D01*
X695171Y37620D01*
X695181Y37660D01*
X695186Y37705D01*
Y37745D01*
X695191Y37790D01*
X695186Y37835D01*
Y37875D01*
X695181Y37920D01*
X695171Y37960D01*
X695166Y38000D01*
X695151Y38045D01*
X695141Y38085D01*
X695126Y38125D01*
X695106Y38165D01*
X695091Y38200D01*
X695071Y38240D01*
X694971Y38380D01*
X694941Y38410D01*
Y41840D01*
X694931Y41965D01*
X694891Y42090D01*
X694831Y42200D01*
X694751Y42300D01*
X694651Y42380D01*
X694541Y42440D01*
X694416Y42480D01*
X694291Y42490D01*
X694166Y42480D01*
X694041Y42440D01*
X693931Y42380D01*
X693831Y42300D01*
X693751Y42200D01*
X693691Y42090D01*
X693651Y41965D01*
X693641Y41840D01*
Y38410D01*
X693611Y38380D01*
X693511Y38240D01*
X693491Y38200D01*
X693476Y38165D01*
X693456Y38125D01*
X693441Y38085D01*
X693431Y38045D01*
X693416Y38000D01*
X693411Y37960D01*
X693401Y37920D01*
X693396Y37875D01*
Y37835D01*
X693391Y37790D01*
X693396Y37745D01*
Y37705D01*
X693401Y37660D01*
X693411Y37620D01*
X693416Y37580D01*
X693431Y37535D01*
X693441Y37495D01*
X693456Y37455D01*
X693476Y37415D01*
X693491Y37380D01*
X693511Y37340D01*
X693611Y37200D01*
X693641Y37170D01*
Y36040D01*
X693651Y35915D01*
X693691Y35790D01*
X693751Y35680D01*
X693831Y35580D01*
X693931Y35500D01*
X694041Y35440D01*
X694166Y35400D01*
X694291Y35390D01*
G37*
G36*
G01X689567D02*
X689692Y35400D01*
X689817Y35440D01*
X689927Y35500D01*
X690027Y35580D01*
X690107Y35680D01*
X690167Y35790D01*
X690207Y35915D01*
X690217Y36040D01*
Y37170D01*
X690247Y37200D01*
X690347Y37340D01*
X690367Y37380D01*
X690382Y37415D01*
X690402Y37455D01*
X690417Y37495D01*
X690427Y37535D01*
X690442Y37580D01*
X690447Y37620D01*
X690457Y37660D01*
X690462Y37705D01*
Y37745D01*
X690467Y37790D01*
X690462Y37835D01*
Y37875D01*
X690457Y37920D01*
X690447Y37960D01*
X690442Y38000D01*
X690427Y38045D01*
X690417Y38085D01*
X690402Y38125D01*
X690382Y38165D01*
X690367Y38200D01*
X690347Y38240D01*
X690247Y38380D01*
X690217Y38410D01*
Y41840D01*
X690207Y41965D01*
X690167Y42090D01*
X690107Y42200D01*
X690027Y42300D01*
X689927Y42380D01*
X689817Y42440D01*
X689692Y42480D01*
X689567Y42490D01*
X689442Y42480D01*
X689317Y42440D01*
X689207Y42380D01*
X689107Y42300D01*
X689027Y42200D01*
X688967Y42090D01*
X688927Y41965D01*
X688917Y41840D01*
Y38410D01*
X688887Y38380D01*
X688787Y38240D01*
X688767Y38200D01*
X688752Y38165D01*
X688732Y38125D01*
X688717Y38085D01*
X688707Y38045D01*
X688692Y38000D01*
X688687Y37960D01*
X688677Y37920D01*
X688672Y37875D01*
Y37835D01*
X688667Y37790D01*
X688672Y37745D01*
Y37705D01*
X688677Y37660D01*
X688687Y37620D01*
X688692Y37580D01*
X688707Y37535D01*
X688717Y37495D01*
X688732Y37455D01*
X688752Y37415D01*
X688767Y37380D01*
X688787Y37340D01*
X688887Y37200D01*
X688917Y37170D01*
Y36040D01*
X688927Y35915D01*
X688967Y35790D01*
X689027Y35680D01*
X689107Y35580D01*
X689207Y35500D01*
X689317Y35440D01*
X689442Y35400D01*
X689567Y35390D01*
G37*
G36*
G01X684842D02*
X684967Y35400D01*
X685092Y35440D01*
X685202Y35500D01*
X685302Y35580D01*
X685382Y35680D01*
X685442Y35790D01*
X685482Y35915D01*
X685492Y36040D01*
Y37170D01*
X685522Y37200D01*
X685622Y37340D01*
X685642Y37380D01*
X685657Y37415D01*
X685677Y37455D01*
X685692Y37495D01*
X685702Y37535D01*
X685717Y37580D01*
X685722Y37620D01*
X685732Y37660D01*
X685737Y37705D01*
Y37745D01*
X685742Y37790D01*
X685737Y37835D01*
Y37875D01*
X685732Y37920D01*
X685722Y37960D01*
X685717Y38000D01*
X685702Y38045D01*
X685692Y38085D01*
X685677Y38125D01*
X685657Y38165D01*
X685642Y38200D01*
X685622Y38240D01*
X685522Y38380D01*
X685492Y38410D01*
Y41840D01*
X685482Y41965D01*
X685442Y42090D01*
X685382Y42200D01*
X685302Y42300D01*
X685202Y42380D01*
X685092Y42440D01*
X684967Y42480D01*
X684842Y42490D01*
X684717Y42480D01*
X684592Y42440D01*
X684482Y42380D01*
X684382Y42300D01*
X684302Y42200D01*
X684242Y42090D01*
X684202Y41965D01*
X684192Y41840D01*
Y38410D01*
X684162Y38380D01*
X684062Y38240D01*
X684042Y38200D01*
X684027Y38165D01*
X684007Y38125D01*
X683992Y38085D01*
X683982Y38045D01*
X683967Y38000D01*
X683962Y37960D01*
X683952Y37920D01*
X683947Y37875D01*
Y37835D01*
X683942Y37790D01*
X683947Y37745D01*
Y37705D01*
X683952Y37660D01*
X683962Y37620D01*
X683967Y37580D01*
X683982Y37535D01*
X683992Y37495D01*
X684007Y37455D01*
X684027Y37415D01*
X684042Y37380D01*
X684062Y37340D01*
X684162Y37200D01*
X684192Y37170D01*
Y36040D01*
X684202Y35915D01*
X684242Y35790D01*
X684302Y35680D01*
X684382Y35580D01*
X684482Y35500D01*
X684592Y35440D01*
X684717Y35400D01*
X684842Y35390D01*
G37*
G36*
G01X708464D02*
X708589Y35400D01*
X708714Y35440D01*
X708824Y35500D01*
X708924Y35580D01*
X709004Y35680D01*
X709064Y35790D01*
X709104Y35915D01*
X709114Y36040D01*
Y37170D01*
X709144Y37200D01*
X709244Y37340D01*
X709264Y37380D01*
X709279Y37415D01*
X709299Y37455D01*
X709314Y37495D01*
X709324Y37535D01*
X709339Y37580D01*
X709344Y37620D01*
X709354Y37660D01*
X709359Y37705D01*
Y37745D01*
X709364Y37790D01*
X709359Y37835D01*
Y37875D01*
X709354Y37920D01*
X709344Y37960D01*
X709339Y38000D01*
X709324Y38045D01*
X709314Y38085D01*
X709299Y38125D01*
X709279Y38165D01*
X709264Y38200D01*
X709244Y38240D01*
X709144Y38380D01*
X709114Y38410D01*
Y41840D01*
X709104Y41965D01*
X709064Y42090D01*
X709004Y42200D01*
X708924Y42300D01*
X708824Y42380D01*
X708714Y42440D01*
X708589Y42480D01*
X708464Y42490D01*
X708339Y42480D01*
X708214Y42440D01*
X708104Y42380D01*
X708004Y42300D01*
X707924Y42200D01*
X707864Y42090D01*
X707824Y41965D01*
X707814Y41840D01*
Y38410D01*
X707784Y38380D01*
X707684Y38240D01*
X707664Y38200D01*
X707649Y38165D01*
X707629Y38125D01*
X707614Y38085D01*
X707604Y38045D01*
X707589Y38000D01*
X707584Y37960D01*
X707574Y37920D01*
X707569Y37875D01*
Y37835D01*
X707564Y37790D01*
X707569Y37745D01*
Y37705D01*
X707574Y37660D01*
X707584Y37620D01*
X707589Y37580D01*
X707604Y37535D01*
X707614Y37495D01*
X707629Y37455D01*
X707649Y37415D01*
X707664Y37380D01*
X707684Y37340D01*
X707784Y37200D01*
X707814Y37170D01*
Y36040D01*
X707824Y35915D01*
X707864Y35790D01*
X707924Y35680D01*
X708004Y35580D01*
X708104Y35500D01*
X708214Y35440D01*
X708339Y35400D01*
X708464Y35390D01*
G37*
G36*
G01X703740D02*
X703865Y35400D01*
X703990Y35440D01*
X704100Y35500D01*
X704200Y35580D01*
X704280Y35680D01*
X704340Y35790D01*
X704380Y35915D01*
X704390Y36040D01*
Y37170D01*
X704420Y37200D01*
X704520Y37340D01*
X704540Y37380D01*
X704555Y37415D01*
X704575Y37455D01*
X704590Y37495D01*
X704600Y37535D01*
X704615Y37580D01*
X704620Y37620D01*
X704630Y37660D01*
X704635Y37705D01*
Y37745D01*
X704640Y37790D01*
X704635Y37835D01*
Y37875D01*
X704630Y37920D01*
X704620Y37960D01*
X704615Y38000D01*
X704600Y38045D01*
X704590Y38085D01*
X704575Y38125D01*
X704555Y38165D01*
X704540Y38200D01*
X704520Y38240D01*
X704420Y38380D01*
X704390Y38410D01*
Y41840D01*
X704380Y41965D01*
X704340Y42090D01*
X704280Y42200D01*
X704200Y42300D01*
X704100Y42380D01*
X703990Y42440D01*
X703865Y42480D01*
X703740Y42490D01*
X703615Y42480D01*
X703490Y42440D01*
X703380Y42380D01*
X703280Y42300D01*
X703200Y42200D01*
X703140Y42090D01*
X703100Y41965D01*
X703090Y41840D01*
Y38410D01*
X703060Y38380D01*
X702960Y38240D01*
X702940Y38200D01*
X702925Y38165D01*
X702905Y38125D01*
X702890Y38085D01*
X702880Y38045D01*
X702865Y38000D01*
X702860Y37960D01*
X702850Y37920D01*
X702845Y37875D01*
Y37835D01*
X702840Y37790D01*
X702845Y37745D01*
Y37705D01*
X702850Y37660D01*
X702860Y37620D01*
X702865Y37580D01*
X702880Y37535D01*
X702890Y37495D01*
X702905Y37455D01*
X702925Y37415D01*
X702940Y37380D01*
X702960Y37340D01*
X703060Y37200D01*
X703090Y37170D01*
Y36040D01*
X703100Y35915D01*
X703140Y35790D01*
X703200Y35680D01*
X703280Y35580D01*
X703380Y35500D01*
X703490Y35440D01*
X703615Y35400D01*
X703740Y35390D01*
G37*
G36*
G01X699015D02*
X699140Y35400D01*
X699265Y35440D01*
X699375Y35500D01*
X699475Y35580D01*
X699555Y35680D01*
X699615Y35790D01*
X699655Y35915D01*
X699665Y36040D01*
Y37170D01*
X699695Y37200D01*
X699795Y37340D01*
X699815Y37380D01*
X699830Y37415D01*
X699850Y37455D01*
X699865Y37495D01*
X699875Y37535D01*
X699890Y37580D01*
X699895Y37620D01*
X699905Y37660D01*
X699910Y37705D01*
Y37745D01*
X699915Y37790D01*
X699910Y37835D01*
Y37875D01*
X699905Y37920D01*
X699895Y37960D01*
X699890Y38000D01*
X699875Y38045D01*
X699865Y38085D01*
X699850Y38125D01*
X699830Y38165D01*
X699815Y38200D01*
X699795Y38240D01*
X699695Y38380D01*
X699665Y38410D01*
Y41840D01*
X699655Y41965D01*
X699615Y42090D01*
X699555Y42200D01*
X699475Y42300D01*
X699375Y42380D01*
X699265Y42440D01*
X699140Y42480D01*
X699015Y42490D01*
X698890Y42480D01*
X698765Y42440D01*
X698655Y42380D01*
X698555Y42300D01*
X698475Y42200D01*
X698415Y42090D01*
X698375Y41965D01*
X698365Y41840D01*
Y38410D01*
X698335Y38380D01*
X698235Y38240D01*
X698215Y38200D01*
X698200Y38165D01*
X698180Y38125D01*
X698165Y38085D01*
X698155Y38045D01*
X698140Y38000D01*
X698135Y37960D01*
X698125Y37920D01*
X698120Y37875D01*
Y37835D01*
X698115Y37790D01*
X698120Y37745D01*
Y37705D01*
X698125Y37660D01*
X698135Y37620D01*
X698140Y37580D01*
X698155Y37535D01*
X698165Y37495D01*
X698180Y37455D01*
X698200Y37415D01*
X698215Y37380D01*
X698235Y37340D01*
X698335Y37200D01*
X698365Y37170D01*
Y36040D01*
X698375Y35915D01*
X698415Y35790D01*
X698475Y35680D01*
X698555Y35580D01*
X698655Y35500D01*
X698765Y35440D01*
X698890Y35400D01*
X699015Y35390D01*
G37*
G36*
G01X722638D02*
X722763Y35400D01*
X722888Y35440D01*
X722998Y35500D01*
X723098Y35580D01*
X723178Y35680D01*
X723238Y35790D01*
X723278Y35915D01*
X723288Y36040D01*
Y37170D01*
X723318Y37200D01*
X723418Y37340D01*
X723438Y37380D01*
X723453Y37415D01*
X723473Y37455D01*
X723488Y37495D01*
X723498Y37535D01*
X723513Y37580D01*
X723518Y37620D01*
X723528Y37660D01*
X723533Y37705D01*
Y37745D01*
X723538Y37790D01*
X723533Y37835D01*
Y37875D01*
X723528Y37920D01*
X723518Y37960D01*
X723513Y38000D01*
X723498Y38045D01*
X723488Y38085D01*
X723473Y38125D01*
X723453Y38165D01*
X723438Y38200D01*
X723418Y38240D01*
X723318Y38380D01*
X723288Y38410D01*
Y41840D01*
X723278Y41965D01*
X723238Y42090D01*
X723178Y42200D01*
X723098Y42300D01*
X722998Y42380D01*
X722888Y42440D01*
X722763Y42480D01*
X722638Y42490D01*
X722513Y42480D01*
X722388Y42440D01*
X722278Y42380D01*
X722178Y42300D01*
X722098Y42200D01*
X722038Y42090D01*
X721998Y41965D01*
X721988Y41840D01*
Y38410D01*
X721958Y38380D01*
X721858Y38240D01*
X721838Y38200D01*
X721823Y38165D01*
X721803Y38125D01*
X721788Y38085D01*
X721778Y38045D01*
X721763Y38000D01*
X721758Y37960D01*
X721748Y37920D01*
X721743Y37875D01*
Y37835D01*
X721738Y37790D01*
X721743Y37745D01*
Y37705D01*
X721748Y37660D01*
X721758Y37620D01*
X721763Y37580D01*
X721778Y37535D01*
X721788Y37495D01*
X721803Y37455D01*
X721823Y37415D01*
X721838Y37380D01*
X721858Y37340D01*
X721958Y37200D01*
X721988Y37170D01*
Y36040D01*
X721998Y35915D01*
X722038Y35790D01*
X722098Y35680D01*
X722178Y35580D01*
X722278Y35500D01*
X722388Y35440D01*
X722513Y35400D01*
X722638Y35390D01*
G37*
G36*
G01X717913D02*
X718038Y35400D01*
X718163Y35440D01*
X718273Y35500D01*
X718373Y35580D01*
X718453Y35680D01*
X718513Y35790D01*
X718553Y35915D01*
X718563Y36040D01*
Y37170D01*
X718593Y37200D01*
X718693Y37340D01*
X718713Y37380D01*
X718728Y37415D01*
X718748Y37455D01*
X718763Y37495D01*
X718773Y37535D01*
X718788Y37580D01*
X718793Y37620D01*
X718803Y37660D01*
X718808Y37705D01*
Y37745D01*
X718813Y37790D01*
X718808Y37835D01*
Y37875D01*
X718803Y37920D01*
X718793Y37960D01*
X718788Y38000D01*
X718773Y38045D01*
X718763Y38085D01*
X718748Y38125D01*
X718728Y38165D01*
X718713Y38200D01*
X718693Y38240D01*
X718593Y38380D01*
X718563Y38410D01*
Y41840D01*
X718553Y41965D01*
X718513Y42090D01*
X718453Y42200D01*
X718373Y42300D01*
X718273Y42380D01*
X718163Y42440D01*
X718038Y42480D01*
X717913Y42490D01*
X717788Y42480D01*
X717663Y42440D01*
X717553Y42380D01*
X717453Y42300D01*
X717373Y42200D01*
X717313Y42090D01*
X717273Y41965D01*
X717263Y41840D01*
Y38410D01*
X717233Y38380D01*
X717133Y38240D01*
X717113Y38200D01*
X717098Y38165D01*
X717078Y38125D01*
X717063Y38085D01*
X717053Y38045D01*
X717038Y38000D01*
X717033Y37960D01*
X717023Y37920D01*
X717018Y37875D01*
Y37835D01*
X717013Y37790D01*
X717018Y37745D01*
Y37705D01*
X717023Y37660D01*
X717033Y37620D01*
X717038Y37580D01*
X717053Y37535D01*
X717063Y37495D01*
X717078Y37455D01*
X717098Y37415D01*
X717113Y37380D01*
X717133Y37340D01*
X717233Y37200D01*
X717263Y37170D01*
Y36040D01*
X717273Y35915D01*
X717313Y35790D01*
X717373Y35680D01*
X717453Y35580D01*
X717553Y35500D01*
X717663Y35440D01*
X717788Y35400D01*
X717913Y35390D01*
G37*
G36*
G01X713189D02*
X713314Y35400D01*
X713439Y35440D01*
X713549Y35500D01*
X713649Y35580D01*
X713729Y35680D01*
X713789Y35790D01*
X713829Y35915D01*
X713839Y36040D01*
Y37170D01*
X713869Y37200D01*
X713969Y37340D01*
X713989Y37380D01*
X714004Y37415D01*
X714024Y37455D01*
X714039Y37495D01*
X714049Y37535D01*
X714064Y37580D01*
X714069Y37620D01*
X714079Y37660D01*
X714084Y37705D01*
Y37745D01*
X714089Y37790D01*
X714084Y37835D01*
Y37875D01*
X714079Y37920D01*
X714069Y37960D01*
X714064Y38000D01*
X714049Y38045D01*
X714039Y38085D01*
X714024Y38125D01*
X714004Y38165D01*
X713989Y38200D01*
X713969Y38240D01*
X713869Y38380D01*
X713839Y38410D01*
Y41840D01*
X713829Y41965D01*
X713789Y42090D01*
X713729Y42200D01*
X713649Y42300D01*
X713549Y42380D01*
X713439Y42440D01*
X713314Y42480D01*
X713189Y42490D01*
X713064Y42480D01*
X712939Y42440D01*
X712829Y42380D01*
X712729Y42300D01*
X712649Y42200D01*
X712589Y42090D01*
X712549Y41965D01*
X712539Y41840D01*
Y38410D01*
X712509Y38380D01*
X712409Y38240D01*
X712389Y38200D01*
X712374Y38165D01*
X712354Y38125D01*
X712339Y38085D01*
X712329Y38045D01*
X712314Y38000D01*
X712309Y37960D01*
X712299Y37920D01*
X712294Y37875D01*
Y37835D01*
X712289Y37790D01*
X712294Y37745D01*
Y37705D01*
X712299Y37660D01*
X712309Y37620D01*
X712314Y37580D01*
X712329Y37535D01*
X712339Y37495D01*
X712354Y37455D01*
X712374Y37415D01*
X712389Y37380D01*
X712409Y37340D01*
X712509Y37200D01*
X712539Y37170D01*
Y36040D01*
X712549Y35915D01*
X712589Y35790D01*
X712649Y35680D01*
X712729Y35580D01*
X712829Y35500D01*
X712939Y35440D01*
X713064Y35400D01*
X713189Y35390D01*
G37*
G36*
G01X741535D02*
X741660Y35400D01*
X741785Y35440D01*
X741895Y35500D01*
X741995Y35580D01*
X742075Y35680D01*
X742135Y35790D01*
X742175Y35915D01*
X742185Y36040D01*
Y37170D01*
X742215Y37200D01*
X742315Y37340D01*
X742335Y37380D01*
X742350Y37415D01*
X742370Y37455D01*
X742385Y37495D01*
X742395Y37535D01*
X742410Y37580D01*
X742415Y37620D01*
X742425Y37660D01*
X742430Y37705D01*
Y37745D01*
X742435Y37790D01*
X742430Y37835D01*
Y37875D01*
X742425Y37920D01*
X742415Y37960D01*
X742410Y38000D01*
X742395Y38045D01*
X742385Y38085D01*
X742370Y38125D01*
X742350Y38165D01*
X742335Y38200D01*
X742315Y38240D01*
X742215Y38380D01*
X742185Y38410D01*
Y41840D01*
X742175Y41965D01*
X742135Y42090D01*
X742075Y42200D01*
X741995Y42300D01*
X741895Y42380D01*
X741785Y42440D01*
X741660Y42480D01*
X741535Y42490D01*
X741410Y42480D01*
X741285Y42440D01*
X741175Y42380D01*
X741075Y42300D01*
X740995Y42200D01*
X740935Y42090D01*
X740895Y41965D01*
X740885Y41840D01*
Y38410D01*
X740855Y38380D01*
X740755Y38240D01*
X740735Y38200D01*
X740720Y38165D01*
X740700Y38125D01*
X740685Y38085D01*
X740675Y38045D01*
X740660Y38000D01*
X740655Y37960D01*
X740645Y37920D01*
X740640Y37875D01*
Y37835D01*
X740635Y37790D01*
X740640Y37745D01*
Y37705D01*
X740645Y37660D01*
X740655Y37620D01*
X740660Y37580D01*
X740675Y37535D01*
X740685Y37495D01*
X740700Y37455D01*
X740720Y37415D01*
X740735Y37380D01*
X740755Y37340D01*
X740855Y37200D01*
X740885Y37170D01*
Y36040D01*
X740895Y35915D01*
X740935Y35790D01*
X740995Y35680D01*
X741075Y35580D01*
X741175Y35500D01*
X741285Y35440D01*
X741410Y35400D01*
X741535Y35390D01*
G37*
G36*
G01X736811D02*
X736936Y35400D01*
X737061Y35440D01*
X737171Y35500D01*
X737271Y35580D01*
X737351Y35680D01*
X737411Y35790D01*
X737451Y35915D01*
X737461Y36040D01*
Y37170D01*
X737491Y37200D01*
X737591Y37340D01*
X737611Y37380D01*
X737626Y37415D01*
X737646Y37455D01*
X737661Y37495D01*
X737671Y37535D01*
X737686Y37580D01*
X737691Y37620D01*
X737701Y37660D01*
X737706Y37705D01*
Y37745D01*
X737711Y37790D01*
X737706Y37835D01*
Y37875D01*
X737701Y37920D01*
X737691Y37960D01*
X737686Y38000D01*
X737671Y38045D01*
X737661Y38085D01*
X737646Y38125D01*
X737626Y38165D01*
X737611Y38200D01*
X737591Y38240D01*
X737491Y38380D01*
X737461Y38410D01*
Y41840D01*
X737451Y41965D01*
X737411Y42090D01*
X737351Y42200D01*
X737271Y42300D01*
X737171Y42380D01*
X737061Y42440D01*
X736936Y42480D01*
X736811Y42490D01*
X736686Y42480D01*
X736561Y42440D01*
X736451Y42380D01*
X736351Y42300D01*
X736271Y42200D01*
X736211Y42090D01*
X736171Y41965D01*
X736161Y41840D01*
Y38410D01*
X736131Y38380D01*
X736031Y38240D01*
X736011Y38200D01*
X735996Y38165D01*
X735976Y38125D01*
X735961Y38085D01*
X735951Y38045D01*
X735936Y38000D01*
X735931Y37960D01*
X735921Y37920D01*
X735916Y37875D01*
Y37835D01*
X735911Y37790D01*
X735916Y37745D01*
Y37705D01*
X735921Y37660D01*
X735931Y37620D01*
X735936Y37580D01*
X735951Y37535D01*
X735961Y37495D01*
X735976Y37455D01*
X735996Y37415D01*
X736011Y37380D01*
X736031Y37340D01*
X736131Y37200D01*
X736161Y37170D01*
Y36040D01*
X736171Y35915D01*
X736211Y35790D01*
X736271Y35680D01*
X736351Y35580D01*
X736451Y35500D01*
X736561Y35440D01*
X736686Y35400D01*
X736811Y35390D01*
G37*
G36*
G01X732086D02*
X732211Y35400D01*
X732336Y35440D01*
X732446Y35500D01*
X732546Y35580D01*
X732626Y35680D01*
X732686Y35790D01*
X732726Y35915D01*
X732736Y36040D01*
Y37170D01*
X732766Y37200D01*
X732866Y37340D01*
X732886Y37380D01*
X732901Y37415D01*
X732921Y37455D01*
X732936Y37495D01*
X732946Y37535D01*
X732961Y37580D01*
X732966Y37620D01*
X732976Y37660D01*
X732981Y37705D01*
Y37745D01*
X732986Y37790D01*
X732981Y37835D01*
Y37875D01*
X732976Y37920D01*
X732966Y37960D01*
X732961Y38000D01*
X732946Y38045D01*
X732936Y38085D01*
X732921Y38125D01*
X732901Y38165D01*
X732886Y38200D01*
X732866Y38240D01*
X732766Y38380D01*
X732736Y38410D01*
Y41840D01*
X732726Y41965D01*
X732686Y42090D01*
X732626Y42200D01*
X732546Y42300D01*
X732446Y42380D01*
X732336Y42440D01*
X732211Y42480D01*
X732086Y42490D01*
X731961Y42480D01*
X731836Y42440D01*
X731726Y42380D01*
X731626Y42300D01*
X731546Y42200D01*
X731486Y42090D01*
X731446Y41965D01*
X731436Y41840D01*
Y38410D01*
X731406Y38380D01*
X731306Y38240D01*
X731286Y38200D01*
X731271Y38165D01*
X731251Y38125D01*
X731236Y38085D01*
X731226Y38045D01*
X731211Y38000D01*
X731206Y37960D01*
X731196Y37920D01*
X731191Y37875D01*
Y37835D01*
X731186Y37790D01*
X731191Y37745D01*
Y37705D01*
X731196Y37660D01*
X731206Y37620D01*
X731211Y37580D01*
X731226Y37535D01*
X731236Y37495D01*
X731251Y37455D01*
X731271Y37415D01*
X731286Y37380D01*
X731306Y37340D01*
X731406Y37200D01*
X731436Y37170D01*
Y36040D01*
X731446Y35915D01*
X731486Y35790D01*
X731546Y35680D01*
X731626Y35580D01*
X731726Y35500D01*
X731836Y35440D01*
X731961Y35400D01*
X732086Y35390D01*
G37*
G36*
G01X727362D02*
X727487Y35400D01*
X727612Y35440D01*
X727722Y35500D01*
X727822Y35580D01*
X727902Y35680D01*
X727962Y35790D01*
X728002Y35915D01*
X728012Y36040D01*
Y37170D01*
X728042Y37200D01*
X728142Y37340D01*
X728162Y37380D01*
X728177Y37415D01*
X728197Y37455D01*
X728212Y37495D01*
X728222Y37535D01*
X728237Y37580D01*
X728242Y37620D01*
X728252Y37660D01*
X728257Y37705D01*
Y37745D01*
X728262Y37790D01*
X728257Y37835D01*
Y37875D01*
X728252Y37920D01*
X728242Y37960D01*
X728237Y38000D01*
X728222Y38045D01*
X728212Y38085D01*
X728197Y38125D01*
X728177Y38165D01*
X728162Y38200D01*
X728142Y38240D01*
X728042Y38380D01*
X728012Y38410D01*
Y41840D01*
X728002Y41965D01*
X727962Y42090D01*
X727902Y42200D01*
X727822Y42300D01*
X727722Y42380D01*
X727612Y42440D01*
X727487Y42480D01*
X727362Y42490D01*
X727237Y42480D01*
X727112Y42440D01*
X727002Y42380D01*
X726902Y42300D01*
X726822Y42200D01*
X726762Y42090D01*
X726722Y41965D01*
X726712Y41840D01*
Y38410D01*
X726682Y38380D01*
X726582Y38240D01*
X726562Y38200D01*
X726547Y38165D01*
X726527Y38125D01*
X726512Y38085D01*
X726502Y38045D01*
X726487Y38000D01*
X726482Y37960D01*
X726472Y37920D01*
X726467Y37875D01*
Y37835D01*
X726462Y37790D01*
X726467Y37745D01*
Y37705D01*
X726472Y37660D01*
X726482Y37620D01*
X726487Y37580D01*
X726502Y37535D01*
X726512Y37495D01*
X726527Y37455D01*
X726547Y37415D01*
X726562Y37380D01*
X726582Y37340D01*
X726682Y37200D01*
X726712Y37170D01*
Y36040D01*
X726722Y35915D01*
X726762Y35790D01*
X726822Y35680D01*
X726902Y35580D01*
X727002Y35500D01*
X727112Y35440D01*
X727237Y35400D01*
X727362Y35390D01*
G37*
G36*
G01X750984D02*
X751109Y35400D01*
X751234Y35440D01*
X751344Y35500D01*
X751444Y35580D01*
X751524Y35680D01*
X751584Y35790D01*
X751624Y35915D01*
X751634Y36040D01*
Y37170D01*
X751664Y37200D01*
X751764Y37340D01*
X751784Y37380D01*
X751799Y37415D01*
X751819Y37455D01*
X751834Y37495D01*
X751844Y37535D01*
X751859Y37580D01*
X751864Y37620D01*
X751874Y37660D01*
X751879Y37705D01*
Y37745D01*
X751884Y37790D01*
X751879Y37835D01*
Y37875D01*
X751874Y37920D01*
X751864Y37960D01*
X751859Y38000D01*
X751844Y38045D01*
X751834Y38085D01*
X751819Y38125D01*
X751799Y38165D01*
X751784Y38200D01*
X751764Y38240D01*
X751664Y38380D01*
X751634Y38410D01*
Y41840D01*
X751624Y41965D01*
X751584Y42090D01*
X751524Y42200D01*
X751444Y42300D01*
X751344Y42380D01*
X751234Y42440D01*
X751109Y42480D01*
X750984Y42490D01*
X750859Y42480D01*
X750734Y42440D01*
X750624Y42380D01*
X750524Y42300D01*
X750444Y42200D01*
X750384Y42090D01*
X750344Y41965D01*
X750334Y41840D01*
Y38410D01*
X750304Y38380D01*
X750204Y38240D01*
X750184Y38200D01*
X750169Y38165D01*
X750149Y38125D01*
X750134Y38085D01*
X750124Y38045D01*
X750109Y38000D01*
X750104Y37960D01*
X750094Y37920D01*
X750089Y37875D01*
Y37835D01*
X750084Y37790D01*
X750089Y37745D01*
Y37705D01*
X750094Y37660D01*
X750104Y37620D01*
X750109Y37580D01*
X750124Y37535D01*
X750134Y37495D01*
X750149Y37455D01*
X750169Y37415D01*
X750184Y37380D01*
X750204Y37340D01*
X750304Y37200D01*
X750334Y37170D01*
Y36040D01*
X750344Y35915D01*
X750384Y35790D01*
X750444Y35680D01*
X750524Y35580D01*
X750624Y35500D01*
X750734Y35440D01*
X750859Y35400D01*
X750984Y35390D01*
G37*
G36*
G01X746260D02*
X746385Y35400D01*
X746510Y35440D01*
X746620Y35500D01*
X746720Y35580D01*
X746800Y35680D01*
X746860Y35790D01*
X746900Y35915D01*
X746910Y36040D01*
Y37170D01*
X746940Y37200D01*
X747040Y37340D01*
X747060Y37380D01*
X747075Y37415D01*
X747095Y37455D01*
X747110Y37495D01*
X747120Y37535D01*
X747135Y37580D01*
X747140Y37620D01*
X747150Y37660D01*
X747155Y37705D01*
Y37745D01*
X747160Y37790D01*
X747155Y37835D01*
Y37875D01*
X747150Y37920D01*
X747140Y37960D01*
X747135Y38000D01*
X747120Y38045D01*
X747110Y38085D01*
X747095Y38125D01*
X747075Y38165D01*
X747060Y38200D01*
X747040Y38240D01*
X746940Y38380D01*
X746910Y38410D01*
Y41840D01*
X746900Y41965D01*
X746860Y42090D01*
X746800Y42200D01*
X746720Y42300D01*
X746620Y42380D01*
X746510Y42440D01*
X746385Y42480D01*
X746260Y42490D01*
X746135Y42480D01*
X746010Y42440D01*
X745900Y42380D01*
X745800Y42300D01*
X745720Y42200D01*
X745660Y42090D01*
X745620Y41965D01*
X745610Y41840D01*
Y38410D01*
X745580Y38380D01*
X745480Y38240D01*
X745460Y38200D01*
X745445Y38165D01*
X745425Y38125D01*
X745410Y38085D01*
X745400Y38045D01*
X745385Y38000D01*
X745380Y37960D01*
X745370Y37920D01*
X745365Y37875D01*
Y37835D01*
X745360Y37790D01*
X745365Y37745D01*
Y37705D01*
X745370Y37660D01*
X745380Y37620D01*
X745385Y37580D01*
X745400Y37535D01*
X745410Y37495D01*
X745425Y37455D01*
X745445Y37415D01*
X745460Y37380D01*
X745480Y37340D01*
X745580Y37200D01*
X745610Y37170D01*
Y36040D01*
X745620Y35915D01*
X745660Y35790D01*
X745720Y35680D01*
X745800Y35580D01*
X745900Y35500D01*
X746010Y35440D01*
X746135Y35400D01*
X746260Y35390D01*
G37*
G54D46*
X249410Y67126D03*
Y182480D03*
G54D65*
X429500Y255413D03*
Y269587D03*
G36*
G01X500591Y250006D02*
X500466Y249996D01*
X500341Y249956D01*
X500231Y249896D01*
X500131Y249816D01*
X500051Y249716D01*
X499991Y249606D01*
X499951Y249481D01*
X499941Y249356D01*
Y247231D01*
X499911Y247201D01*
X499886Y247166D01*
X499856Y247131D01*
X499836Y247096D01*
X499811Y247061D01*
X499771Y246981D01*
X499726Y246861D01*
X499716Y246821D01*
X499706Y246776D01*
X499701Y246736D01*
X499691Y246691D01*
Y246521D01*
X499701Y246476D01*
X499706Y246436D01*
X499716Y246391D01*
X499726Y246351D01*
X499771Y246231D01*
X499811Y246151D01*
X499836Y246116D01*
X499856Y246081D01*
X499886Y246046D01*
X499911Y246011D01*
X499941Y245981D01*
Y243556D01*
X499951Y243431D01*
X499991Y243306D01*
X500051Y243196D01*
X500131Y243096D01*
X500231Y243016D01*
X500341Y242956D01*
X500466Y242916D01*
X500591Y242906D01*
X500716Y242916D01*
X500841Y242956D01*
X500951Y243016D01*
X501051Y243096D01*
X501131Y243196D01*
X501191Y243306D01*
X501231Y243431D01*
X501241Y243556D01*
Y245986D01*
X501271Y246016D01*
X501371Y246156D01*
X501391Y246196D01*
X501406Y246231D01*
X501426Y246271D01*
X501441Y246311D01*
X501451Y246351D01*
X501466Y246396D01*
X501471Y246436D01*
X501481Y246476D01*
X501486Y246521D01*
Y246561D01*
X501491Y246606D01*
X501486Y246651D01*
Y246691D01*
X501481Y246736D01*
X501471Y246776D01*
X501466Y246816D01*
X501451Y246861D01*
X501441Y246901D01*
X501426Y246941D01*
X501406Y246981D01*
X501391Y247016D01*
X501371Y247056D01*
X501271Y247196D01*
X501241Y247226D01*
Y249356D01*
X501231Y249481D01*
X501191Y249606D01*
X501131Y249716D01*
X501051Y249816D01*
X500951Y249896D01*
X500841Y249956D01*
X500716Y249996D01*
X500591Y250006D01*
G37*
G36*
G01X505315D02*
X505190Y249996D01*
X505065Y249956D01*
X504955Y249896D01*
X504855Y249816D01*
X504775Y249716D01*
X504715Y249606D01*
X504675Y249481D01*
X504665Y249356D01*
Y247231D01*
X504635Y247201D01*
X504610Y247166D01*
X504580Y247131D01*
X504560Y247096D01*
X504535Y247061D01*
X504495Y246981D01*
X504450Y246861D01*
X504440Y246821D01*
X504430Y246776D01*
X504425Y246736D01*
X504415Y246691D01*
Y246521D01*
X504425Y246476D01*
X504430Y246436D01*
X504440Y246391D01*
X504450Y246351D01*
X504495Y246231D01*
X504535Y246151D01*
X504560Y246116D01*
X504580Y246081D01*
X504610Y246046D01*
X504635Y246011D01*
X504665Y245981D01*
Y243556D01*
X504675Y243431D01*
X504715Y243306D01*
X504775Y243196D01*
X504855Y243096D01*
X504955Y243016D01*
X505065Y242956D01*
X505190Y242916D01*
X505315Y242906D01*
X505440Y242916D01*
X505565Y242956D01*
X505675Y243016D01*
X505775Y243096D01*
X505855Y243196D01*
X505915Y243306D01*
X505955Y243431D01*
X505965Y243556D01*
Y245986D01*
X505995Y246016D01*
X506095Y246156D01*
X506115Y246196D01*
X506130Y246231D01*
X506150Y246271D01*
X506165Y246311D01*
X506175Y246351D01*
X506190Y246396D01*
X506195Y246436D01*
X506205Y246476D01*
X506210Y246521D01*
Y246561D01*
X506215Y246606D01*
X506210Y246651D01*
Y246691D01*
X506205Y246736D01*
X506195Y246776D01*
X506190Y246816D01*
X506175Y246861D01*
X506165Y246901D01*
X506150Y246941D01*
X506130Y246981D01*
X506115Y247016D01*
X506095Y247056D01*
X505995Y247196D01*
X505965Y247226D01*
Y249356D01*
X505955Y249481D01*
X505915Y249606D01*
X505855Y249716D01*
X505775Y249816D01*
X505675Y249896D01*
X505565Y249956D01*
X505440Y249996D01*
X505315Y250006D01*
G37*
G36*
G01X510040D02*
X509915Y249996D01*
X509790Y249956D01*
X509680Y249896D01*
X509580Y249816D01*
X509500Y249716D01*
X509440Y249606D01*
X509400Y249481D01*
X509390Y249356D01*
Y247231D01*
X509360Y247201D01*
X509335Y247166D01*
X509305Y247131D01*
X509285Y247096D01*
X509260Y247061D01*
X509220Y246981D01*
X509175Y246861D01*
X509165Y246821D01*
X509155Y246776D01*
X509150Y246736D01*
X509140Y246691D01*
Y246521D01*
X509150Y246476D01*
X509155Y246436D01*
X509165Y246391D01*
X509175Y246351D01*
X509220Y246231D01*
X509260Y246151D01*
X509285Y246116D01*
X509305Y246081D01*
X509335Y246046D01*
X509360Y246011D01*
X509390Y245981D01*
Y243556D01*
X509400Y243431D01*
X509440Y243306D01*
X509500Y243196D01*
X509580Y243096D01*
X509680Y243016D01*
X509790Y242956D01*
X509915Y242916D01*
X510040Y242906D01*
X510165Y242916D01*
X510290Y242956D01*
X510400Y243016D01*
X510500Y243096D01*
X510580Y243196D01*
X510640Y243306D01*
X510680Y243431D01*
X510690Y243556D01*
Y245986D01*
X510720Y246016D01*
X510820Y246156D01*
X510840Y246196D01*
X510855Y246231D01*
X510875Y246271D01*
X510890Y246311D01*
X510900Y246351D01*
X510915Y246396D01*
X510920Y246436D01*
X510930Y246476D01*
X510935Y246521D01*
Y246561D01*
X510940Y246606D01*
X510935Y246651D01*
Y246691D01*
X510930Y246736D01*
X510920Y246776D01*
X510915Y246816D01*
X510900Y246861D01*
X510890Y246901D01*
X510875Y246941D01*
X510855Y246981D01*
X510840Y247016D01*
X510820Y247056D01*
X510720Y247196D01*
X510690Y247226D01*
Y249356D01*
X510680Y249481D01*
X510640Y249606D01*
X510580Y249716D01*
X510500Y249816D01*
X510400Y249896D01*
X510290Y249956D01*
X510165Y249996D01*
X510040Y250006D01*
G37*
G36*
G01X514764D02*
X514639Y249996D01*
X514514Y249956D01*
X514404Y249896D01*
X514304Y249816D01*
X514224Y249716D01*
X514164Y249606D01*
X514124Y249481D01*
X514114Y249356D01*
Y247231D01*
X514084Y247201D01*
X514059Y247166D01*
X514029Y247131D01*
X514009Y247096D01*
X513984Y247061D01*
X513944Y246981D01*
X513899Y246861D01*
X513889Y246821D01*
X513879Y246776D01*
X513874Y246736D01*
X513864Y246691D01*
Y246521D01*
X513874Y246476D01*
X513879Y246436D01*
X513889Y246391D01*
X513899Y246351D01*
X513944Y246231D01*
X513984Y246151D01*
X514009Y246116D01*
X514029Y246081D01*
X514059Y246046D01*
X514084Y246011D01*
X514114Y245981D01*
Y243556D01*
X514124Y243431D01*
X514164Y243306D01*
X514224Y243196D01*
X514304Y243096D01*
X514404Y243016D01*
X514514Y242956D01*
X514639Y242916D01*
X514764Y242906D01*
X514889Y242916D01*
X515014Y242956D01*
X515124Y243016D01*
X515224Y243096D01*
X515304Y243196D01*
X515364Y243306D01*
X515404Y243431D01*
X515414Y243556D01*
Y245986D01*
X515444Y246016D01*
X515544Y246156D01*
X515564Y246196D01*
X515579Y246231D01*
X515599Y246271D01*
X515614Y246311D01*
X515624Y246351D01*
X515639Y246396D01*
X515644Y246436D01*
X515654Y246476D01*
X515659Y246521D01*
Y246561D01*
X515664Y246606D01*
X515659Y246651D01*
Y246691D01*
X515654Y246736D01*
X515644Y246776D01*
X515639Y246816D01*
X515624Y246861D01*
X515614Y246901D01*
X515599Y246941D01*
X515579Y246981D01*
X515564Y247016D01*
X515544Y247056D01*
X515444Y247196D01*
X515414Y247226D01*
Y249356D01*
X515404Y249481D01*
X515364Y249606D01*
X515304Y249716D01*
X515224Y249816D01*
X515124Y249896D01*
X515014Y249956D01*
X514889Y249996D01*
X514764Y250006D01*
G37*
G36*
G01X519488D02*
X519363Y249996D01*
X519238Y249956D01*
X519128Y249896D01*
X519028Y249816D01*
X518948Y249716D01*
X518888Y249606D01*
X518848Y249481D01*
X518838Y249356D01*
Y247231D01*
X518808Y247201D01*
X518783Y247166D01*
X518753Y247131D01*
X518733Y247096D01*
X518708Y247061D01*
X518668Y246981D01*
X518623Y246861D01*
X518613Y246821D01*
X518603Y246776D01*
X518598Y246736D01*
X518588Y246691D01*
Y246521D01*
X518598Y246476D01*
X518603Y246436D01*
X518613Y246391D01*
X518623Y246351D01*
X518668Y246231D01*
X518708Y246151D01*
X518733Y246116D01*
X518753Y246081D01*
X518783Y246046D01*
X518808Y246011D01*
X518838Y245981D01*
Y243556D01*
X518848Y243431D01*
X518888Y243306D01*
X518948Y243196D01*
X519028Y243096D01*
X519128Y243016D01*
X519238Y242956D01*
X519363Y242916D01*
X519488Y242906D01*
X519613Y242916D01*
X519738Y242956D01*
X519848Y243016D01*
X519948Y243096D01*
X520028Y243196D01*
X520088Y243306D01*
X520128Y243431D01*
X520138Y243556D01*
Y245986D01*
X520168Y246016D01*
X520268Y246156D01*
X520288Y246196D01*
X520303Y246231D01*
X520323Y246271D01*
X520338Y246311D01*
X520348Y246351D01*
X520363Y246396D01*
X520368Y246436D01*
X520378Y246476D01*
X520383Y246521D01*
Y246561D01*
X520388Y246606D01*
X520383Y246651D01*
Y246691D01*
X520378Y246736D01*
X520368Y246776D01*
X520363Y246816D01*
X520348Y246861D01*
X520338Y246901D01*
X520323Y246941D01*
X520303Y246981D01*
X520288Y247016D01*
X520268Y247056D01*
X520168Y247196D01*
X520138Y247226D01*
Y249356D01*
X520128Y249481D01*
X520088Y249606D01*
X520028Y249716D01*
X519948Y249816D01*
X519848Y249896D01*
X519738Y249956D01*
X519613Y249996D01*
X519488Y250006D01*
G37*
G36*
G01X524213D02*
X524088Y249996D01*
X523963Y249956D01*
X523853Y249896D01*
X523753Y249816D01*
X523673Y249716D01*
X523613Y249606D01*
X523573Y249481D01*
X523563Y249356D01*
Y247231D01*
X523533Y247201D01*
X523508Y247166D01*
X523478Y247131D01*
X523458Y247096D01*
X523433Y247061D01*
X523393Y246981D01*
X523348Y246861D01*
X523338Y246821D01*
X523328Y246776D01*
X523323Y246736D01*
X523313Y246691D01*
Y246521D01*
X523323Y246476D01*
X523328Y246436D01*
X523338Y246391D01*
X523348Y246351D01*
X523393Y246231D01*
X523433Y246151D01*
X523458Y246116D01*
X523478Y246081D01*
X523508Y246046D01*
X523533Y246011D01*
X523563Y245981D01*
Y243556D01*
X523573Y243431D01*
X523613Y243306D01*
X523673Y243196D01*
X523753Y243096D01*
X523853Y243016D01*
X523963Y242956D01*
X524088Y242916D01*
X524213Y242906D01*
X524338Y242916D01*
X524463Y242956D01*
X524573Y243016D01*
X524673Y243096D01*
X524753Y243196D01*
X524813Y243306D01*
X524853Y243431D01*
X524863Y243556D01*
Y245986D01*
X524893Y246016D01*
X524993Y246156D01*
X525013Y246196D01*
X525028Y246231D01*
X525048Y246271D01*
X525063Y246311D01*
X525073Y246351D01*
X525088Y246396D01*
X525093Y246436D01*
X525103Y246476D01*
X525108Y246521D01*
Y246561D01*
X525113Y246606D01*
X525108Y246651D01*
Y246691D01*
X525103Y246736D01*
X525093Y246776D01*
X525088Y246816D01*
X525073Y246861D01*
X525063Y246901D01*
X525048Y246941D01*
X525028Y246981D01*
X525013Y247016D01*
X524993Y247056D01*
X524893Y247196D01*
X524863Y247226D01*
Y249356D01*
X524853Y249481D01*
X524813Y249606D01*
X524753Y249716D01*
X524673Y249816D01*
X524573Y249896D01*
X524463Y249956D01*
X524338Y249996D01*
X524213Y250006D01*
G37*
G36*
G01X528937D02*
X528812Y249996D01*
X528687Y249956D01*
X528577Y249896D01*
X528477Y249816D01*
X528397Y249716D01*
X528337Y249606D01*
X528297Y249481D01*
X528287Y249356D01*
Y247231D01*
X528257Y247201D01*
X528232Y247166D01*
X528202Y247131D01*
X528182Y247096D01*
X528157Y247061D01*
X528117Y246981D01*
X528072Y246861D01*
X528062Y246821D01*
X528052Y246776D01*
X528047Y246736D01*
X528037Y246691D01*
Y246521D01*
X528047Y246476D01*
X528052Y246436D01*
X528062Y246391D01*
X528072Y246351D01*
X528117Y246231D01*
X528157Y246151D01*
X528182Y246116D01*
X528202Y246081D01*
X528232Y246046D01*
X528257Y246011D01*
X528287Y245981D01*
Y243556D01*
X528297Y243431D01*
X528337Y243306D01*
X528397Y243196D01*
X528477Y243096D01*
X528577Y243016D01*
X528687Y242956D01*
X528812Y242916D01*
X528937Y242906D01*
X529062Y242916D01*
X529187Y242956D01*
X529297Y243016D01*
X529397Y243096D01*
X529477Y243196D01*
X529537Y243306D01*
X529577Y243431D01*
X529587Y243556D01*
Y245986D01*
X529617Y246016D01*
X529717Y246156D01*
X529737Y246196D01*
X529752Y246231D01*
X529772Y246271D01*
X529787Y246311D01*
X529797Y246351D01*
X529812Y246396D01*
X529817Y246436D01*
X529827Y246476D01*
X529832Y246521D01*
Y246561D01*
X529837Y246606D01*
X529832Y246651D01*
Y246691D01*
X529827Y246736D01*
X529817Y246776D01*
X529812Y246816D01*
X529797Y246861D01*
X529787Y246901D01*
X529772Y246941D01*
X529752Y246981D01*
X529737Y247016D01*
X529717Y247056D01*
X529617Y247196D01*
X529587Y247226D01*
Y249356D01*
X529577Y249481D01*
X529537Y249606D01*
X529477Y249716D01*
X529397Y249816D01*
X529297Y249896D01*
X529187Y249956D01*
X529062Y249996D01*
X528937Y250006D01*
G37*
G36*
G01X533662D02*
X533537Y249996D01*
X533412Y249956D01*
X533302Y249896D01*
X533202Y249816D01*
X533122Y249716D01*
X533062Y249606D01*
X533022Y249481D01*
X533012Y249356D01*
Y247231D01*
X532982Y247201D01*
X532957Y247166D01*
X532927Y247131D01*
X532907Y247096D01*
X532882Y247061D01*
X532842Y246981D01*
X532797Y246861D01*
X532787Y246821D01*
X532777Y246776D01*
X532772Y246736D01*
X532762Y246691D01*
Y246521D01*
X532772Y246476D01*
X532777Y246436D01*
X532787Y246391D01*
X532797Y246351D01*
X532842Y246231D01*
X532882Y246151D01*
X532907Y246116D01*
X532927Y246081D01*
X532957Y246046D01*
X532982Y246011D01*
X533012Y245981D01*
Y243556D01*
X533022Y243431D01*
X533062Y243306D01*
X533122Y243196D01*
X533202Y243096D01*
X533302Y243016D01*
X533412Y242956D01*
X533537Y242916D01*
X533662Y242906D01*
X533787Y242916D01*
X533912Y242956D01*
X534022Y243016D01*
X534122Y243096D01*
X534202Y243196D01*
X534262Y243306D01*
X534302Y243431D01*
X534312Y243556D01*
Y245986D01*
X534342Y246016D01*
X534442Y246156D01*
X534462Y246196D01*
X534477Y246231D01*
X534497Y246271D01*
X534512Y246311D01*
X534522Y246351D01*
X534537Y246396D01*
X534542Y246436D01*
X534552Y246476D01*
X534557Y246521D01*
Y246561D01*
X534562Y246606D01*
X534557Y246651D01*
Y246691D01*
X534552Y246736D01*
X534542Y246776D01*
X534537Y246816D01*
X534522Y246861D01*
X534512Y246901D01*
X534497Y246941D01*
X534477Y246981D01*
X534462Y247016D01*
X534442Y247056D01*
X534342Y247196D01*
X534312Y247226D01*
Y249356D01*
X534302Y249481D01*
X534262Y249606D01*
X534202Y249716D01*
X534122Y249816D01*
X534022Y249896D01*
X533912Y249956D01*
X533787Y249996D01*
X533662Y250006D01*
G37*
G36*
G01X538386D02*
X538261Y249996D01*
X538136Y249956D01*
X538026Y249896D01*
X537926Y249816D01*
X537846Y249716D01*
X537786Y249606D01*
X537746Y249481D01*
X537736Y249356D01*
Y247231D01*
X537706Y247201D01*
X537681Y247166D01*
X537651Y247131D01*
X537631Y247096D01*
X537606Y247061D01*
X537566Y246981D01*
X537521Y246861D01*
X537511Y246821D01*
X537501Y246776D01*
X537496Y246736D01*
X537486Y246691D01*
Y246521D01*
X537496Y246476D01*
X537501Y246436D01*
X537511Y246391D01*
X537521Y246351D01*
X537566Y246231D01*
X537606Y246151D01*
X537631Y246116D01*
X537651Y246081D01*
X537681Y246046D01*
X537706Y246011D01*
X537736Y245981D01*
Y243556D01*
X537746Y243431D01*
X537786Y243306D01*
X537846Y243196D01*
X537926Y243096D01*
X538026Y243016D01*
X538136Y242956D01*
X538261Y242916D01*
X538386Y242906D01*
X538511Y242916D01*
X538636Y242956D01*
X538746Y243016D01*
X538846Y243096D01*
X538926Y243196D01*
X538986Y243306D01*
X539026Y243431D01*
X539036Y243556D01*
Y245986D01*
X539066Y246016D01*
X539166Y246156D01*
X539186Y246196D01*
X539201Y246231D01*
X539221Y246271D01*
X539236Y246311D01*
X539246Y246351D01*
X539261Y246396D01*
X539266Y246436D01*
X539276Y246476D01*
X539281Y246521D01*
Y246561D01*
X539286Y246606D01*
X539281Y246651D01*
Y246691D01*
X539276Y246736D01*
X539266Y246776D01*
X539261Y246816D01*
X539246Y246861D01*
X539236Y246901D01*
X539221Y246941D01*
X539201Y246981D01*
X539186Y247016D01*
X539166Y247056D01*
X539066Y247196D01*
X539036Y247226D01*
Y249356D01*
X539026Y249481D01*
X538986Y249606D01*
X538926Y249716D01*
X538846Y249816D01*
X538746Y249896D01*
X538636Y249956D01*
X538511Y249996D01*
X538386Y250006D01*
G37*
G36*
G01X543110D02*
X542985Y249996D01*
X542860Y249956D01*
X542750Y249896D01*
X542650Y249816D01*
X542570Y249716D01*
X542510Y249606D01*
X542470Y249481D01*
X542460Y249356D01*
Y247231D01*
X542430Y247201D01*
X542405Y247166D01*
X542375Y247131D01*
X542355Y247096D01*
X542330Y247061D01*
X542290Y246981D01*
X542245Y246861D01*
X542235Y246821D01*
X542225Y246776D01*
X542220Y246736D01*
X542210Y246691D01*
Y246521D01*
X542220Y246476D01*
X542225Y246436D01*
X542235Y246391D01*
X542245Y246351D01*
X542290Y246231D01*
X542330Y246151D01*
X542355Y246116D01*
X542375Y246081D01*
X542405Y246046D01*
X542430Y246011D01*
X542460Y245981D01*
Y243556D01*
X542470Y243431D01*
X542510Y243306D01*
X542570Y243196D01*
X542650Y243096D01*
X542750Y243016D01*
X542860Y242956D01*
X542985Y242916D01*
X543110Y242906D01*
X543235Y242916D01*
X543360Y242956D01*
X543470Y243016D01*
X543570Y243096D01*
X543650Y243196D01*
X543710Y243306D01*
X543750Y243431D01*
X543760Y243556D01*
Y245986D01*
X543790Y246016D01*
X543890Y246156D01*
X543910Y246196D01*
X543925Y246231D01*
X543945Y246271D01*
X543960Y246311D01*
X543970Y246351D01*
X543985Y246396D01*
X543990Y246436D01*
X544000Y246476D01*
X544005Y246521D01*
Y246561D01*
X544010Y246606D01*
X544005Y246651D01*
Y246691D01*
X544000Y246736D01*
X543990Y246776D01*
X543985Y246816D01*
X543970Y246861D01*
X543960Y246901D01*
X543945Y246941D01*
X543925Y246981D01*
X543910Y247016D01*
X543890Y247056D01*
X543790Y247196D01*
X543760Y247226D01*
Y249356D01*
X543750Y249481D01*
X543710Y249606D01*
X543650Y249716D01*
X543570Y249816D01*
X543470Y249896D01*
X543360Y249956D01*
X543235Y249996D01*
X543110Y250006D01*
G37*
G36*
G01X547835D02*
X547710Y249996D01*
X547585Y249956D01*
X547475Y249896D01*
X547375Y249816D01*
X547295Y249716D01*
X547235Y249606D01*
X547195Y249481D01*
X547185Y249356D01*
Y247231D01*
X547155Y247201D01*
X547130Y247166D01*
X547100Y247131D01*
X547080Y247096D01*
X547055Y247061D01*
X547015Y246981D01*
X546970Y246861D01*
X546960Y246821D01*
X546950Y246776D01*
X546945Y246736D01*
X546935Y246691D01*
Y246521D01*
X546945Y246476D01*
X546950Y246436D01*
X546960Y246391D01*
X546970Y246351D01*
X547015Y246231D01*
X547055Y246151D01*
X547080Y246116D01*
X547100Y246081D01*
X547130Y246046D01*
X547155Y246011D01*
X547185Y245981D01*
Y243556D01*
X547195Y243431D01*
X547235Y243306D01*
X547295Y243196D01*
X547375Y243096D01*
X547475Y243016D01*
X547585Y242956D01*
X547710Y242916D01*
X547835Y242906D01*
X547960Y242916D01*
X548085Y242956D01*
X548195Y243016D01*
X548295Y243096D01*
X548375Y243196D01*
X548435Y243306D01*
X548475Y243431D01*
X548485Y243556D01*
Y245986D01*
X548515Y246016D01*
X548615Y246156D01*
X548635Y246196D01*
X548650Y246231D01*
X548670Y246271D01*
X548685Y246311D01*
X548695Y246351D01*
X548710Y246396D01*
X548715Y246436D01*
X548725Y246476D01*
X548730Y246521D01*
Y246561D01*
X548735Y246606D01*
X548730Y246651D01*
Y246691D01*
X548725Y246736D01*
X548715Y246776D01*
X548710Y246816D01*
X548695Y246861D01*
X548685Y246901D01*
X548670Y246941D01*
X548650Y246981D01*
X548635Y247016D01*
X548615Y247056D01*
X548515Y247196D01*
X548485Y247226D01*
Y249356D01*
X548475Y249481D01*
X548435Y249606D01*
X548375Y249716D01*
X548295Y249816D01*
X548195Y249896D01*
X548085Y249956D01*
X547960Y249996D01*
X547835Y250006D01*
G37*
G36*
G01X552559D02*
X552434Y249996D01*
X552309Y249956D01*
X552199Y249896D01*
X552099Y249816D01*
X552019Y249716D01*
X551959Y249606D01*
X551919Y249481D01*
X551909Y249356D01*
Y247231D01*
X551879Y247201D01*
X551854Y247166D01*
X551824Y247131D01*
X551804Y247096D01*
X551779Y247061D01*
X551739Y246981D01*
X551694Y246861D01*
X551684Y246821D01*
X551674Y246776D01*
X551669Y246736D01*
X551659Y246691D01*
Y246521D01*
X551669Y246476D01*
X551674Y246436D01*
X551684Y246391D01*
X551694Y246351D01*
X551739Y246231D01*
X551779Y246151D01*
X551804Y246116D01*
X551824Y246081D01*
X551854Y246046D01*
X551879Y246011D01*
X551909Y245981D01*
Y243556D01*
X551919Y243431D01*
X551959Y243306D01*
X552019Y243196D01*
X552099Y243096D01*
X552199Y243016D01*
X552309Y242956D01*
X552434Y242916D01*
X552559Y242906D01*
X552684Y242916D01*
X552809Y242956D01*
X552919Y243016D01*
X553019Y243096D01*
X553099Y243196D01*
X553159Y243306D01*
X553199Y243431D01*
X553209Y243556D01*
Y245986D01*
X553239Y246016D01*
X553339Y246156D01*
X553359Y246196D01*
X553374Y246231D01*
X553394Y246271D01*
X553409Y246311D01*
X553419Y246351D01*
X553434Y246396D01*
X553439Y246436D01*
X553449Y246476D01*
X553454Y246521D01*
Y246561D01*
X553459Y246606D01*
X553454Y246651D01*
Y246691D01*
X553449Y246736D01*
X553439Y246776D01*
X553434Y246816D01*
X553419Y246861D01*
X553409Y246901D01*
X553394Y246941D01*
X553374Y246981D01*
X553359Y247016D01*
X553339Y247056D01*
X553239Y247196D01*
X553209Y247226D01*
Y249356D01*
X553199Y249481D01*
X553159Y249606D01*
X553099Y249716D01*
X553019Y249816D01*
X552919Y249896D01*
X552809Y249956D01*
X552684Y249996D01*
X552559Y250006D01*
G37*
G36*
G01X557284D02*
X557159Y249996D01*
X557034Y249956D01*
X556924Y249896D01*
X556824Y249816D01*
X556744Y249716D01*
X556684Y249606D01*
X556644Y249481D01*
X556634Y249356D01*
Y247231D01*
X556604Y247201D01*
X556579Y247166D01*
X556549Y247131D01*
X556529Y247096D01*
X556504Y247061D01*
X556464Y246981D01*
X556419Y246861D01*
X556409Y246821D01*
X556399Y246776D01*
X556394Y246736D01*
X556384Y246691D01*
Y246521D01*
X556394Y246476D01*
X556399Y246436D01*
X556409Y246391D01*
X556419Y246351D01*
X556464Y246231D01*
X556504Y246151D01*
X556529Y246116D01*
X556549Y246081D01*
X556579Y246046D01*
X556604Y246011D01*
X556634Y245981D01*
Y243556D01*
X556644Y243431D01*
X556684Y243306D01*
X556744Y243196D01*
X556824Y243096D01*
X556924Y243016D01*
X557034Y242956D01*
X557159Y242916D01*
X557284Y242906D01*
X557409Y242916D01*
X557534Y242956D01*
X557644Y243016D01*
X557744Y243096D01*
X557824Y243196D01*
X557884Y243306D01*
X557924Y243431D01*
X557934Y243556D01*
Y245986D01*
X557964Y246016D01*
X558064Y246156D01*
X558084Y246196D01*
X558099Y246231D01*
X558119Y246271D01*
X558134Y246311D01*
X558144Y246351D01*
X558159Y246396D01*
X558164Y246436D01*
X558174Y246476D01*
X558179Y246521D01*
Y246561D01*
X558184Y246606D01*
X558179Y246651D01*
Y246691D01*
X558174Y246736D01*
X558164Y246776D01*
X558159Y246816D01*
X558144Y246861D01*
X558134Y246901D01*
X558119Y246941D01*
X558099Y246981D01*
X558084Y247016D01*
X558064Y247056D01*
X557964Y247196D01*
X557934Y247226D01*
Y249356D01*
X557924Y249481D01*
X557884Y249606D01*
X557824Y249716D01*
X557744Y249816D01*
X557644Y249896D01*
X557534Y249956D01*
X557409Y249996D01*
X557284Y250006D01*
G37*
G36*
G01X562008D02*
X561883Y249996D01*
X561758Y249956D01*
X561648Y249896D01*
X561548Y249816D01*
X561468Y249716D01*
X561408Y249606D01*
X561368Y249481D01*
X561358Y249356D01*
Y247231D01*
X561328Y247201D01*
X561303Y247166D01*
X561273Y247131D01*
X561253Y247096D01*
X561228Y247061D01*
X561188Y246981D01*
X561143Y246861D01*
X561133Y246821D01*
X561123Y246776D01*
X561118Y246736D01*
X561108Y246691D01*
Y246521D01*
X561118Y246476D01*
X561123Y246436D01*
X561133Y246391D01*
X561143Y246351D01*
X561188Y246231D01*
X561228Y246151D01*
X561253Y246116D01*
X561273Y246081D01*
X561303Y246046D01*
X561328Y246011D01*
X561358Y245981D01*
Y243556D01*
X561368Y243431D01*
X561408Y243306D01*
X561468Y243196D01*
X561548Y243096D01*
X561648Y243016D01*
X561758Y242956D01*
X561883Y242916D01*
X562008Y242906D01*
X562133Y242916D01*
X562258Y242956D01*
X562368Y243016D01*
X562468Y243096D01*
X562548Y243196D01*
X562608Y243306D01*
X562648Y243431D01*
X562658Y243556D01*
Y245986D01*
X562688Y246016D01*
X562788Y246156D01*
X562808Y246196D01*
X562823Y246231D01*
X562843Y246271D01*
X562858Y246311D01*
X562868Y246351D01*
X562883Y246396D01*
X562888Y246436D01*
X562898Y246476D01*
X562903Y246521D01*
Y246561D01*
X562908Y246606D01*
X562903Y246651D01*
Y246691D01*
X562898Y246736D01*
X562888Y246776D01*
X562883Y246816D01*
X562868Y246861D01*
X562858Y246901D01*
X562843Y246941D01*
X562823Y246981D01*
X562808Y247016D01*
X562788Y247056D01*
X562688Y247196D01*
X562658Y247226D01*
Y249356D01*
X562648Y249481D01*
X562608Y249606D01*
X562548Y249716D01*
X562468Y249816D01*
X562368Y249896D01*
X562258Y249956D01*
X562133Y249996D01*
X562008Y250006D01*
G37*
G36*
G01X566733D02*
X566608Y249996D01*
X566483Y249956D01*
X566373Y249896D01*
X566273Y249816D01*
X566193Y249716D01*
X566133Y249606D01*
X566093Y249481D01*
X566083Y249356D01*
Y247231D01*
X566053Y247201D01*
X566028Y247166D01*
X565998Y247131D01*
X565978Y247096D01*
X565953Y247061D01*
X565913Y246981D01*
X565868Y246861D01*
X565858Y246821D01*
X565848Y246776D01*
X565843Y246736D01*
X565833Y246691D01*
Y246521D01*
X565843Y246476D01*
X565848Y246436D01*
X565858Y246391D01*
X565868Y246351D01*
X565913Y246231D01*
X565953Y246151D01*
X565978Y246116D01*
X565998Y246081D01*
X566028Y246046D01*
X566053Y246011D01*
X566083Y245981D01*
Y243556D01*
X566093Y243431D01*
X566133Y243306D01*
X566193Y243196D01*
X566273Y243096D01*
X566373Y243016D01*
X566483Y242956D01*
X566608Y242916D01*
X566733Y242906D01*
X566858Y242916D01*
X566983Y242956D01*
X567093Y243016D01*
X567193Y243096D01*
X567273Y243196D01*
X567333Y243306D01*
X567373Y243431D01*
X567383Y243556D01*
Y245986D01*
X567413Y246016D01*
X567513Y246156D01*
X567533Y246196D01*
X567548Y246231D01*
X567568Y246271D01*
X567583Y246311D01*
X567593Y246351D01*
X567608Y246396D01*
X567613Y246436D01*
X567623Y246476D01*
X567628Y246521D01*
Y246561D01*
X567633Y246606D01*
X567628Y246651D01*
Y246691D01*
X567623Y246736D01*
X567613Y246776D01*
X567608Y246816D01*
X567593Y246861D01*
X567583Y246901D01*
X567568Y246941D01*
X567548Y246981D01*
X567533Y247016D01*
X567513Y247056D01*
X567413Y247196D01*
X567383Y247226D01*
Y249356D01*
X567373Y249481D01*
X567333Y249606D01*
X567273Y249716D01*
X567193Y249816D01*
X567093Y249896D01*
X566983Y249956D01*
X566858Y249996D01*
X566733Y250006D01*
G37*
G36*
G01X571457D02*
X571332Y249996D01*
X571207Y249956D01*
X571097Y249896D01*
X570997Y249816D01*
X570917Y249716D01*
X570857Y249606D01*
X570817Y249481D01*
X570807Y249356D01*
Y247231D01*
X570777Y247201D01*
X570752Y247166D01*
X570722Y247131D01*
X570702Y247096D01*
X570677Y247061D01*
X570637Y246981D01*
X570592Y246861D01*
X570582Y246821D01*
X570572Y246776D01*
X570567Y246736D01*
X570557Y246691D01*
Y246521D01*
X570567Y246476D01*
X570572Y246436D01*
X570582Y246391D01*
X570592Y246351D01*
X570637Y246231D01*
X570677Y246151D01*
X570702Y246116D01*
X570722Y246081D01*
X570752Y246046D01*
X570777Y246011D01*
X570807Y245981D01*
Y243556D01*
X570817Y243431D01*
X570857Y243306D01*
X570917Y243196D01*
X570997Y243096D01*
X571097Y243016D01*
X571207Y242956D01*
X571332Y242916D01*
X571457Y242906D01*
X571582Y242916D01*
X571707Y242956D01*
X571817Y243016D01*
X571917Y243096D01*
X571997Y243196D01*
X572057Y243306D01*
X572097Y243431D01*
X572107Y243556D01*
Y245986D01*
X572137Y246016D01*
X572237Y246156D01*
X572257Y246196D01*
X572272Y246231D01*
X572292Y246271D01*
X572307Y246311D01*
X572317Y246351D01*
X572332Y246396D01*
X572337Y246436D01*
X572347Y246476D01*
X572352Y246521D01*
Y246561D01*
X572357Y246606D01*
X572352Y246651D01*
Y246691D01*
X572347Y246736D01*
X572337Y246776D01*
X572332Y246816D01*
X572317Y246861D01*
X572307Y246901D01*
X572292Y246941D01*
X572272Y246981D01*
X572257Y247016D01*
X572237Y247056D01*
X572137Y247196D01*
X572107Y247226D01*
Y249356D01*
X572097Y249481D01*
X572057Y249606D01*
X571997Y249716D01*
X571917Y249816D01*
X571817Y249896D01*
X571707Y249956D01*
X571582Y249996D01*
X571457Y250006D01*
G37*
G36*
G01X576181D02*
X576056Y249996D01*
X575931Y249956D01*
X575821Y249896D01*
X575721Y249816D01*
X575641Y249716D01*
X575581Y249606D01*
X575541Y249481D01*
X575531Y249356D01*
Y247231D01*
X575501Y247201D01*
X575476Y247166D01*
X575446Y247131D01*
X575426Y247096D01*
X575401Y247061D01*
X575361Y246981D01*
X575316Y246861D01*
X575306Y246821D01*
X575296Y246776D01*
X575291Y246736D01*
X575281Y246691D01*
Y246521D01*
X575291Y246476D01*
X575296Y246436D01*
X575306Y246391D01*
X575316Y246351D01*
X575361Y246231D01*
X575401Y246151D01*
X575426Y246116D01*
X575446Y246081D01*
X575476Y246046D01*
X575501Y246011D01*
X575531Y245981D01*
Y243556D01*
X575541Y243431D01*
X575581Y243306D01*
X575641Y243196D01*
X575721Y243096D01*
X575821Y243016D01*
X575931Y242956D01*
X576056Y242916D01*
X576181Y242906D01*
X576306Y242916D01*
X576431Y242956D01*
X576541Y243016D01*
X576641Y243096D01*
X576721Y243196D01*
X576781Y243306D01*
X576821Y243431D01*
X576831Y243556D01*
Y245986D01*
X576861Y246016D01*
X576961Y246156D01*
X576981Y246196D01*
X576996Y246231D01*
X577016Y246271D01*
X577031Y246311D01*
X577041Y246351D01*
X577056Y246396D01*
X577061Y246436D01*
X577071Y246476D01*
X577076Y246521D01*
Y246561D01*
X577081Y246606D01*
X577076Y246651D01*
Y246691D01*
X577071Y246736D01*
X577061Y246776D01*
X577056Y246816D01*
X577041Y246861D01*
X577031Y246901D01*
X577016Y246941D01*
X576996Y246981D01*
X576981Y247016D01*
X576961Y247056D01*
X576861Y247196D01*
X576831Y247226D01*
Y249356D01*
X576821Y249481D01*
X576781Y249606D01*
X576721Y249716D01*
X576641Y249816D01*
X576541Y249896D01*
X576431Y249956D01*
X576306Y249996D01*
X576181Y250006D01*
G37*
G36*
G01X580906D02*
X580781Y249996D01*
X580656Y249956D01*
X580546Y249896D01*
X580446Y249816D01*
X580366Y249716D01*
X580306Y249606D01*
X580266Y249481D01*
X580256Y249356D01*
Y247231D01*
X580226Y247201D01*
X580201Y247166D01*
X580171Y247131D01*
X580151Y247096D01*
X580126Y247061D01*
X580086Y246981D01*
X580041Y246861D01*
X580031Y246821D01*
X580021Y246776D01*
X580016Y246736D01*
X580006Y246691D01*
Y246521D01*
X580016Y246476D01*
X580021Y246436D01*
X580031Y246391D01*
X580041Y246351D01*
X580086Y246231D01*
X580126Y246151D01*
X580151Y246116D01*
X580171Y246081D01*
X580201Y246046D01*
X580226Y246011D01*
X580256Y245981D01*
Y243556D01*
X580266Y243431D01*
X580306Y243306D01*
X580366Y243196D01*
X580446Y243096D01*
X580546Y243016D01*
X580656Y242956D01*
X580781Y242916D01*
X580906Y242906D01*
X581031Y242916D01*
X581156Y242956D01*
X581266Y243016D01*
X581366Y243096D01*
X581446Y243196D01*
X581506Y243306D01*
X581546Y243431D01*
X581556Y243556D01*
Y245986D01*
X581586Y246016D01*
X581686Y246156D01*
X581706Y246196D01*
X581721Y246231D01*
X581741Y246271D01*
X581756Y246311D01*
X581766Y246351D01*
X581781Y246396D01*
X581786Y246436D01*
X581796Y246476D01*
X581801Y246521D01*
Y246561D01*
X581806Y246606D01*
X581801Y246651D01*
Y246691D01*
X581796Y246736D01*
X581786Y246776D01*
X581781Y246816D01*
X581766Y246861D01*
X581756Y246901D01*
X581741Y246941D01*
X581721Y246981D01*
X581706Y247016D01*
X581686Y247056D01*
X581586Y247196D01*
X581556Y247226D01*
Y249356D01*
X581546Y249481D01*
X581506Y249606D01*
X581446Y249716D01*
X581366Y249816D01*
X581266Y249896D01*
X581156Y249956D01*
X581031Y249996D01*
X580906Y250006D01*
G37*
G36*
G01X585630D02*
X585505Y249996D01*
X585380Y249956D01*
X585270Y249896D01*
X585170Y249816D01*
X585090Y249716D01*
X585030Y249606D01*
X584990Y249481D01*
X584980Y249356D01*
Y247231D01*
X584950Y247201D01*
X584925Y247166D01*
X584895Y247131D01*
X584875Y247096D01*
X584850Y247061D01*
X584810Y246981D01*
X584765Y246861D01*
X584755Y246821D01*
X584745Y246776D01*
X584740Y246736D01*
X584730Y246691D01*
Y246521D01*
X584740Y246476D01*
X584745Y246436D01*
X584755Y246391D01*
X584765Y246351D01*
X584810Y246231D01*
X584850Y246151D01*
X584875Y246116D01*
X584895Y246081D01*
X584925Y246046D01*
X584950Y246011D01*
X584980Y245981D01*
Y243556D01*
X584990Y243431D01*
X585030Y243306D01*
X585090Y243196D01*
X585170Y243096D01*
X585270Y243016D01*
X585380Y242956D01*
X585505Y242916D01*
X585630Y242906D01*
X585755Y242916D01*
X585880Y242956D01*
X585990Y243016D01*
X586090Y243096D01*
X586170Y243196D01*
X586230Y243306D01*
X586270Y243431D01*
X586280Y243556D01*
Y245986D01*
X586310Y246016D01*
X586410Y246156D01*
X586430Y246196D01*
X586445Y246231D01*
X586465Y246271D01*
X586480Y246311D01*
X586490Y246351D01*
X586505Y246396D01*
X586510Y246436D01*
X586520Y246476D01*
X586525Y246521D01*
Y246561D01*
X586530Y246606D01*
X586525Y246651D01*
Y246691D01*
X586520Y246736D01*
X586510Y246776D01*
X586505Y246816D01*
X586490Y246861D01*
X586480Y246901D01*
X586465Y246941D01*
X586445Y246981D01*
X586430Y247016D01*
X586410Y247056D01*
X586310Y247196D01*
X586280Y247226D01*
Y249356D01*
X586270Y249481D01*
X586230Y249606D01*
X586170Y249716D01*
X586090Y249816D01*
X585990Y249896D01*
X585880Y249956D01*
X585755Y249996D01*
X585630Y250006D01*
G37*
G36*
G01X590355D02*
X590230Y249996D01*
X590105Y249956D01*
X589995Y249896D01*
X589895Y249816D01*
X589815Y249716D01*
X589755Y249606D01*
X589715Y249481D01*
X589705Y249356D01*
Y247231D01*
X589675Y247201D01*
X589650Y247166D01*
X589620Y247131D01*
X589600Y247096D01*
X589575Y247061D01*
X589535Y246981D01*
X589490Y246861D01*
X589480Y246821D01*
X589470Y246776D01*
X589465Y246736D01*
X589455Y246691D01*
Y246521D01*
X589465Y246476D01*
X589470Y246436D01*
X589480Y246391D01*
X589490Y246351D01*
X589535Y246231D01*
X589575Y246151D01*
X589600Y246116D01*
X589620Y246081D01*
X589650Y246046D01*
X589675Y246011D01*
X589705Y245981D01*
Y243556D01*
X589715Y243431D01*
X589755Y243306D01*
X589815Y243196D01*
X589895Y243096D01*
X589995Y243016D01*
X590105Y242956D01*
X590230Y242916D01*
X590355Y242906D01*
X590480Y242916D01*
X590605Y242956D01*
X590715Y243016D01*
X590815Y243096D01*
X590895Y243196D01*
X590955Y243306D01*
X590995Y243431D01*
X591005Y243556D01*
Y245986D01*
X591035Y246016D01*
X591135Y246156D01*
X591155Y246196D01*
X591170Y246231D01*
X591190Y246271D01*
X591205Y246311D01*
X591215Y246351D01*
X591230Y246396D01*
X591235Y246436D01*
X591245Y246476D01*
X591250Y246521D01*
Y246561D01*
X591255Y246606D01*
X591250Y246651D01*
Y246691D01*
X591245Y246736D01*
X591235Y246776D01*
X591230Y246816D01*
X591215Y246861D01*
X591205Y246901D01*
X591190Y246941D01*
X591170Y246981D01*
X591155Y247016D01*
X591135Y247056D01*
X591035Y247196D01*
X591005Y247226D01*
Y249356D01*
X590995Y249481D01*
X590955Y249606D01*
X590895Y249716D01*
X590815Y249816D01*
X590715Y249896D01*
X590605Y249956D01*
X590480Y249996D01*
X590355Y250006D01*
G37*
G36*
G01X595079D02*
X594954Y249996D01*
X594829Y249956D01*
X594719Y249896D01*
X594619Y249816D01*
X594539Y249716D01*
X594479Y249606D01*
X594439Y249481D01*
X594429Y249356D01*
Y247231D01*
X594399Y247201D01*
X594374Y247166D01*
X594344Y247131D01*
X594324Y247096D01*
X594299Y247061D01*
X594259Y246981D01*
X594214Y246861D01*
X594204Y246821D01*
X594194Y246776D01*
X594189Y246736D01*
X594179Y246691D01*
Y246521D01*
X594189Y246476D01*
X594194Y246436D01*
X594204Y246391D01*
X594214Y246351D01*
X594259Y246231D01*
X594299Y246151D01*
X594324Y246116D01*
X594344Y246081D01*
X594374Y246046D01*
X594399Y246011D01*
X594429Y245981D01*
Y243556D01*
X594439Y243431D01*
X594479Y243306D01*
X594539Y243196D01*
X594619Y243096D01*
X594719Y243016D01*
X594829Y242956D01*
X594954Y242916D01*
X595079Y242906D01*
X595204Y242916D01*
X595329Y242956D01*
X595439Y243016D01*
X595539Y243096D01*
X595619Y243196D01*
X595679Y243306D01*
X595719Y243431D01*
X595729Y243556D01*
Y245986D01*
X595759Y246016D01*
X595859Y246156D01*
X595879Y246196D01*
X595894Y246231D01*
X595914Y246271D01*
X595929Y246311D01*
X595939Y246351D01*
X595954Y246396D01*
X595959Y246436D01*
X595969Y246476D01*
X595974Y246521D01*
Y246561D01*
X595979Y246606D01*
X595974Y246651D01*
Y246691D01*
X595969Y246736D01*
X595959Y246776D01*
X595954Y246816D01*
X595939Y246861D01*
X595929Y246901D01*
X595914Y246941D01*
X595894Y246981D01*
X595879Y247016D01*
X595859Y247056D01*
X595759Y247196D01*
X595729Y247226D01*
Y249356D01*
X595719Y249481D01*
X595679Y249606D01*
X595619Y249716D01*
X595539Y249816D01*
X595439Y249896D01*
X595329Y249956D01*
X595204Y249996D01*
X595079Y250006D01*
G37*
G36*
G01X599803D02*
X599678Y249996D01*
X599553Y249956D01*
X599443Y249896D01*
X599343Y249816D01*
X599263Y249716D01*
X599203Y249606D01*
X599163Y249481D01*
X599153Y249356D01*
Y247231D01*
X599123Y247201D01*
X599098Y247166D01*
X599068Y247131D01*
X599048Y247096D01*
X599023Y247061D01*
X598983Y246981D01*
X598938Y246861D01*
X598928Y246821D01*
X598918Y246776D01*
X598913Y246736D01*
X598903Y246691D01*
Y246521D01*
X598913Y246476D01*
X598918Y246436D01*
X598928Y246391D01*
X598938Y246351D01*
X598983Y246231D01*
X599023Y246151D01*
X599048Y246116D01*
X599068Y246081D01*
X599098Y246046D01*
X599123Y246011D01*
X599153Y245981D01*
Y243556D01*
X599163Y243431D01*
X599203Y243306D01*
X599263Y243196D01*
X599343Y243096D01*
X599443Y243016D01*
X599553Y242956D01*
X599678Y242916D01*
X599803Y242906D01*
X599928Y242916D01*
X600053Y242956D01*
X600163Y243016D01*
X600263Y243096D01*
X600343Y243196D01*
X600403Y243306D01*
X600443Y243431D01*
X600453Y243556D01*
Y245986D01*
X600483Y246016D01*
X600583Y246156D01*
X600603Y246196D01*
X600618Y246231D01*
X600638Y246271D01*
X600653Y246311D01*
X600663Y246351D01*
X600678Y246396D01*
X600683Y246436D01*
X600693Y246476D01*
X600698Y246521D01*
Y246561D01*
X600703Y246606D01*
X600698Y246651D01*
Y246691D01*
X600693Y246736D01*
X600683Y246776D01*
X600678Y246816D01*
X600663Y246861D01*
X600653Y246901D01*
X600638Y246941D01*
X600618Y246981D01*
X600603Y247016D01*
X600583Y247056D01*
X600483Y247196D01*
X600453Y247226D01*
Y249356D01*
X600443Y249481D01*
X600403Y249606D01*
X600343Y249716D01*
X600263Y249816D01*
X600163Y249896D01*
X600053Y249956D01*
X599928Y249996D01*
X599803Y250006D01*
G37*
G36*
G01X604528D02*
X604403Y249996D01*
X604278Y249956D01*
X604168Y249896D01*
X604068Y249816D01*
X603988Y249716D01*
X603928Y249606D01*
X603888Y249481D01*
X603878Y249356D01*
Y247231D01*
X603848Y247201D01*
X603823Y247166D01*
X603793Y247131D01*
X603773Y247096D01*
X603748Y247061D01*
X603708Y246981D01*
X603663Y246861D01*
X603653Y246821D01*
X603643Y246776D01*
X603638Y246736D01*
X603628Y246691D01*
Y246521D01*
X603638Y246476D01*
X603643Y246436D01*
X603653Y246391D01*
X603663Y246351D01*
X603708Y246231D01*
X603748Y246151D01*
X603773Y246116D01*
X603793Y246081D01*
X603823Y246046D01*
X603848Y246011D01*
X603878Y245981D01*
Y243556D01*
X603888Y243431D01*
X603928Y243306D01*
X603988Y243196D01*
X604068Y243096D01*
X604168Y243016D01*
X604278Y242956D01*
X604403Y242916D01*
X604528Y242906D01*
X604653Y242916D01*
X604778Y242956D01*
X604888Y243016D01*
X604988Y243096D01*
X605068Y243196D01*
X605128Y243306D01*
X605168Y243431D01*
X605178Y243556D01*
Y245986D01*
X605208Y246016D01*
X605308Y246156D01*
X605328Y246196D01*
X605343Y246231D01*
X605363Y246271D01*
X605378Y246311D01*
X605388Y246351D01*
X605403Y246396D01*
X605408Y246436D01*
X605418Y246476D01*
X605423Y246521D01*
Y246561D01*
X605428Y246606D01*
X605423Y246651D01*
Y246691D01*
X605418Y246736D01*
X605408Y246776D01*
X605403Y246816D01*
X605388Y246861D01*
X605378Y246901D01*
X605363Y246941D01*
X605343Y246981D01*
X605328Y247016D01*
X605308Y247056D01*
X605208Y247196D01*
X605178Y247226D01*
Y249356D01*
X605168Y249481D01*
X605128Y249606D01*
X605068Y249716D01*
X604988Y249816D01*
X604888Y249896D01*
X604778Y249956D01*
X604653Y249996D01*
X604528Y250006D01*
G37*
G36*
G01X609252D02*
X609127Y249996D01*
X609002Y249956D01*
X608892Y249896D01*
X608792Y249816D01*
X608712Y249716D01*
X608652Y249606D01*
X608612Y249481D01*
X608602Y249356D01*
Y247231D01*
X608572Y247201D01*
X608547Y247166D01*
X608517Y247131D01*
X608497Y247096D01*
X608472Y247061D01*
X608432Y246981D01*
X608387Y246861D01*
X608377Y246821D01*
X608367Y246776D01*
X608362Y246736D01*
X608352Y246691D01*
Y246521D01*
X608362Y246476D01*
X608367Y246436D01*
X608377Y246391D01*
X608387Y246351D01*
X608432Y246231D01*
X608472Y246151D01*
X608497Y246116D01*
X608517Y246081D01*
X608547Y246046D01*
X608572Y246011D01*
X608602Y245981D01*
Y243556D01*
X608612Y243431D01*
X608652Y243306D01*
X608712Y243196D01*
X608792Y243096D01*
X608892Y243016D01*
X609002Y242956D01*
X609127Y242916D01*
X609252Y242906D01*
X609377Y242916D01*
X609502Y242956D01*
X609612Y243016D01*
X609712Y243096D01*
X609792Y243196D01*
X609852Y243306D01*
X609892Y243431D01*
X609902Y243556D01*
Y245986D01*
X609932Y246016D01*
X610032Y246156D01*
X610052Y246196D01*
X610067Y246231D01*
X610087Y246271D01*
X610102Y246311D01*
X610112Y246351D01*
X610127Y246396D01*
X610132Y246436D01*
X610142Y246476D01*
X610147Y246521D01*
Y246561D01*
X610152Y246606D01*
X610147Y246651D01*
Y246691D01*
X610142Y246736D01*
X610132Y246776D01*
X610127Y246816D01*
X610112Y246861D01*
X610102Y246901D01*
X610087Y246941D01*
X610067Y246981D01*
X610052Y247016D01*
X610032Y247056D01*
X609932Y247196D01*
X609902Y247226D01*
Y249356D01*
X609892Y249481D01*
X609852Y249606D01*
X609792Y249716D01*
X609712Y249816D01*
X609612Y249896D01*
X609502Y249956D01*
X609377Y249996D01*
X609252Y250006D01*
G37*
G36*
G01X613977D02*
X613852Y249996D01*
X613727Y249956D01*
X613617Y249896D01*
X613517Y249816D01*
X613437Y249716D01*
X613377Y249606D01*
X613337Y249481D01*
X613327Y249356D01*
Y247231D01*
X613297Y247201D01*
X613272Y247166D01*
X613242Y247131D01*
X613222Y247096D01*
X613197Y247061D01*
X613157Y246981D01*
X613112Y246861D01*
X613102Y246821D01*
X613092Y246776D01*
X613087Y246736D01*
X613077Y246691D01*
Y246521D01*
X613087Y246476D01*
X613092Y246436D01*
X613102Y246391D01*
X613112Y246351D01*
X613157Y246231D01*
X613197Y246151D01*
X613222Y246116D01*
X613242Y246081D01*
X613272Y246046D01*
X613297Y246011D01*
X613327Y245981D01*
Y243556D01*
X613337Y243431D01*
X613377Y243306D01*
X613437Y243196D01*
X613517Y243096D01*
X613617Y243016D01*
X613727Y242956D01*
X613852Y242916D01*
X613977Y242906D01*
X614102Y242916D01*
X614227Y242956D01*
X614337Y243016D01*
X614437Y243096D01*
X614517Y243196D01*
X614577Y243306D01*
X614617Y243431D01*
X614627Y243556D01*
Y245986D01*
X614657Y246016D01*
X614757Y246156D01*
X614777Y246196D01*
X614792Y246231D01*
X614812Y246271D01*
X614827Y246311D01*
X614837Y246351D01*
X614852Y246396D01*
X614857Y246436D01*
X614867Y246476D01*
X614872Y246521D01*
Y246561D01*
X614877Y246606D01*
X614872Y246651D01*
Y246691D01*
X614867Y246736D01*
X614857Y246776D01*
X614852Y246816D01*
X614837Y246861D01*
X614827Y246901D01*
X614812Y246941D01*
X614792Y246981D01*
X614777Y247016D01*
X614757Y247056D01*
X614657Y247196D01*
X614627Y247226D01*
Y249356D01*
X614617Y249481D01*
X614577Y249606D01*
X614517Y249716D01*
X614437Y249816D01*
X614337Y249896D01*
X614227Y249956D01*
X614102Y249996D01*
X613977Y250006D01*
G37*
G36*
G01X618701D02*
X618576Y249996D01*
X618451Y249956D01*
X618341Y249896D01*
X618241Y249816D01*
X618161Y249716D01*
X618101Y249606D01*
X618061Y249481D01*
X618051Y249356D01*
Y247231D01*
X618021Y247201D01*
X617996Y247166D01*
X617966Y247131D01*
X617946Y247096D01*
X617921Y247061D01*
X617881Y246981D01*
X617836Y246861D01*
X617826Y246821D01*
X617816Y246776D01*
X617811Y246736D01*
X617801Y246691D01*
Y246521D01*
X617811Y246476D01*
X617816Y246436D01*
X617826Y246391D01*
X617836Y246351D01*
X617881Y246231D01*
X617921Y246151D01*
X617946Y246116D01*
X617966Y246081D01*
X617996Y246046D01*
X618021Y246011D01*
X618051Y245981D01*
Y243556D01*
X618061Y243431D01*
X618101Y243306D01*
X618161Y243196D01*
X618241Y243096D01*
X618341Y243016D01*
X618451Y242956D01*
X618576Y242916D01*
X618701Y242906D01*
X618826Y242916D01*
X618951Y242956D01*
X619061Y243016D01*
X619161Y243096D01*
X619241Y243196D01*
X619301Y243306D01*
X619341Y243431D01*
X619351Y243556D01*
Y245986D01*
X619381Y246016D01*
X619481Y246156D01*
X619501Y246196D01*
X619516Y246231D01*
X619536Y246271D01*
X619551Y246311D01*
X619561Y246351D01*
X619576Y246396D01*
X619581Y246436D01*
X619591Y246476D01*
X619596Y246521D01*
Y246561D01*
X619601Y246606D01*
X619596Y246651D01*
Y246691D01*
X619591Y246736D01*
X619581Y246776D01*
X619576Y246816D01*
X619561Y246861D01*
X619551Y246901D01*
X619536Y246941D01*
X619516Y246981D01*
X619501Y247016D01*
X619481Y247056D01*
X619381Y247196D01*
X619351Y247226D01*
Y249356D01*
X619341Y249481D01*
X619301Y249606D01*
X619241Y249716D01*
X619161Y249816D01*
X619061Y249896D01*
X618951Y249956D01*
X618826Y249996D01*
X618701Y250006D01*
G37*
G36*
G01X623425D02*
X623300Y249996D01*
X623175Y249956D01*
X623065Y249896D01*
X622965Y249816D01*
X622885Y249716D01*
X622825Y249606D01*
X622785Y249481D01*
X622775Y249356D01*
Y247231D01*
X622745Y247201D01*
X622720Y247166D01*
X622690Y247131D01*
X622670Y247096D01*
X622645Y247061D01*
X622605Y246981D01*
X622560Y246861D01*
X622550Y246821D01*
X622540Y246776D01*
X622535Y246736D01*
X622525Y246691D01*
Y246521D01*
X622535Y246476D01*
X622540Y246436D01*
X622550Y246391D01*
X622560Y246351D01*
X622605Y246231D01*
X622645Y246151D01*
X622670Y246116D01*
X622690Y246081D01*
X622720Y246046D01*
X622745Y246011D01*
X622775Y245981D01*
Y243556D01*
X622785Y243431D01*
X622825Y243306D01*
X622885Y243196D01*
X622965Y243096D01*
X623065Y243016D01*
X623175Y242956D01*
X623300Y242916D01*
X623425Y242906D01*
X623550Y242916D01*
X623675Y242956D01*
X623785Y243016D01*
X623885Y243096D01*
X623965Y243196D01*
X624025Y243306D01*
X624065Y243431D01*
X624075Y243556D01*
Y245986D01*
X624105Y246016D01*
X624205Y246156D01*
X624225Y246196D01*
X624240Y246231D01*
X624260Y246271D01*
X624275Y246311D01*
X624285Y246351D01*
X624300Y246396D01*
X624305Y246436D01*
X624315Y246476D01*
X624320Y246521D01*
Y246561D01*
X624325Y246606D01*
X624320Y246651D01*
Y246691D01*
X624315Y246736D01*
X624305Y246776D01*
X624300Y246816D01*
X624285Y246861D01*
X624275Y246901D01*
X624260Y246941D01*
X624240Y246981D01*
X624225Y247016D01*
X624205Y247056D01*
X624105Y247196D01*
X624075Y247226D01*
Y249356D01*
X624065Y249481D01*
X624025Y249606D01*
X623965Y249716D01*
X623885Y249816D01*
X623785Y249896D01*
X623675Y249956D01*
X623550Y249996D01*
X623425Y250006D01*
G37*
G36*
G01X628150D02*
X628025Y249996D01*
X627900Y249956D01*
X627790Y249896D01*
X627690Y249816D01*
X627610Y249716D01*
X627550Y249606D01*
X627510Y249481D01*
X627500Y249356D01*
Y247231D01*
X627470Y247201D01*
X627445Y247166D01*
X627415Y247131D01*
X627395Y247096D01*
X627370Y247061D01*
X627330Y246981D01*
X627285Y246861D01*
X627275Y246821D01*
X627265Y246776D01*
X627260Y246736D01*
X627250Y246691D01*
Y246521D01*
X627260Y246476D01*
X627265Y246436D01*
X627275Y246391D01*
X627285Y246351D01*
X627330Y246231D01*
X627370Y246151D01*
X627395Y246116D01*
X627415Y246081D01*
X627445Y246046D01*
X627470Y246011D01*
X627500Y245981D01*
Y243556D01*
X627510Y243431D01*
X627550Y243306D01*
X627610Y243196D01*
X627690Y243096D01*
X627790Y243016D01*
X627900Y242956D01*
X628025Y242916D01*
X628150Y242906D01*
X628275Y242916D01*
X628400Y242956D01*
X628510Y243016D01*
X628610Y243096D01*
X628690Y243196D01*
X628750Y243306D01*
X628790Y243431D01*
X628800Y243556D01*
Y245986D01*
X628830Y246016D01*
X628930Y246156D01*
X628950Y246196D01*
X628965Y246231D01*
X628985Y246271D01*
X629000Y246311D01*
X629010Y246351D01*
X629025Y246396D01*
X629030Y246436D01*
X629040Y246476D01*
X629045Y246521D01*
Y246561D01*
X629050Y246606D01*
X629045Y246651D01*
Y246691D01*
X629040Y246736D01*
X629030Y246776D01*
X629025Y246816D01*
X629010Y246861D01*
X629000Y246901D01*
X628985Y246941D01*
X628965Y246981D01*
X628950Y247016D01*
X628930Y247056D01*
X628830Y247196D01*
X628800Y247226D01*
Y249356D01*
X628790Y249481D01*
X628750Y249606D01*
X628690Y249716D01*
X628610Y249816D01*
X628510Y249896D01*
X628400Y249956D01*
X628275Y249996D01*
X628150Y250006D01*
G37*
G36*
G01X632874D02*
X632749Y249996D01*
X632624Y249956D01*
X632514Y249896D01*
X632414Y249816D01*
X632334Y249716D01*
X632274Y249606D01*
X632234Y249481D01*
X632224Y249356D01*
Y247231D01*
X632194Y247201D01*
X632169Y247166D01*
X632139Y247131D01*
X632119Y247096D01*
X632094Y247061D01*
X632054Y246981D01*
X632009Y246861D01*
X631999Y246821D01*
X631989Y246776D01*
X631984Y246736D01*
X631974Y246691D01*
Y246521D01*
X631984Y246476D01*
X631989Y246436D01*
X631999Y246391D01*
X632009Y246351D01*
X632054Y246231D01*
X632094Y246151D01*
X632119Y246116D01*
X632139Y246081D01*
X632169Y246046D01*
X632194Y246011D01*
X632224Y245981D01*
Y243556D01*
X632234Y243431D01*
X632274Y243306D01*
X632334Y243196D01*
X632414Y243096D01*
X632514Y243016D01*
X632624Y242956D01*
X632749Y242916D01*
X632874Y242906D01*
X632999Y242916D01*
X633124Y242956D01*
X633234Y243016D01*
X633334Y243096D01*
X633414Y243196D01*
X633474Y243306D01*
X633514Y243431D01*
X633524Y243556D01*
Y245986D01*
X633554Y246016D01*
X633654Y246156D01*
X633674Y246196D01*
X633689Y246231D01*
X633709Y246271D01*
X633724Y246311D01*
X633734Y246351D01*
X633749Y246396D01*
X633754Y246436D01*
X633764Y246476D01*
X633769Y246521D01*
Y246561D01*
X633774Y246606D01*
X633769Y246651D01*
Y246691D01*
X633764Y246736D01*
X633754Y246776D01*
X633749Y246816D01*
X633734Y246861D01*
X633724Y246901D01*
X633709Y246941D01*
X633689Y246981D01*
X633674Y247016D01*
X633654Y247056D01*
X633554Y247196D01*
X633524Y247226D01*
Y249356D01*
X633514Y249481D01*
X633474Y249606D01*
X633414Y249716D01*
X633334Y249816D01*
X633234Y249896D01*
X633124Y249956D01*
X632999Y249996D01*
X632874Y250006D01*
G37*
G36*
G01X637599D02*
X637474Y249996D01*
X637349Y249956D01*
X637239Y249896D01*
X637139Y249816D01*
X637059Y249716D01*
X636999Y249606D01*
X636959Y249481D01*
X636949Y249356D01*
Y247231D01*
X636919Y247201D01*
X636894Y247166D01*
X636864Y247131D01*
X636844Y247096D01*
X636819Y247061D01*
X636779Y246981D01*
X636734Y246861D01*
X636724Y246821D01*
X636714Y246776D01*
X636709Y246736D01*
X636699Y246691D01*
Y246521D01*
X636709Y246476D01*
X636714Y246436D01*
X636724Y246391D01*
X636734Y246351D01*
X636779Y246231D01*
X636819Y246151D01*
X636844Y246116D01*
X636864Y246081D01*
X636894Y246046D01*
X636919Y246011D01*
X636949Y245981D01*
Y243556D01*
X636959Y243431D01*
X636999Y243306D01*
X637059Y243196D01*
X637139Y243096D01*
X637239Y243016D01*
X637349Y242956D01*
X637474Y242916D01*
X637599Y242906D01*
X637724Y242916D01*
X637849Y242956D01*
X637959Y243016D01*
X638059Y243096D01*
X638139Y243196D01*
X638199Y243306D01*
X638239Y243431D01*
X638249Y243556D01*
Y245986D01*
X638279Y246016D01*
X638379Y246156D01*
X638399Y246196D01*
X638414Y246231D01*
X638434Y246271D01*
X638449Y246311D01*
X638459Y246351D01*
X638474Y246396D01*
X638479Y246436D01*
X638489Y246476D01*
X638494Y246521D01*
Y246561D01*
X638499Y246606D01*
X638494Y246651D01*
Y246691D01*
X638489Y246736D01*
X638479Y246776D01*
X638474Y246816D01*
X638459Y246861D01*
X638449Y246901D01*
X638434Y246941D01*
X638414Y246981D01*
X638399Y247016D01*
X638379Y247056D01*
X638279Y247196D01*
X638249Y247226D01*
Y249356D01*
X638239Y249481D01*
X638199Y249606D01*
X638139Y249716D01*
X638059Y249816D01*
X637959Y249896D01*
X637849Y249956D01*
X637724Y249996D01*
X637599Y250006D01*
G37*
G36*
G01X642323D02*
X642198Y249996D01*
X642073Y249956D01*
X641963Y249896D01*
X641863Y249816D01*
X641783Y249716D01*
X641723Y249606D01*
X641683Y249481D01*
X641673Y249356D01*
Y247231D01*
X641643Y247201D01*
X641618Y247166D01*
X641588Y247131D01*
X641568Y247096D01*
X641543Y247061D01*
X641503Y246981D01*
X641458Y246861D01*
X641448Y246821D01*
X641438Y246776D01*
X641433Y246736D01*
X641423Y246691D01*
Y246521D01*
X641433Y246476D01*
X641438Y246436D01*
X641448Y246391D01*
X641458Y246351D01*
X641503Y246231D01*
X641543Y246151D01*
X641568Y246116D01*
X641588Y246081D01*
X641618Y246046D01*
X641643Y246011D01*
X641673Y245981D01*
Y243556D01*
X641683Y243431D01*
X641723Y243306D01*
X641783Y243196D01*
X641863Y243096D01*
X641963Y243016D01*
X642073Y242956D01*
X642198Y242916D01*
X642323Y242906D01*
X642448Y242916D01*
X642573Y242956D01*
X642683Y243016D01*
X642783Y243096D01*
X642863Y243196D01*
X642923Y243306D01*
X642963Y243431D01*
X642973Y243556D01*
Y245986D01*
X643003Y246016D01*
X643103Y246156D01*
X643123Y246196D01*
X643138Y246231D01*
X643158Y246271D01*
X643173Y246311D01*
X643183Y246351D01*
X643198Y246396D01*
X643203Y246436D01*
X643213Y246476D01*
X643218Y246521D01*
Y246561D01*
X643223Y246606D01*
X643218Y246651D01*
Y246691D01*
X643213Y246736D01*
X643203Y246776D01*
X643198Y246816D01*
X643183Y246861D01*
X643173Y246901D01*
X643158Y246941D01*
X643138Y246981D01*
X643123Y247016D01*
X643103Y247056D01*
X643003Y247196D01*
X642973Y247226D01*
Y249356D01*
X642963Y249481D01*
X642923Y249606D01*
X642863Y249716D01*
X642783Y249816D01*
X642683Y249896D01*
X642573Y249956D01*
X642448Y249996D01*
X642323Y250006D01*
G37*
G36*
G01X647047D02*
X646922Y249996D01*
X646797Y249956D01*
X646687Y249896D01*
X646587Y249816D01*
X646507Y249716D01*
X646447Y249606D01*
X646407Y249481D01*
X646397Y249356D01*
Y247231D01*
X646367Y247201D01*
X646342Y247166D01*
X646312Y247131D01*
X646292Y247096D01*
X646267Y247061D01*
X646227Y246981D01*
X646182Y246861D01*
X646172Y246821D01*
X646162Y246776D01*
X646157Y246736D01*
X646147Y246691D01*
Y246521D01*
X646157Y246476D01*
X646162Y246436D01*
X646172Y246391D01*
X646182Y246351D01*
X646227Y246231D01*
X646267Y246151D01*
X646292Y246116D01*
X646312Y246081D01*
X646342Y246046D01*
X646367Y246011D01*
X646397Y245981D01*
Y243556D01*
X646407Y243431D01*
X646447Y243306D01*
X646507Y243196D01*
X646587Y243096D01*
X646687Y243016D01*
X646797Y242956D01*
X646922Y242916D01*
X647047Y242906D01*
X647172Y242916D01*
X647297Y242956D01*
X647407Y243016D01*
X647507Y243096D01*
X647587Y243196D01*
X647647Y243306D01*
X647687Y243431D01*
X647697Y243556D01*
Y245986D01*
X647727Y246016D01*
X647827Y246156D01*
X647847Y246196D01*
X647862Y246231D01*
X647882Y246271D01*
X647897Y246311D01*
X647907Y246351D01*
X647922Y246396D01*
X647927Y246436D01*
X647937Y246476D01*
X647942Y246521D01*
Y246561D01*
X647947Y246606D01*
X647942Y246651D01*
Y246691D01*
X647937Y246736D01*
X647927Y246776D01*
X647922Y246816D01*
X647907Y246861D01*
X647897Y246901D01*
X647882Y246941D01*
X647862Y246981D01*
X647847Y247016D01*
X647827Y247056D01*
X647727Y247196D01*
X647697Y247226D01*
Y249356D01*
X647687Y249481D01*
X647647Y249606D01*
X647587Y249716D01*
X647507Y249816D01*
X647407Y249896D01*
X647297Y249956D01*
X647172Y249996D01*
X647047Y250006D01*
G37*
G36*
G01X651772D02*
X651647Y249996D01*
X651522Y249956D01*
X651412Y249896D01*
X651312Y249816D01*
X651232Y249716D01*
X651172Y249606D01*
X651132Y249481D01*
X651122Y249356D01*
Y247231D01*
X651092Y247201D01*
X651067Y247166D01*
X651037Y247131D01*
X651017Y247096D01*
X650992Y247061D01*
X650952Y246981D01*
X650907Y246861D01*
X650897Y246821D01*
X650887Y246776D01*
X650882Y246736D01*
X650872Y246691D01*
Y246521D01*
X650882Y246476D01*
X650887Y246436D01*
X650897Y246391D01*
X650907Y246351D01*
X650952Y246231D01*
X650992Y246151D01*
X651017Y246116D01*
X651037Y246081D01*
X651067Y246046D01*
X651092Y246011D01*
X651122Y245981D01*
Y243556D01*
X651132Y243431D01*
X651172Y243306D01*
X651232Y243196D01*
X651312Y243096D01*
X651412Y243016D01*
X651522Y242956D01*
X651647Y242916D01*
X651772Y242906D01*
X651897Y242916D01*
X652022Y242956D01*
X652132Y243016D01*
X652232Y243096D01*
X652312Y243196D01*
X652372Y243306D01*
X652412Y243431D01*
X652422Y243556D01*
Y245986D01*
X652452Y246016D01*
X652552Y246156D01*
X652572Y246196D01*
X652587Y246231D01*
X652607Y246271D01*
X652622Y246311D01*
X652632Y246351D01*
X652647Y246396D01*
X652652Y246436D01*
X652662Y246476D01*
X652667Y246521D01*
Y246561D01*
X652672Y246606D01*
X652667Y246651D01*
Y246691D01*
X652662Y246736D01*
X652652Y246776D01*
X652647Y246816D01*
X652632Y246861D01*
X652622Y246901D01*
X652607Y246941D01*
X652587Y246981D01*
X652572Y247016D01*
X652552Y247056D01*
X652452Y247196D01*
X652422Y247226D01*
Y249356D01*
X652412Y249481D01*
X652372Y249606D01*
X652312Y249716D01*
X652232Y249816D01*
X652132Y249896D01*
X652022Y249956D01*
X651897Y249996D01*
X651772Y250006D01*
G37*
G36*
G01X665945D02*
X665820Y249996D01*
X665695Y249956D01*
X665585Y249896D01*
X665485Y249816D01*
X665405Y249716D01*
X665345Y249606D01*
X665305Y249481D01*
X665295Y249356D01*
Y247231D01*
X665265Y247201D01*
X665240Y247166D01*
X665210Y247131D01*
X665190Y247096D01*
X665165Y247061D01*
X665125Y246981D01*
X665080Y246861D01*
X665070Y246821D01*
X665060Y246776D01*
X665055Y246736D01*
X665045Y246691D01*
Y246521D01*
X665055Y246476D01*
X665060Y246436D01*
X665070Y246391D01*
X665080Y246351D01*
X665125Y246231D01*
X665165Y246151D01*
X665190Y246116D01*
X665210Y246081D01*
X665240Y246046D01*
X665265Y246011D01*
X665295Y245981D01*
Y243556D01*
X665305Y243431D01*
X665345Y243306D01*
X665405Y243196D01*
X665485Y243096D01*
X665585Y243016D01*
X665695Y242956D01*
X665820Y242916D01*
X665945Y242906D01*
X666070Y242916D01*
X666195Y242956D01*
X666305Y243016D01*
X666405Y243096D01*
X666485Y243196D01*
X666545Y243306D01*
X666585Y243431D01*
X666595Y243556D01*
Y245986D01*
X666625Y246016D01*
X666725Y246156D01*
X666745Y246196D01*
X666760Y246231D01*
X666780Y246271D01*
X666795Y246311D01*
X666805Y246351D01*
X666820Y246396D01*
X666825Y246436D01*
X666835Y246476D01*
X666840Y246521D01*
Y246561D01*
X666845Y246606D01*
X666840Y246651D01*
Y246691D01*
X666835Y246736D01*
X666825Y246776D01*
X666820Y246816D01*
X666805Y246861D01*
X666795Y246901D01*
X666780Y246941D01*
X666760Y246981D01*
X666745Y247016D01*
X666725Y247056D01*
X666625Y247196D01*
X666595Y247226D01*
Y249356D01*
X666585Y249481D01*
X666545Y249606D01*
X666485Y249716D01*
X666405Y249816D01*
X666305Y249896D01*
X666195Y249956D01*
X666070Y249996D01*
X665945Y250006D01*
G37*
G36*
G01X670670D02*
X670545Y249996D01*
X670420Y249956D01*
X670310Y249896D01*
X670210Y249816D01*
X670130Y249716D01*
X670070Y249606D01*
X670030Y249481D01*
X670020Y249356D01*
Y247231D01*
X669990Y247201D01*
X669965Y247166D01*
X669935Y247131D01*
X669915Y247096D01*
X669890Y247061D01*
X669850Y246981D01*
X669805Y246861D01*
X669795Y246821D01*
X669785Y246776D01*
X669780Y246736D01*
X669770Y246691D01*
Y246521D01*
X669780Y246476D01*
X669785Y246436D01*
X669795Y246391D01*
X669805Y246351D01*
X669850Y246231D01*
X669890Y246151D01*
X669915Y246116D01*
X669935Y246081D01*
X669965Y246046D01*
X669990Y246011D01*
X670020Y245981D01*
Y243556D01*
X670030Y243431D01*
X670070Y243306D01*
X670130Y243196D01*
X670210Y243096D01*
X670310Y243016D01*
X670420Y242956D01*
X670545Y242916D01*
X670670Y242906D01*
X670795Y242916D01*
X670920Y242956D01*
X671030Y243016D01*
X671130Y243096D01*
X671210Y243196D01*
X671270Y243306D01*
X671310Y243431D01*
X671320Y243556D01*
Y245986D01*
X671350Y246016D01*
X671450Y246156D01*
X671470Y246196D01*
X671485Y246231D01*
X671505Y246271D01*
X671520Y246311D01*
X671530Y246351D01*
X671545Y246396D01*
X671550Y246436D01*
X671560Y246476D01*
X671565Y246521D01*
Y246561D01*
X671570Y246606D01*
X671565Y246651D01*
Y246691D01*
X671560Y246736D01*
X671550Y246776D01*
X671545Y246816D01*
X671530Y246861D01*
X671520Y246901D01*
X671505Y246941D01*
X671485Y246981D01*
X671470Y247016D01*
X671450Y247056D01*
X671350Y247196D01*
X671320Y247226D01*
Y249356D01*
X671310Y249481D01*
X671270Y249606D01*
X671210Y249716D01*
X671130Y249816D01*
X671030Y249896D01*
X670920Y249956D01*
X670795Y249996D01*
X670670Y250006D01*
G37*
G36*
G01X675394D02*
X675269Y249996D01*
X675144Y249956D01*
X675034Y249896D01*
X674934Y249816D01*
X674854Y249716D01*
X674794Y249606D01*
X674754Y249481D01*
X674744Y249356D01*
Y247231D01*
X674714Y247201D01*
X674689Y247166D01*
X674659Y247131D01*
X674639Y247096D01*
X674614Y247061D01*
X674574Y246981D01*
X674529Y246861D01*
X674519Y246821D01*
X674509Y246776D01*
X674504Y246736D01*
X674494Y246691D01*
Y246521D01*
X674504Y246476D01*
X674509Y246436D01*
X674519Y246391D01*
X674529Y246351D01*
X674574Y246231D01*
X674614Y246151D01*
X674639Y246116D01*
X674659Y246081D01*
X674689Y246046D01*
X674714Y246011D01*
X674744Y245981D01*
Y243556D01*
X674754Y243431D01*
X674794Y243306D01*
X674854Y243196D01*
X674934Y243096D01*
X675034Y243016D01*
X675144Y242956D01*
X675269Y242916D01*
X675394Y242906D01*
X675519Y242916D01*
X675644Y242956D01*
X675754Y243016D01*
X675854Y243096D01*
X675934Y243196D01*
X675994Y243306D01*
X676034Y243431D01*
X676044Y243556D01*
Y245986D01*
X676074Y246016D01*
X676174Y246156D01*
X676194Y246196D01*
X676209Y246231D01*
X676229Y246271D01*
X676244Y246311D01*
X676254Y246351D01*
X676269Y246396D01*
X676274Y246436D01*
X676284Y246476D01*
X676289Y246521D01*
Y246561D01*
X676294Y246606D01*
X676289Y246651D01*
Y246691D01*
X676284Y246736D01*
X676274Y246776D01*
X676269Y246816D01*
X676254Y246861D01*
X676244Y246901D01*
X676229Y246941D01*
X676209Y246981D01*
X676194Y247016D01*
X676174Y247056D01*
X676074Y247196D01*
X676044Y247226D01*
Y249356D01*
X676034Y249481D01*
X675994Y249606D01*
X675934Y249716D01*
X675854Y249816D01*
X675754Y249896D01*
X675644Y249956D01*
X675519Y249996D01*
X675394Y250006D01*
G37*
G36*
G01X680118D02*
X679993Y249996D01*
X679868Y249956D01*
X679758Y249896D01*
X679658Y249816D01*
X679578Y249716D01*
X679518Y249606D01*
X679478Y249481D01*
X679468Y249356D01*
Y247231D01*
X679438Y247201D01*
X679413Y247166D01*
X679383Y247131D01*
X679363Y247096D01*
X679338Y247061D01*
X679298Y246981D01*
X679253Y246861D01*
X679243Y246821D01*
X679233Y246776D01*
X679228Y246736D01*
X679218Y246691D01*
Y246521D01*
X679228Y246476D01*
X679233Y246436D01*
X679243Y246391D01*
X679253Y246351D01*
X679298Y246231D01*
X679338Y246151D01*
X679363Y246116D01*
X679383Y246081D01*
X679413Y246046D01*
X679438Y246011D01*
X679468Y245981D01*
Y243556D01*
X679478Y243431D01*
X679518Y243306D01*
X679578Y243196D01*
X679658Y243096D01*
X679758Y243016D01*
X679868Y242956D01*
X679993Y242916D01*
X680118Y242906D01*
X680243Y242916D01*
X680368Y242956D01*
X680478Y243016D01*
X680578Y243096D01*
X680658Y243196D01*
X680718Y243306D01*
X680758Y243431D01*
X680768Y243556D01*
Y245986D01*
X680798Y246016D01*
X680898Y246156D01*
X680918Y246196D01*
X680933Y246231D01*
X680953Y246271D01*
X680968Y246311D01*
X680978Y246351D01*
X680993Y246396D01*
X680998Y246436D01*
X681008Y246476D01*
X681013Y246521D01*
Y246561D01*
X681018Y246606D01*
X681013Y246651D01*
Y246691D01*
X681008Y246736D01*
X680998Y246776D01*
X680993Y246816D01*
X680978Y246861D01*
X680968Y246901D01*
X680953Y246941D01*
X680933Y246981D01*
X680918Y247016D01*
X680898Y247056D01*
X680798Y247196D01*
X680768Y247226D01*
Y249356D01*
X680758Y249481D01*
X680718Y249606D01*
X680658Y249716D01*
X680578Y249816D01*
X680478Y249896D01*
X680368Y249956D01*
X680243Y249996D01*
X680118Y250006D01*
G37*
G36*
G01X684843D02*
X684718Y249996D01*
X684593Y249956D01*
X684483Y249896D01*
X684383Y249816D01*
X684303Y249716D01*
X684243Y249606D01*
X684203Y249481D01*
X684193Y249356D01*
Y247231D01*
X684163Y247201D01*
X684138Y247166D01*
X684108Y247131D01*
X684088Y247096D01*
X684063Y247061D01*
X684023Y246981D01*
X683978Y246861D01*
X683968Y246821D01*
X683958Y246776D01*
X683953Y246736D01*
X683943Y246691D01*
Y246521D01*
X683953Y246476D01*
X683958Y246436D01*
X683968Y246391D01*
X683978Y246351D01*
X684023Y246231D01*
X684063Y246151D01*
X684088Y246116D01*
X684108Y246081D01*
X684138Y246046D01*
X684163Y246011D01*
X684193Y245981D01*
Y243556D01*
X684203Y243431D01*
X684243Y243306D01*
X684303Y243196D01*
X684383Y243096D01*
X684483Y243016D01*
X684593Y242956D01*
X684718Y242916D01*
X684843Y242906D01*
X684968Y242916D01*
X685093Y242956D01*
X685203Y243016D01*
X685303Y243096D01*
X685383Y243196D01*
X685443Y243306D01*
X685483Y243431D01*
X685493Y243556D01*
Y245986D01*
X685523Y246016D01*
X685623Y246156D01*
X685643Y246196D01*
X685658Y246231D01*
X685678Y246271D01*
X685693Y246311D01*
X685703Y246351D01*
X685718Y246396D01*
X685723Y246436D01*
X685733Y246476D01*
X685738Y246521D01*
Y246561D01*
X685743Y246606D01*
X685738Y246651D01*
Y246691D01*
X685733Y246736D01*
X685723Y246776D01*
X685718Y246816D01*
X685703Y246861D01*
X685693Y246901D01*
X685678Y246941D01*
X685658Y246981D01*
X685643Y247016D01*
X685623Y247056D01*
X685523Y247196D01*
X685493Y247226D01*
Y249356D01*
X685483Y249481D01*
X685443Y249606D01*
X685383Y249716D01*
X685303Y249816D01*
X685203Y249896D01*
X685093Y249956D01*
X684968Y249996D01*
X684843Y250006D01*
G37*
G36*
G01X689567D02*
X689442Y249996D01*
X689317Y249956D01*
X689207Y249896D01*
X689107Y249816D01*
X689027Y249716D01*
X688967Y249606D01*
X688927Y249481D01*
X688917Y249356D01*
Y247231D01*
X688887Y247201D01*
X688862Y247166D01*
X688832Y247131D01*
X688812Y247096D01*
X688787Y247061D01*
X688747Y246981D01*
X688702Y246861D01*
X688692Y246821D01*
X688682Y246776D01*
X688677Y246736D01*
X688667Y246691D01*
Y246521D01*
X688677Y246476D01*
X688682Y246436D01*
X688692Y246391D01*
X688702Y246351D01*
X688747Y246231D01*
X688787Y246151D01*
X688812Y246116D01*
X688832Y246081D01*
X688862Y246046D01*
X688887Y246011D01*
X688917Y245981D01*
Y243556D01*
X688927Y243431D01*
X688967Y243306D01*
X689027Y243196D01*
X689107Y243096D01*
X689207Y243016D01*
X689317Y242956D01*
X689442Y242916D01*
X689567Y242906D01*
X689692Y242916D01*
X689817Y242956D01*
X689927Y243016D01*
X690027Y243096D01*
X690107Y243196D01*
X690167Y243306D01*
X690207Y243431D01*
X690217Y243556D01*
Y245986D01*
X690247Y246016D01*
X690347Y246156D01*
X690367Y246196D01*
X690382Y246231D01*
X690402Y246271D01*
X690417Y246311D01*
X690427Y246351D01*
X690442Y246396D01*
X690447Y246436D01*
X690457Y246476D01*
X690462Y246521D01*
Y246561D01*
X690467Y246606D01*
X690462Y246651D01*
Y246691D01*
X690457Y246736D01*
X690447Y246776D01*
X690442Y246816D01*
X690427Y246861D01*
X690417Y246901D01*
X690402Y246941D01*
X690382Y246981D01*
X690367Y247016D01*
X690347Y247056D01*
X690247Y247196D01*
X690217Y247226D01*
Y249356D01*
X690207Y249481D01*
X690167Y249606D01*
X690107Y249716D01*
X690027Y249816D01*
X689927Y249896D01*
X689817Y249956D01*
X689692Y249996D01*
X689567Y250006D01*
G37*
G36*
G01X694292D02*
X694167Y249996D01*
X694042Y249956D01*
X693932Y249896D01*
X693832Y249816D01*
X693752Y249716D01*
X693692Y249606D01*
X693652Y249481D01*
X693642Y249356D01*
Y247231D01*
X693612Y247201D01*
X693587Y247166D01*
X693557Y247131D01*
X693537Y247096D01*
X693512Y247061D01*
X693472Y246981D01*
X693427Y246861D01*
X693417Y246821D01*
X693407Y246776D01*
X693402Y246736D01*
X693392Y246691D01*
Y246521D01*
X693402Y246476D01*
X693407Y246436D01*
X693417Y246391D01*
X693427Y246351D01*
X693472Y246231D01*
X693512Y246151D01*
X693537Y246116D01*
X693557Y246081D01*
X693587Y246046D01*
X693612Y246011D01*
X693642Y245981D01*
Y243556D01*
X693652Y243431D01*
X693692Y243306D01*
X693752Y243196D01*
X693832Y243096D01*
X693932Y243016D01*
X694042Y242956D01*
X694167Y242916D01*
X694292Y242906D01*
X694417Y242916D01*
X694542Y242956D01*
X694652Y243016D01*
X694752Y243096D01*
X694832Y243196D01*
X694892Y243306D01*
X694932Y243431D01*
X694942Y243556D01*
Y245986D01*
X694972Y246016D01*
X695072Y246156D01*
X695092Y246196D01*
X695107Y246231D01*
X695127Y246271D01*
X695142Y246311D01*
X695152Y246351D01*
X695167Y246396D01*
X695172Y246436D01*
X695182Y246476D01*
X695187Y246521D01*
Y246561D01*
X695192Y246606D01*
X695187Y246651D01*
Y246691D01*
X695182Y246736D01*
X695172Y246776D01*
X695167Y246816D01*
X695152Y246861D01*
X695142Y246901D01*
X695127Y246941D01*
X695107Y246981D01*
X695092Y247016D01*
X695072Y247056D01*
X694972Y247196D01*
X694942Y247226D01*
Y249356D01*
X694932Y249481D01*
X694892Y249606D01*
X694832Y249716D01*
X694752Y249816D01*
X694652Y249896D01*
X694542Y249956D01*
X694417Y249996D01*
X694292Y250006D01*
G37*
G36*
G01X699016D02*
X698891Y249996D01*
X698766Y249956D01*
X698656Y249896D01*
X698556Y249816D01*
X698476Y249716D01*
X698416Y249606D01*
X698376Y249481D01*
X698366Y249356D01*
Y247231D01*
X698336Y247201D01*
X698311Y247166D01*
X698281Y247131D01*
X698261Y247096D01*
X698236Y247061D01*
X698196Y246981D01*
X698151Y246861D01*
X698141Y246821D01*
X698131Y246776D01*
X698126Y246736D01*
X698116Y246691D01*
Y246521D01*
X698126Y246476D01*
X698131Y246436D01*
X698141Y246391D01*
X698151Y246351D01*
X698196Y246231D01*
X698236Y246151D01*
X698261Y246116D01*
X698281Y246081D01*
X698311Y246046D01*
X698336Y246011D01*
X698366Y245981D01*
Y243556D01*
X698376Y243431D01*
X698416Y243306D01*
X698476Y243196D01*
X698556Y243096D01*
X698656Y243016D01*
X698766Y242956D01*
X698891Y242916D01*
X699016Y242906D01*
X699141Y242916D01*
X699266Y242956D01*
X699376Y243016D01*
X699476Y243096D01*
X699556Y243196D01*
X699616Y243306D01*
X699656Y243431D01*
X699666Y243556D01*
Y245986D01*
X699696Y246016D01*
X699796Y246156D01*
X699816Y246196D01*
X699831Y246231D01*
X699851Y246271D01*
X699866Y246311D01*
X699876Y246351D01*
X699891Y246396D01*
X699896Y246436D01*
X699906Y246476D01*
X699911Y246521D01*
Y246561D01*
X699916Y246606D01*
X699911Y246651D01*
Y246691D01*
X699906Y246736D01*
X699896Y246776D01*
X699891Y246816D01*
X699876Y246861D01*
X699866Y246901D01*
X699851Y246941D01*
X699831Y246981D01*
X699816Y247016D01*
X699796Y247056D01*
X699696Y247196D01*
X699666Y247226D01*
Y249356D01*
X699656Y249481D01*
X699616Y249606D01*
X699556Y249716D01*
X699476Y249816D01*
X699376Y249896D01*
X699266Y249956D01*
X699141Y249996D01*
X699016Y250006D01*
G37*
G36*
G01X703740D02*
X703615Y249996D01*
X703490Y249956D01*
X703380Y249896D01*
X703280Y249816D01*
X703200Y249716D01*
X703140Y249606D01*
X703100Y249481D01*
X703090Y249356D01*
Y247231D01*
X703060Y247201D01*
X703035Y247166D01*
X703005Y247131D01*
X702985Y247096D01*
X702960Y247061D01*
X702920Y246981D01*
X702875Y246861D01*
X702865Y246821D01*
X702855Y246776D01*
X702850Y246736D01*
X702840Y246691D01*
Y246521D01*
X702850Y246476D01*
X702855Y246436D01*
X702865Y246391D01*
X702875Y246351D01*
X702920Y246231D01*
X702960Y246151D01*
X702985Y246116D01*
X703005Y246081D01*
X703035Y246046D01*
X703060Y246011D01*
X703090Y245981D01*
Y243556D01*
X703100Y243431D01*
X703140Y243306D01*
X703200Y243196D01*
X703280Y243096D01*
X703380Y243016D01*
X703490Y242956D01*
X703615Y242916D01*
X703740Y242906D01*
X703865Y242916D01*
X703990Y242956D01*
X704100Y243016D01*
X704200Y243096D01*
X704280Y243196D01*
X704340Y243306D01*
X704380Y243431D01*
X704390Y243556D01*
Y245986D01*
X704420Y246016D01*
X704520Y246156D01*
X704540Y246196D01*
X704555Y246231D01*
X704575Y246271D01*
X704590Y246311D01*
X704600Y246351D01*
X704615Y246396D01*
X704620Y246436D01*
X704630Y246476D01*
X704635Y246521D01*
Y246561D01*
X704640Y246606D01*
X704635Y246651D01*
Y246691D01*
X704630Y246736D01*
X704620Y246776D01*
X704615Y246816D01*
X704600Y246861D01*
X704590Y246901D01*
X704575Y246941D01*
X704555Y246981D01*
X704540Y247016D01*
X704520Y247056D01*
X704420Y247196D01*
X704390Y247226D01*
Y249356D01*
X704380Y249481D01*
X704340Y249606D01*
X704280Y249716D01*
X704200Y249816D01*
X704100Y249896D01*
X703990Y249956D01*
X703865Y249996D01*
X703740Y250006D01*
G37*
G36*
G01X708465D02*
X708340Y249996D01*
X708215Y249956D01*
X708105Y249896D01*
X708005Y249816D01*
X707925Y249716D01*
X707865Y249606D01*
X707825Y249481D01*
X707815Y249356D01*
Y247231D01*
X707785Y247201D01*
X707760Y247166D01*
X707730Y247131D01*
X707710Y247096D01*
X707685Y247061D01*
X707645Y246981D01*
X707600Y246861D01*
X707590Y246821D01*
X707580Y246776D01*
X707575Y246736D01*
X707565Y246691D01*
Y246521D01*
X707575Y246476D01*
X707580Y246436D01*
X707590Y246391D01*
X707600Y246351D01*
X707645Y246231D01*
X707685Y246151D01*
X707710Y246116D01*
X707730Y246081D01*
X707760Y246046D01*
X707785Y246011D01*
X707815Y245981D01*
Y243556D01*
X707825Y243431D01*
X707865Y243306D01*
X707925Y243196D01*
X708005Y243096D01*
X708105Y243016D01*
X708215Y242956D01*
X708340Y242916D01*
X708465Y242906D01*
X708590Y242916D01*
X708715Y242956D01*
X708825Y243016D01*
X708925Y243096D01*
X709005Y243196D01*
X709065Y243306D01*
X709105Y243431D01*
X709115Y243556D01*
Y245986D01*
X709145Y246016D01*
X709245Y246156D01*
X709265Y246196D01*
X709280Y246231D01*
X709300Y246271D01*
X709315Y246311D01*
X709325Y246351D01*
X709340Y246396D01*
X709345Y246436D01*
X709355Y246476D01*
X709360Y246521D01*
Y246561D01*
X709365Y246606D01*
X709360Y246651D01*
Y246691D01*
X709355Y246736D01*
X709345Y246776D01*
X709340Y246816D01*
X709325Y246861D01*
X709315Y246901D01*
X709300Y246941D01*
X709280Y246981D01*
X709265Y247016D01*
X709245Y247056D01*
X709145Y247196D01*
X709115Y247226D01*
Y249356D01*
X709105Y249481D01*
X709065Y249606D01*
X709005Y249716D01*
X708925Y249816D01*
X708825Y249896D01*
X708715Y249956D01*
X708590Y249996D01*
X708465Y250006D01*
G37*
G36*
G01X713189D02*
X713064Y249996D01*
X712939Y249956D01*
X712829Y249896D01*
X712729Y249816D01*
X712649Y249716D01*
X712589Y249606D01*
X712549Y249481D01*
X712539Y249356D01*
Y247231D01*
X712509Y247201D01*
X712484Y247166D01*
X712454Y247131D01*
X712434Y247096D01*
X712409Y247061D01*
X712369Y246981D01*
X712324Y246861D01*
X712314Y246821D01*
X712304Y246776D01*
X712299Y246736D01*
X712289Y246691D01*
Y246521D01*
X712299Y246476D01*
X712304Y246436D01*
X712314Y246391D01*
X712324Y246351D01*
X712369Y246231D01*
X712409Y246151D01*
X712434Y246116D01*
X712454Y246081D01*
X712484Y246046D01*
X712509Y246011D01*
X712539Y245981D01*
Y243556D01*
X712549Y243431D01*
X712589Y243306D01*
X712649Y243196D01*
X712729Y243096D01*
X712829Y243016D01*
X712939Y242956D01*
X713064Y242916D01*
X713189Y242906D01*
X713314Y242916D01*
X713439Y242956D01*
X713549Y243016D01*
X713649Y243096D01*
X713729Y243196D01*
X713789Y243306D01*
X713829Y243431D01*
X713839Y243556D01*
Y245986D01*
X713869Y246016D01*
X713969Y246156D01*
X713989Y246196D01*
X714004Y246231D01*
X714024Y246271D01*
X714039Y246311D01*
X714049Y246351D01*
X714064Y246396D01*
X714069Y246436D01*
X714079Y246476D01*
X714084Y246521D01*
Y246561D01*
X714089Y246606D01*
X714084Y246651D01*
Y246691D01*
X714079Y246736D01*
X714069Y246776D01*
X714064Y246816D01*
X714049Y246861D01*
X714039Y246901D01*
X714024Y246941D01*
X714004Y246981D01*
X713989Y247016D01*
X713969Y247056D01*
X713869Y247196D01*
X713839Y247226D01*
Y249356D01*
X713829Y249481D01*
X713789Y249606D01*
X713729Y249716D01*
X713649Y249816D01*
X713549Y249896D01*
X713439Y249956D01*
X713314Y249996D01*
X713189Y250006D01*
G37*
G36*
G01X717914D02*
X717789Y249996D01*
X717664Y249956D01*
X717554Y249896D01*
X717454Y249816D01*
X717374Y249716D01*
X717314Y249606D01*
X717274Y249481D01*
X717264Y249356D01*
Y247231D01*
X717234Y247201D01*
X717209Y247166D01*
X717179Y247131D01*
X717159Y247096D01*
X717134Y247061D01*
X717094Y246981D01*
X717049Y246861D01*
X717039Y246821D01*
X717029Y246776D01*
X717024Y246736D01*
X717014Y246691D01*
Y246521D01*
X717024Y246476D01*
X717029Y246436D01*
X717039Y246391D01*
X717049Y246351D01*
X717094Y246231D01*
X717134Y246151D01*
X717159Y246116D01*
X717179Y246081D01*
X717209Y246046D01*
X717234Y246011D01*
X717264Y245981D01*
Y243556D01*
X717274Y243431D01*
X717314Y243306D01*
X717374Y243196D01*
X717454Y243096D01*
X717554Y243016D01*
X717664Y242956D01*
X717789Y242916D01*
X717914Y242906D01*
X718039Y242916D01*
X718164Y242956D01*
X718274Y243016D01*
X718374Y243096D01*
X718454Y243196D01*
X718514Y243306D01*
X718554Y243431D01*
X718564Y243556D01*
Y245986D01*
X718594Y246016D01*
X718694Y246156D01*
X718714Y246196D01*
X718729Y246231D01*
X718749Y246271D01*
X718764Y246311D01*
X718774Y246351D01*
X718789Y246396D01*
X718794Y246436D01*
X718804Y246476D01*
X718809Y246521D01*
Y246561D01*
X718814Y246606D01*
X718809Y246651D01*
Y246691D01*
X718804Y246736D01*
X718794Y246776D01*
X718789Y246816D01*
X718774Y246861D01*
X718764Y246901D01*
X718749Y246941D01*
X718729Y246981D01*
X718714Y247016D01*
X718694Y247056D01*
X718594Y247196D01*
X718564Y247226D01*
Y249356D01*
X718554Y249481D01*
X718514Y249606D01*
X718454Y249716D01*
X718374Y249816D01*
X718274Y249896D01*
X718164Y249956D01*
X718039Y249996D01*
X717914Y250006D01*
G37*
G36*
G01X722638D02*
X722513Y249996D01*
X722388Y249956D01*
X722278Y249896D01*
X722178Y249816D01*
X722098Y249716D01*
X722038Y249606D01*
X721998Y249481D01*
X721988Y249356D01*
Y247231D01*
X721958Y247201D01*
X721933Y247166D01*
X721903Y247131D01*
X721883Y247096D01*
X721858Y247061D01*
X721818Y246981D01*
X721773Y246861D01*
X721763Y246821D01*
X721753Y246776D01*
X721748Y246736D01*
X721738Y246691D01*
Y246521D01*
X721748Y246476D01*
X721753Y246436D01*
X721763Y246391D01*
X721773Y246351D01*
X721818Y246231D01*
X721858Y246151D01*
X721883Y246116D01*
X721903Y246081D01*
X721933Y246046D01*
X721958Y246011D01*
X721988Y245981D01*
Y243556D01*
X721998Y243431D01*
X722038Y243306D01*
X722098Y243196D01*
X722178Y243096D01*
X722278Y243016D01*
X722388Y242956D01*
X722513Y242916D01*
X722638Y242906D01*
X722763Y242916D01*
X722888Y242956D01*
X722998Y243016D01*
X723098Y243096D01*
X723178Y243196D01*
X723238Y243306D01*
X723278Y243431D01*
X723288Y243556D01*
Y245986D01*
X723318Y246016D01*
X723418Y246156D01*
X723438Y246196D01*
X723453Y246231D01*
X723473Y246271D01*
X723488Y246311D01*
X723498Y246351D01*
X723513Y246396D01*
X723518Y246436D01*
X723528Y246476D01*
X723533Y246521D01*
Y246561D01*
X723538Y246606D01*
X723533Y246651D01*
Y246691D01*
X723528Y246736D01*
X723518Y246776D01*
X723513Y246816D01*
X723498Y246861D01*
X723488Y246901D01*
X723473Y246941D01*
X723453Y246981D01*
X723438Y247016D01*
X723418Y247056D01*
X723318Y247196D01*
X723288Y247226D01*
Y249356D01*
X723278Y249481D01*
X723238Y249606D01*
X723178Y249716D01*
X723098Y249816D01*
X722998Y249896D01*
X722888Y249956D01*
X722763Y249996D01*
X722638Y250006D01*
G37*
G36*
G01X727362D02*
X727237Y249996D01*
X727112Y249956D01*
X727002Y249896D01*
X726902Y249816D01*
X726822Y249716D01*
X726762Y249606D01*
X726722Y249481D01*
X726712Y249356D01*
Y247231D01*
X726682Y247201D01*
X726657Y247166D01*
X726627Y247131D01*
X726607Y247096D01*
X726582Y247061D01*
X726542Y246981D01*
X726497Y246861D01*
X726487Y246821D01*
X726477Y246776D01*
X726472Y246736D01*
X726462Y246691D01*
Y246521D01*
X726472Y246476D01*
X726477Y246436D01*
X726487Y246391D01*
X726497Y246351D01*
X726542Y246231D01*
X726582Y246151D01*
X726607Y246116D01*
X726627Y246081D01*
X726657Y246046D01*
X726682Y246011D01*
X726712Y245981D01*
Y243556D01*
X726722Y243431D01*
X726762Y243306D01*
X726822Y243196D01*
X726902Y243096D01*
X727002Y243016D01*
X727112Y242956D01*
X727237Y242916D01*
X727362Y242906D01*
X727487Y242916D01*
X727612Y242956D01*
X727722Y243016D01*
X727822Y243096D01*
X727902Y243196D01*
X727962Y243306D01*
X728002Y243431D01*
X728012Y243556D01*
Y245986D01*
X728042Y246016D01*
X728142Y246156D01*
X728162Y246196D01*
X728177Y246231D01*
X728197Y246271D01*
X728212Y246311D01*
X728222Y246351D01*
X728237Y246396D01*
X728242Y246436D01*
X728252Y246476D01*
X728257Y246521D01*
Y246561D01*
X728262Y246606D01*
X728257Y246651D01*
Y246691D01*
X728252Y246736D01*
X728242Y246776D01*
X728237Y246816D01*
X728222Y246861D01*
X728212Y246901D01*
X728197Y246941D01*
X728177Y246981D01*
X728162Y247016D01*
X728142Y247056D01*
X728042Y247196D01*
X728012Y247226D01*
Y249356D01*
X728002Y249481D01*
X727962Y249606D01*
X727902Y249716D01*
X727822Y249816D01*
X727722Y249896D01*
X727612Y249956D01*
X727487Y249996D01*
X727362Y250006D01*
G37*
G36*
G01X732087D02*
X731962Y249996D01*
X731837Y249956D01*
X731727Y249896D01*
X731627Y249816D01*
X731547Y249716D01*
X731487Y249606D01*
X731447Y249481D01*
X731437Y249356D01*
Y247231D01*
X731407Y247201D01*
X731382Y247166D01*
X731352Y247131D01*
X731332Y247096D01*
X731307Y247061D01*
X731267Y246981D01*
X731222Y246861D01*
X731212Y246821D01*
X731202Y246776D01*
X731197Y246736D01*
X731187Y246691D01*
Y246521D01*
X731197Y246476D01*
X731202Y246436D01*
X731212Y246391D01*
X731222Y246351D01*
X731267Y246231D01*
X731307Y246151D01*
X731332Y246116D01*
X731352Y246081D01*
X731382Y246046D01*
X731407Y246011D01*
X731437Y245981D01*
Y243556D01*
X731447Y243431D01*
X731487Y243306D01*
X731547Y243196D01*
X731627Y243096D01*
X731727Y243016D01*
X731837Y242956D01*
X731962Y242916D01*
X732087Y242906D01*
X732212Y242916D01*
X732337Y242956D01*
X732447Y243016D01*
X732547Y243096D01*
X732627Y243196D01*
X732687Y243306D01*
X732727Y243431D01*
X732737Y243556D01*
Y245986D01*
X732767Y246016D01*
X732867Y246156D01*
X732887Y246196D01*
X732902Y246231D01*
X732922Y246271D01*
X732937Y246311D01*
X732947Y246351D01*
X732962Y246396D01*
X732967Y246436D01*
X732977Y246476D01*
X732982Y246521D01*
Y246561D01*
X732987Y246606D01*
X732982Y246651D01*
Y246691D01*
X732977Y246736D01*
X732967Y246776D01*
X732962Y246816D01*
X732947Y246861D01*
X732937Y246901D01*
X732922Y246941D01*
X732902Y246981D01*
X732887Y247016D01*
X732867Y247056D01*
X732767Y247196D01*
X732737Y247226D01*
Y249356D01*
X732727Y249481D01*
X732687Y249606D01*
X732627Y249716D01*
X732547Y249816D01*
X732447Y249896D01*
X732337Y249956D01*
X732212Y249996D01*
X732087Y250006D01*
G37*
G36*
G01X736811D02*
X736686Y249996D01*
X736561Y249956D01*
X736451Y249896D01*
X736351Y249816D01*
X736271Y249716D01*
X736211Y249606D01*
X736171Y249481D01*
X736161Y249356D01*
Y247231D01*
X736131Y247201D01*
X736106Y247166D01*
X736076Y247131D01*
X736056Y247096D01*
X736031Y247061D01*
X735991Y246981D01*
X735946Y246861D01*
X735936Y246821D01*
X735926Y246776D01*
X735921Y246736D01*
X735911Y246691D01*
Y246521D01*
X735921Y246476D01*
X735926Y246436D01*
X735936Y246391D01*
X735946Y246351D01*
X735991Y246231D01*
X736031Y246151D01*
X736056Y246116D01*
X736076Y246081D01*
X736106Y246046D01*
X736131Y246011D01*
X736161Y245981D01*
Y243556D01*
X736171Y243431D01*
X736211Y243306D01*
X736271Y243196D01*
X736351Y243096D01*
X736451Y243016D01*
X736561Y242956D01*
X736686Y242916D01*
X736811Y242906D01*
X736936Y242916D01*
X737061Y242956D01*
X737171Y243016D01*
X737271Y243096D01*
X737351Y243196D01*
X737411Y243306D01*
X737451Y243431D01*
X737461Y243556D01*
Y245986D01*
X737491Y246016D01*
X737591Y246156D01*
X737611Y246196D01*
X737626Y246231D01*
X737646Y246271D01*
X737661Y246311D01*
X737671Y246351D01*
X737686Y246396D01*
X737691Y246436D01*
X737701Y246476D01*
X737706Y246521D01*
Y246561D01*
X737711Y246606D01*
X737706Y246651D01*
Y246691D01*
X737701Y246736D01*
X737691Y246776D01*
X737686Y246816D01*
X737671Y246861D01*
X737661Y246901D01*
X737646Y246941D01*
X737626Y246981D01*
X737611Y247016D01*
X737591Y247056D01*
X737491Y247196D01*
X737461Y247226D01*
Y249356D01*
X737451Y249481D01*
X737411Y249606D01*
X737351Y249716D01*
X737271Y249816D01*
X737171Y249896D01*
X737061Y249956D01*
X736936Y249996D01*
X736811Y250006D01*
G37*
G36*
G01X741536D02*
X741411Y249996D01*
X741286Y249956D01*
X741176Y249896D01*
X741076Y249816D01*
X740996Y249716D01*
X740936Y249606D01*
X740896Y249481D01*
X740886Y249356D01*
Y247231D01*
X740856Y247201D01*
X740831Y247166D01*
X740801Y247131D01*
X740781Y247096D01*
X740756Y247061D01*
X740716Y246981D01*
X740671Y246861D01*
X740661Y246821D01*
X740651Y246776D01*
X740646Y246736D01*
X740636Y246691D01*
Y246521D01*
X740646Y246476D01*
X740651Y246436D01*
X740661Y246391D01*
X740671Y246351D01*
X740716Y246231D01*
X740756Y246151D01*
X740781Y246116D01*
X740801Y246081D01*
X740831Y246046D01*
X740856Y246011D01*
X740886Y245981D01*
Y243556D01*
X740896Y243431D01*
X740936Y243306D01*
X740996Y243196D01*
X741076Y243096D01*
X741176Y243016D01*
X741286Y242956D01*
X741411Y242916D01*
X741536Y242906D01*
X741661Y242916D01*
X741786Y242956D01*
X741896Y243016D01*
X741996Y243096D01*
X742076Y243196D01*
X742136Y243306D01*
X742176Y243431D01*
X742186Y243556D01*
Y245986D01*
X742216Y246016D01*
X742316Y246156D01*
X742336Y246196D01*
X742351Y246231D01*
X742371Y246271D01*
X742386Y246311D01*
X742396Y246351D01*
X742411Y246396D01*
X742416Y246436D01*
X742426Y246476D01*
X742431Y246521D01*
Y246561D01*
X742436Y246606D01*
X742431Y246651D01*
Y246691D01*
X742426Y246736D01*
X742416Y246776D01*
X742411Y246816D01*
X742396Y246861D01*
X742386Y246901D01*
X742371Y246941D01*
X742351Y246981D01*
X742336Y247016D01*
X742316Y247056D01*
X742216Y247196D01*
X742186Y247226D01*
Y249356D01*
X742176Y249481D01*
X742136Y249606D01*
X742076Y249716D01*
X741996Y249816D01*
X741896Y249896D01*
X741786Y249956D01*
X741661Y249996D01*
X741536Y250006D01*
G37*
G36*
G01X746260D02*
X746135Y249996D01*
X746010Y249956D01*
X745900Y249896D01*
X745800Y249816D01*
X745720Y249716D01*
X745660Y249606D01*
X745620Y249481D01*
X745610Y249356D01*
Y247231D01*
X745580Y247201D01*
X745555Y247166D01*
X745525Y247131D01*
X745505Y247096D01*
X745480Y247061D01*
X745440Y246981D01*
X745395Y246861D01*
X745385Y246821D01*
X745375Y246776D01*
X745370Y246736D01*
X745360Y246691D01*
Y246521D01*
X745370Y246476D01*
X745375Y246436D01*
X745385Y246391D01*
X745395Y246351D01*
X745440Y246231D01*
X745480Y246151D01*
X745505Y246116D01*
X745525Y246081D01*
X745555Y246046D01*
X745580Y246011D01*
X745610Y245981D01*
Y243556D01*
X745620Y243431D01*
X745660Y243306D01*
X745720Y243196D01*
X745800Y243096D01*
X745900Y243016D01*
X746010Y242956D01*
X746135Y242916D01*
X746260Y242906D01*
X746385Y242916D01*
X746510Y242956D01*
X746620Y243016D01*
X746720Y243096D01*
X746800Y243196D01*
X746860Y243306D01*
X746900Y243431D01*
X746910Y243556D01*
Y245986D01*
X746940Y246016D01*
X747040Y246156D01*
X747060Y246196D01*
X747075Y246231D01*
X747095Y246271D01*
X747110Y246311D01*
X747120Y246351D01*
X747135Y246396D01*
X747140Y246436D01*
X747150Y246476D01*
X747155Y246521D01*
Y246561D01*
X747160Y246606D01*
X747155Y246651D01*
Y246691D01*
X747150Y246736D01*
X747140Y246776D01*
X747135Y246816D01*
X747120Y246861D01*
X747110Y246901D01*
X747095Y246941D01*
X747075Y246981D01*
X747060Y247016D01*
X747040Y247056D01*
X746940Y247196D01*
X746910Y247226D01*
Y249356D01*
X746900Y249481D01*
X746860Y249606D01*
X746800Y249716D01*
X746720Y249816D01*
X746620Y249896D01*
X746510Y249956D01*
X746385Y249996D01*
X746260Y250006D01*
G37*
G54D56*
X339200Y269500D03*
X349800D03*
G54D47*
X272079Y73795D03*
X274047D03*
X276016D03*
X277984D03*
Y84205D03*
X276016D03*
X274047D03*
X272079D03*
X279953Y73795D03*
X281921D03*
Y84205D03*
X279953D03*
G54D83*
X787246Y280709D03*
G54D29*
X69000Y225700D03*
X74000D03*
X69000Y230900D03*
X74000D03*
X156100Y181900D03*
Y187100D03*
X185000Y163400D03*
X174000Y163900D03*
X185000Y168600D03*
X174000Y169100D03*
X297000Y208600D03*
Y203400D03*
X326500Y244900D03*
Y250100D03*
X371500Y208100D03*
Y202900D03*
X414000Y72900D03*
Y78100D03*
X507000Y224600D03*
Y219400D03*
X596000Y236100D03*
Y230900D03*
X606000Y236100D03*
Y230900D03*
X628000Y236100D03*
Y230900D03*
X694000Y163900D03*
Y169100D03*
X742000Y67100D03*
Y61900D03*
X740000Y238600D03*
Y233400D03*
G54D38*
X169085Y183848D03*
Y201170D03*
X192007Y183848D03*
Y201170D03*
G54D66*
X449150Y143900D03*
X444350Y162800D03*
X467650D03*
X472450Y143900D03*
X780650Y195800D03*
X803950D03*
G36*
G01X502953Y250006D02*
X502828Y249996D01*
X502703Y249956D01*
X502593Y249896D01*
X502493Y249816D01*
X502413Y249716D01*
X502353Y249606D01*
X502313Y249481D01*
X502303Y249356D01*
Y248226D01*
X502273Y248196D01*
X502173Y248056D01*
X502153Y248016D01*
X502138Y247981D01*
X502118Y247941D01*
X502103Y247901D01*
X502093Y247861D01*
X502078Y247816D01*
X502073Y247776D01*
X502063Y247736D01*
X502058Y247691D01*
Y247651D01*
X502053Y247606D01*
X502058Y247561D01*
Y247521D01*
X502063Y247476D01*
X502073Y247436D01*
X502078Y247396D01*
X502093Y247351D01*
X502103Y247311D01*
X502118Y247271D01*
X502138Y247231D01*
X502153Y247196D01*
X502173Y247156D01*
X502273Y247016D01*
X502303Y246986D01*
Y243556D01*
X502313Y243431D01*
X502353Y243306D01*
X502413Y243196D01*
X502493Y243096D01*
X502593Y243016D01*
X502703Y242956D01*
X502828Y242916D01*
X502953Y242906D01*
X503078Y242916D01*
X503203Y242956D01*
X503313Y243016D01*
X503413Y243096D01*
X503493Y243196D01*
X503553Y243306D01*
X503593Y243431D01*
X503603Y243556D01*
Y246986D01*
X503633Y247016D01*
X503733Y247156D01*
X503753Y247196D01*
X503768Y247231D01*
X503788Y247271D01*
X503803Y247311D01*
X503813Y247351D01*
X503828Y247396D01*
X503833Y247436D01*
X503843Y247476D01*
X503848Y247521D01*
Y247561D01*
X503853Y247606D01*
X503848Y247651D01*
Y247691D01*
X503843Y247736D01*
X503833Y247776D01*
X503828Y247816D01*
X503813Y247861D01*
X503803Y247901D01*
X503788Y247941D01*
X503768Y247981D01*
X503753Y248016D01*
X503733Y248056D01*
X503633Y248196D01*
X503603Y248226D01*
Y249356D01*
X503593Y249481D01*
X503553Y249606D01*
X503493Y249716D01*
X503413Y249816D01*
X503313Y249896D01*
X503203Y249956D01*
X503078Y249996D01*
X502953Y250006D01*
G37*
G36*
G01X507677D02*
X507552Y249996D01*
X507427Y249956D01*
X507317Y249896D01*
X507217Y249816D01*
X507137Y249716D01*
X507077Y249606D01*
X507037Y249481D01*
X507027Y249356D01*
Y248226D01*
X506997Y248196D01*
X506897Y248056D01*
X506877Y248016D01*
X506862Y247981D01*
X506842Y247941D01*
X506827Y247901D01*
X506817Y247861D01*
X506802Y247816D01*
X506797Y247776D01*
X506787Y247736D01*
X506782Y247691D01*
Y247651D01*
X506777Y247606D01*
X506782Y247561D01*
Y247521D01*
X506787Y247476D01*
X506797Y247436D01*
X506802Y247396D01*
X506817Y247351D01*
X506827Y247311D01*
X506842Y247271D01*
X506862Y247231D01*
X506877Y247196D01*
X506897Y247156D01*
X506997Y247016D01*
X507027Y246986D01*
Y243556D01*
X507037Y243431D01*
X507077Y243306D01*
X507137Y243196D01*
X507217Y243096D01*
X507317Y243016D01*
X507427Y242956D01*
X507552Y242916D01*
X507677Y242906D01*
X507802Y242916D01*
X507927Y242956D01*
X508037Y243016D01*
X508137Y243096D01*
X508217Y243196D01*
X508277Y243306D01*
X508317Y243431D01*
X508327Y243556D01*
Y246986D01*
X508357Y247016D01*
X508457Y247156D01*
X508477Y247196D01*
X508492Y247231D01*
X508512Y247271D01*
X508527Y247311D01*
X508537Y247351D01*
X508552Y247396D01*
X508557Y247436D01*
X508567Y247476D01*
X508572Y247521D01*
Y247561D01*
X508577Y247606D01*
X508572Y247651D01*
Y247691D01*
X508567Y247736D01*
X508557Y247776D01*
X508552Y247816D01*
X508537Y247861D01*
X508527Y247901D01*
X508512Y247941D01*
X508492Y247981D01*
X508477Y248016D01*
X508457Y248056D01*
X508357Y248196D01*
X508327Y248226D01*
Y249356D01*
X508317Y249481D01*
X508277Y249606D01*
X508217Y249716D01*
X508137Y249816D01*
X508037Y249896D01*
X507927Y249956D01*
X507802Y249996D01*
X507677Y250006D01*
G37*
G36*
G01X512402D02*
X512277Y249996D01*
X512152Y249956D01*
X512042Y249896D01*
X511942Y249816D01*
X511862Y249716D01*
X511802Y249606D01*
X511762Y249481D01*
X511752Y249356D01*
Y248226D01*
X511722Y248196D01*
X511622Y248056D01*
X511602Y248016D01*
X511587Y247981D01*
X511567Y247941D01*
X511552Y247901D01*
X511542Y247861D01*
X511527Y247816D01*
X511522Y247776D01*
X511512Y247736D01*
X511507Y247691D01*
Y247651D01*
X511502Y247606D01*
X511507Y247561D01*
Y247521D01*
X511512Y247476D01*
X511522Y247436D01*
X511527Y247396D01*
X511542Y247351D01*
X511552Y247311D01*
X511567Y247271D01*
X511587Y247231D01*
X511602Y247196D01*
X511622Y247156D01*
X511722Y247016D01*
X511752Y246986D01*
Y243556D01*
X511762Y243431D01*
X511802Y243306D01*
X511862Y243196D01*
X511942Y243096D01*
X512042Y243016D01*
X512152Y242956D01*
X512277Y242916D01*
X512402Y242906D01*
X512527Y242916D01*
X512652Y242956D01*
X512762Y243016D01*
X512862Y243096D01*
X512942Y243196D01*
X513002Y243306D01*
X513042Y243431D01*
X513052Y243556D01*
Y246986D01*
X513082Y247016D01*
X513182Y247156D01*
X513202Y247196D01*
X513217Y247231D01*
X513237Y247271D01*
X513252Y247311D01*
X513262Y247351D01*
X513277Y247396D01*
X513282Y247436D01*
X513292Y247476D01*
X513297Y247521D01*
Y247561D01*
X513302Y247606D01*
X513297Y247651D01*
Y247691D01*
X513292Y247736D01*
X513282Y247776D01*
X513277Y247816D01*
X513262Y247861D01*
X513252Y247901D01*
X513237Y247941D01*
X513217Y247981D01*
X513202Y248016D01*
X513182Y248056D01*
X513082Y248196D01*
X513052Y248226D01*
Y249356D01*
X513042Y249481D01*
X513002Y249606D01*
X512942Y249716D01*
X512862Y249816D01*
X512762Y249896D01*
X512652Y249956D01*
X512527Y249996D01*
X512402Y250006D01*
G37*
G36*
G01X517126D02*
X517001Y249996D01*
X516876Y249956D01*
X516766Y249896D01*
X516666Y249816D01*
X516586Y249716D01*
X516526Y249606D01*
X516486Y249481D01*
X516476Y249356D01*
Y248226D01*
X516446Y248196D01*
X516346Y248056D01*
X516326Y248016D01*
X516311Y247981D01*
X516291Y247941D01*
X516276Y247901D01*
X516266Y247861D01*
X516251Y247816D01*
X516246Y247776D01*
X516236Y247736D01*
X516231Y247691D01*
Y247651D01*
X516226Y247606D01*
X516231Y247561D01*
Y247521D01*
X516236Y247476D01*
X516246Y247436D01*
X516251Y247396D01*
X516266Y247351D01*
X516276Y247311D01*
X516291Y247271D01*
X516311Y247231D01*
X516326Y247196D01*
X516346Y247156D01*
X516446Y247016D01*
X516476Y246986D01*
Y243556D01*
X516486Y243431D01*
X516526Y243306D01*
X516586Y243196D01*
X516666Y243096D01*
X516766Y243016D01*
X516876Y242956D01*
X517001Y242916D01*
X517126Y242906D01*
X517251Y242916D01*
X517376Y242956D01*
X517486Y243016D01*
X517586Y243096D01*
X517666Y243196D01*
X517726Y243306D01*
X517766Y243431D01*
X517776Y243556D01*
Y246986D01*
X517806Y247016D01*
X517906Y247156D01*
X517926Y247196D01*
X517941Y247231D01*
X517961Y247271D01*
X517976Y247311D01*
X517986Y247351D01*
X518001Y247396D01*
X518006Y247436D01*
X518016Y247476D01*
X518021Y247521D01*
Y247561D01*
X518026Y247606D01*
X518021Y247651D01*
Y247691D01*
X518016Y247736D01*
X518006Y247776D01*
X518001Y247816D01*
X517986Y247861D01*
X517976Y247901D01*
X517961Y247941D01*
X517941Y247981D01*
X517926Y248016D01*
X517906Y248056D01*
X517806Y248196D01*
X517776Y248226D01*
Y249356D01*
X517766Y249481D01*
X517726Y249606D01*
X517666Y249716D01*
X517586Y249816D01*
X517486Y249896D01*
X517376Y249956D01*
X517251Y249996D01*
X517126Y250006D01*
G37*
G36*
G01X521851D02*
X521726Y249996D01*
X521601Y249956D01*
X521491Y249896D01*
X521391Y249816D01*
X521311Y249716D01*
X521251Y249606D01*
X521211Y249481D01*
X521201Y249356D01*
Y248226D01*
X521171Y248196D01*
X521071Y248056D01*
X521051Y248016D01*
X521036Y247981D01*
X521016Y247941D01*
X521001Y247901D01*
X520991Y247861D01*
X520976Y247816D01*
X520971Y247776D01*
X520961Y247736D01*
X520956Y247691D01*
Y247651D01*
X520951Y247606D01*
X520956Y247561D01*
Y247521D01*
X520961Y247476D01*
X520971Y247436D01*
X520976Y247396D01*
X520991Y247351D01*
X521001Y247311D01*
X521016Y247271D01*
X521036Y247231D01*
X521051Y247196D01*
X521071Y247156D01*
X521171Y247016D01*
X521201Y246986D01*
Y243556D01*
X521211Y243431D01*
X521251Y243306D01*
X521311Y243196D01*
X521391Y243096D01*
X521491Y243016D01*
X521601Y242956D01*
X521726Y242916D01*
X521851Y242906D01*
X521976Y242916D01*
X522101Y242956D01*
X522211Y243016D01*
X522311Y243096D01*
X522391Y243196D01*
X522451Y243306D01*
X522491Y243431D01*
X522501Y243556D01*
Y246986D01*
X522531Y247016D01*
X522631Y247156D01*
X522651Y247196D01*
X522666Y247231D01*
X522686Y247271D01*
X522701Y247311D01*
X522711Y247351D01*
X522726Y247396D01*
X522731Y247436D01*
X522741Y247476D01*
X522746Y247521D01*
Y247561D01*
X522751Y247606D01*
X522746Y247651D01*
Y247691D01*
X522741Y247736D01*
X522731Y247776D01*
X522726Y247816D01*
X522711Y247861D01*
X522701Y247901D01*
X522686Y247941D01*
X522666Y247981D01*
X522651Y248016D01*
X522631Y248056D01*
X522531Y248196D01*
X522501Y248226D01*
Y249356D01*
X522491Y249481D01*
X522451Y249606D01*
X522391Y249716D01*
X522311Y249816D01*
X522211Y249896D01*
X522101Y249956D01*
X521976Y249996D01*
X521851Y250006D01*
G37*
G36*
G01X526575D02*
X526450Y249996D01*
X526325Y249956D01*
X526215Y249896D01*
X526115Y249816D01*
X526035Y249716D01*
X525975Y249606D01*
X525935Y249481D01*
X525925Y249356D01*
Y248226D01*
X525895Y248196D01*
X525795Y248056D01*
X525775Y248016D01*
X525760Y247981D01*
X525740Y247941D01*
X525725Y247901D01*
X525715Y247861D01*
X525700Y247816D01*
X525695Y247776D01*
X525685Y247736D01*
X525680Y247691D01*
Y247651D01*
X525675Y247606D01*
X525680Y247561D01*
Y247521D01*
X525685Y247476D01*
X525695Y247436D01*
X525700Y247396D01*
X525715Y247351D01*
X525725Y247311D01*
X525740Y247271D01*
X525760Y247231D01*
X525775Y247196D01*
X525795Y247156D01*
X525895Y247016D01*
X525925Y246986D01*
Y243556D01*
X525935Y243431D01*
X525975Y243306D01*
X526035Y243196D01*
X526115Y243096D01*
X526215Y243016D01*
X526325Y242956D01*
X526450Y242916D01*
X526575Y242906D01*
X526700Y242916D01*
X526825Y242956D01*
X526935Y243016D01*
X527035Y243096D01*
X527115Y243196D01*
X527175Y243306D01*
X527215Y243431D01*
X527225Y243556D01*
Y246986D01*
X527255Y247016D01*
X527355Y247156D01*
X527375Y247196D01*
X527390Y247231D01*
X527410Y247271D01*
X527425Y247311D01*
X527435Y247351D01*
X527450Y247396D01*
X527455Y247436D01*
X527465Y247476D01*
X527470Y247521D01*
Y247561D01*
X527475Y247606D01*
X527470Y247651D01*
Y247691D01*
X527465Y247736D01*
X527455Y247776D01*
X527450Y247816D01*
X527435Y247861D01*
X527425Y247901D01*
X527410Y247941D01*
X527390Y247981D01*
X527375Y248016D01*
X527355Y248056D01*
X527255Y248196D01*
X527225Y248226D01*
Y249356D01*
X527215Y249481D01*
X527175Y249606D01*
X527115Y249716D01*
X527035Y249816D01*
X526935Y249896D01*
X526825Y249956D01*
X526700Y249996D01*
X526575Y250006D01*
G37*
G36*
G01X531299D02*
X531174Y249996D01*
X531049Y249956D01*
X530939Y249896D01*
X530839Y249816D01*
X530759Y249716D01*
X530699Y249606D01*
X530659Y249481D01*
X530649Y249356D01*
Y248226D01*
X530619Y248196D01*
X530519Y248056D01*
X530499Y248016D01*
X530484Y247981D01*
X530464Y247941D01*
X530449Y247901D01*
X530439Y247861D01*
X530424Y247816D01*
X530419Y247776D01*
X530409Y247736D01*
X530404Y247691D01*
Y247651D01*
X530399Y247606D01*
X530404Y247561D01*
Y247521D01*
X530409Y247476D01*
X530419Y247436D01*
X530424Y247396D01*
X530439Y247351D01*
X530449Y247311D01*
X530464Y247271D01*
X530484Y247231D01*
X530499Y247196D01*
X530519Y247156D01*
X530619Y247016D01*
X530649Y246986D01*
Y243556D01*
X530659Y243431D01*
X530699Y243306D01*
X530759Y243196D01*
X530839Y243096D01*
X530939Y243016D01*
X531049Y242956D01*
X531174Y242916D01*
X531299Y242906D01*
X531424Y242916D01*
X531549Y242956D01*
X531659Y243016D01*
X531759Y243096D01*
X531839Y243196D01*
X531899Y243306D01*
X531939Y243431D01*
X531949Y243556D01*
Y246986D01*
X531979Y247016D01*
X532079Y247156D01*
X532099Y247196D01*
X532114Y247231D01*
X532134Y247271D01*
X532149Y247311D01*
X532159Y247351D01*
X532174Y247396D01*
X532179Y247436D01*
X532189Y247476D01*
X532194Y247521D01*
Y247561D01*
X532199Y247606D01*
X532194Y247651D01*
Y247691D01*
X532189Y247736D01*
X532179Y247776D01*
X532174Y247816D01*
X532159Y247861D01*
X532149Y247901D01*
X532134Y247941D01*
X532114Y247981D01*
X532099Y248016D01*
X532079Y248056D01*
X531979Y248196D01*
X531949Y248226D01*
Y249356D01*
X531939Y249481D01*
X531899Y249606D01*
X531839Y249716D01*
X531759Y249816D01*
X531659Y249896D01*
X531549Y249956D01*
X531424Y249996D01*
X531299Y250006D01*
G37*
G36*
G01X536024D02*
X535899Y249996D01*
X535774Y249956D01*
X535664Y249896D01*
X535564Y249816D01*
X535484Y249716D01*
X535424Y249606D01*
X535384Y249481D01*
X535374Y249356D01*
Y248226D01*
X535344Y248196D01*
X535244Y248056D01*
X535224Y248016D01*
X535209Y247981D01*
X535189Y247941D01*
X535174Y247901D01*
X535164Y247861D01*
X535149Y247816D01*
X535144Y247776D01*
X535134Y247736D01*
X535129Y247691D01*
Y247651D01*
X535124Y247606D01*
X535129Y247561D01*
Y247521D01*
X535134Y247476D01*
X535144Y247436D01*
X535149Y247396D01*
X535164Y247351D01*
X535174Y247311D01*
X535189Y247271D01*
X535209Y247231D01*
X535224Y247196D01*
X535244Y247156D01*
X535344Y247016D01*
X535374Y246986D01*
Y243556D01*
X535384Y243431D01*
X535424Y243306D01*
X535484Y243196D01*
X535564Y243096D01*
X535664Y243016D01*
X535774Y242956D01*
X535899Y242916D01*
X536024Y242906D01*
X536149Y242916D01*
X536274Y242956D01*
X536384Y243016D01*
X536484Y243096D01*
X536564Y243196D01*
X536624Y243306D01*
X536664Y243431D01*
X536674Y243556D01*
Y246986D01*
X536704Y247016D01*
X536804Y247156D01*
X536824Y247196D01*
X536839Y247231D01*
X536859Y247271D01*
X536874Y247311D01*
X536884Y247351D01*
X536899Y247396D01*
X536904Y247436D01*
X536914Y247476D01*
X536919Y247521D01*
Y247561D01*
X536924Y247606D01*
X536919Y247651D01*
Y247691D01*
X536914Y247736D01*
X536904Y247776D01*
X536899Y247816D01*
X536884Y247861D01*
X536874Y247901D01*
X536859Y247941D01*
X536839Y247981D01*
X536824Y248016D01*
X536804Y248056D01*
X536704Y248196D01*
X536674Y248226D01*
Y249356D01*
X536664Y249481D01*
X536624Y249606D01*
X536564Y249716D01*
X536484Y249816D01*
X536384Y249896D01*
X536274Y249956D01*
X536149Y249996D01*
X536024Y250006D01*
G37*
G36*
G01X540748D02*
X540623Y249996D01*
X540498Y249956D01*
X540388Y249896D01*
X540288Y249816D01*
X540208Y249716D01*
X540148Y249606D01*
X540108Y249481D01*
X540098Y249356D01*
Y248226D01*
X540068Y248196D01*
X539968Y248056D01*
X539948Y248016D01*
X539933Y247981D01*
X539913Y247941D01*
X539898Y247901D01*
X539888Y247861D01*
X539873Y247816D01*
X539868Y247776D01*
X539858Y247736D01*
X539853Y247691D01*
Y247651D01*
X539848Y247606D01*
X539853Y247561D01*
Y247521D01*
X539858Y247476D01*
X539868Y247436D01*
X539873Y247396D01*
X539888Y247351D01*
X539898Y247311D01*
X539913Y247271D01*
X539933Y247231D01*
X539948Y247196D01*
X539968Y247156D01*
X540068Y247016D01*
X540098Y246986D01*
Y243556D01*
X540108Y243431D01*
X540148Y243306D01*
X540208Y243196D01*
X540288Y243096D01*
X540388Y243016D01*
X540498Y242956D01*
X540623Y242916D01*
X540748Y242906D01*
X540873Y242916D01*
X540998Y242956D01*
X541108Y243016D01*
X541208Y243096D01*
X541288Y243196D01*
X541348Y243306D01*
X541388Y243431D01*
X541398Y243556D01*
Y246986D01*
X541428Y247016D01*
X541528Y247156D01*
X541548Y247196D01*
X541563Y247231D01*
X541583Y247271D01*
X541598Y247311D01*
X541608Y247351D01*
X541623Y247396D01*
X541628Y247436D01*
X541638Y247476D01*
X541643Y247521D01*
Y247561D01*
X541648Y247606D01*
X541643Y247651D01*
Y247691D01*
X541638Y247736D01*
X541628Y247776D01*
X541623Y247816D01*
X541608Y247861D01*
X541598Y247901D01*
X541583Y247941D01*
X541563Y247981D01*
X541548Y248016D01*
X541528Y248056D01*
X541428Y248196D01*
X541398Y248226D01*
Y249356D01*
X541388Y249481D01*
X541348Y249606D01*
X541288Y249716D01*
X541208Y249816D01*
X541108Y249896D01*
X540998Y249956D01*
X540873Y249996D01*
X540748Y250006D01*
G37*
G36*
G01X545473D02*
X545348Y249996D01*
X545223Y249956D01*
X545113Y249896D01*
X545013Y249816D01*
X544933Y249716D01*
X544873Y249606D01*
X544833Y249481D01*
X544823Y249356D01*
Y248226D01*
X544793Y248196D01*
X544693Y248056D01*
X544673Y248016D01*
X544658Y247981D01*
X544638Y247941D01*
X544623Y247901D01*
X544613Y247861D01*
X544598Y247816D01*
X544593Y247776D01*
X544583Y247736D01*
X544578Y247691D01*
Y247651D01*
X544573Y247606D01*
X544578Y247561D01*
Y247521D01*
X544583Y247476D01*
X544593Y247436D01*
X544598Y247396D01*
X544613Y247351D01*
X544623Y247311D01*
X544638Y247271D01*
X544658Y247231D01*
X544673Y247196D01*
X544693Y247156D01*
X544793Y247016D01*
X544823Y246986D01*
Y243556D01*
X544833Y243431D01*
X544873Y243306D01*
X544933Y243196D01*
X545013Y243096D01*
X545113Y243016D01*
X545223Y242956D01*
X545348Y242916D01*
X545473Y242906D01*
X545598Y242916D01*
X545723Y242956D01*
X545833Y243016D01*
X545933Y243096D01*
X546013Y243196D01*
X546073Y243306D01*
X546113Y243431D01*
X546123Y243556D01*
Y246986D01*
X546153Y247016D01*
X546253Y247156D01*
X546273Y247196D01*
X546288Y247231D01*
X546308Y247271D01*
X546323Y247311D01*
X546333Y247351D01*
X546348Y247396D01*
X546353Y247436D01*
X546363Y247476D01*
X546368Y247521D01*
Y247561D01*
X546373Y247606D01*
X546368Y247651D01*
Y247691D01*
X546363Y247736D01*
X546353Y247776D01*
X546348Y247816D01*
X546333Y247861D01*
X546323Y247901D01*
X546308Y247941D01*
X546288Y247981D01*
X546273Y248016D01*
X546253Y248056D01*
X546153Y248196D01*
X546123Y248226D01*
Y249356D01*
X546113Y249481D01*
X546073Y249606D01*
X546013Y249716D01*
X545933Y249816D01*
X545833Y249896D01*
X545723Y249956D01*
X545598Y249996D01*
X545473Y250006D01*
G37*
G36*
G01X550197D02*
X550072Y249996D01*
X549947Y249956D01*
X549837Y249896D01*
X549737Y249816D01*
X549657Y249716D01*
X549597Y249606D01*
X549557Y249481D01*
X549547Y249356D01*
Y248226D01*
X549517Y248196D01*
X549417Y248056D01*
X549397Y248016D01*
X549382Y247981D01*
X549362Y247941D01*
X549347Y247901D01*
X549337Y247861D01*
X549322Y247816D01*
X549317Y247776D01*
X549307Y247736D01*
X549302Y247691D01*
Y247651D01*
X549297Y247606D01*
X549302Y247561D01*
Y247521D01*
X549307Y247476D01*
X549317Y247436D01*
X549322Y247396D01*
X549337Y247351D01*
X549347Y247311D01*
X549362Y247271D01*
X549382Y247231D01*
X549397Y247196D01*
X549417Y247156D01*
X549517Y247016D01*
X549547Y246986D01*
Y243556D01*
X549557Y243431D01*
X549597Y243306D01*
X549657Y243196D01*
X549737Y243096D01*
X549837Y243016D01*
X549947Y242956D01*
X550072Y242916D01*
X550197Y242906D01*
X550322Y242916D01*
X550447Y242956D01*
X550557Y243016D01*
X550657Y243096D01*
X550737Y243196D01*
X550797Y243306D01*
X550837Y243431D01*
X550847Y243556D01*
Y246986D01*
X550877Y247016D01*
X550977Y247156D01*
X550997Y247196D01*
X551012Y247231D01*
X551032Y247271D01*
X551047Y247311D01*
X551057Y247351D01*
X551072Y247396D01*
X551077Y247436D01*
X551087Y247476D01*
X551092Y247521D01*
Y247561D01*
X551097Y247606D01*
X551092Y247651D01*
Y247691D01*
X551087Y247736D01*
X551077Y247776D01*
X551072Y247816D01*
X551057Y247861D01*
X551047Y247901D01*
X551032Y247941D01*
X551012Y247981D01*
X550997Y248016D01*
X550977Y248056D01*
X550877Y248196D01*
X550847Y248226D01*
Y249356D01*
X550837Y249481D01*
X550797Y249606D01*
X550737Y249716D01*
X550657Y249816D01*
X550557Y249896D01*
X550447Y249956D01*
X550322Y249996D01*
X550197Y250006D01*
G37*
G36*
G01X554922D02*
X554797Y249996D01*
X554672Y249956D01*
X554562Y249896D01*
X554462Y249816D01*
X554382Y249716D01*
X554322Y249606D01*
X554282Y249481D01*
X554272Y249356D01*
Y248226D01*
X554242Y248196D01*
X554142Y248056D01*
X554122Y248016D01*
X554107Y247981D01*
X554087Y247941D01*
X554072Y247901D01*
X554062Y247861D01*
X554047Y247816D01*
X554042Y247776D01*
X554032Y247736D01*
X554027Y247691D01*
Y247651D01*
X554022Y247606D01*
X554027Y247561D01*
Y247521D01*
X554032Y247476D01*
X554042Y247436D01*
X554047Y247396D01*
X554062Y247351D01*
X554072Y247311D01*
X554087Y247271D01*
X554107Y247231D01*
X554122Y247196D01*
X554142Y247156D01*
X554242Y247016D01*
X554272Y246986D01*
Y243556D01*
X554282Y243431D01*
X554322Y243306D01*
X554382Y243196D01*
X554462Y243096D01*
X554562Y243016D01*
X554672Y242956D01*
X554797Y242916D01*
X554922Y242906D01*
X555047Y242916D01*
X555172Y242956D01*
X555282Y243016D01*
X555382Y243096D01*
X555462Y243196D01*
X555522Y243306D01*
X555562Y243431D01*
X555572Y243556D01*
Y246986D01*
X555602Y247016D01*
X555702Y247156D01*
X555722Y247196D01*
X555737Y247231D01*
X555757Y247271D01*
X555772Y247311D01*
X555782Y247351D01*
X555797Y247396D01*
X555802Y247436D01*
X555812Y247476D01*
X555817Y247521D01*
Y247561D01*
X555822Y247606D01*
X555817Y247651D01*
Y247691D01*
X555812Y247736D01*
X555802Y247776D01*
X555797Y247816D01*
X555782Y247861D01*
X555772Y247901D01*
X555757Y247941D01*
X555737Y247981D01*
X555722Y248016D01*
X555702Y248056D01*
X555602Y248196D01*
X555572Y248226D01*
Y249356D01*
X555562Y249481D01*
X555522Y249606D01*
X555462Y249716D01*
X555382Y249816D01*
X555282Y249896D01*
X555172Y249956D01*
X555047Y249996D01*
X554922Y250006D01*
G37*
G36*
G01X559646D02*
X559521Y249996D01*
X559396Y249956D01*
X559286Y249896D01*
X559186Y249816D01*
X559106Y249716D01*
X559046Y249606D01*
X559006Y249481D01*
X558996Y249356D01*
Y248226D01*
X558966Y248196D01*
X558866Y248056D01*
X558846Y248016D01*
X558831Y247981D01*
X558811Y247941D01*
X558796Y247901D01*
X558786Y247861D01*
X558771Y247816D01*
X558766Y247776D01*
X558756Y247736D01*
X558751Y247691D01*
Y247651D01*
X558746Y247606D01*
X558751Y247561D01*
Y247521D01*
X558756Y247476D01*
X558766Y247436D01*
X558771Y247396D01*
X558786Y247351D01*
X558796Y247311D01*
X558811Y247271D01*
X558831Y247231D01*
X558846Y247196D01*
X558866Y247156D01*
X558966Y247016D01*
X558996Y246986D01*
Y243556D01*
X559006Y243431D01*
X559046Y243306D01*
X559106Y243196D01*
X559186Y243096D01*
X559286Y243016D01*
X559396Y242956D01*
X559521Y242916D01*
X559646Y242906D01*
X559771Y242916D01*
X559896Y242956D01*
X560006Y243016D01*
X560106Y243096D01*
X560186Y243196D01*
X560246Y243306D01*
X560286Y243431D01*
X560296Y243556D01*
Y246986D01*
X560326Y247016D01*
X560426Y247156D01*
X560446Y247196D01*
X560461Y247231D01*
X560481Y247271D01*
X560496Y247311D01*
X560506Y247351D01*
X560521Y247396D01*
X560526Y247436D01*
X560536Y247476D01*
X560541Y247521D01*
Y247561D01*
X560546Y247606D01*
X560541Y247651D01*
Y247691D01*
X560536Y247736D01*
X560526Y247776D01*
X560521Y247816D01*
X560506Y247861D01*
X560496Y247901D01*
X560481Y247941D01*
X560461Y247981D01*
X560446Y248016D01*
X560426Y248056D01*
X560326Y248196D01*
X560296Y248226D01*
Y249356D01*
X560286Y249481D01*
X560246Y249606D01*
X560186Y249716D01*
X560106Y249816D01*
X560006Y249896D01*
X559896Y249956D01*
X559771Y249996D01*
X559646Y250006D01*
G37*
G36*
G01X564370D02*
X564245Y249996D01*
X564120Y249956D01*
X564010Y249896D01*
X563910Y249816D01*
X563830Y249716D01*
X563770Y249606D01*
X563730Y249481D01*
X563720Y249356D01*
Y248226D01*
X563690Y248196D01*
X563590Y248056D01*
X563570Y248016D01*
X563555Y247981D01*
X563535Y247941D01*
X563520Y247901D01*
X563510Y247861D01*
X563495Y247816D01*
X563490Y247776D01*
X563480Y247736D01*
X563475Y247691D01*
Y247651D01*
X563470Y247606D01*
X563475Y247561D01*
Y247521D01*
X563480Y247476D01*
X563490Y247436D01*
X563495Y247396D01*
X563510Y247351D01*
X563520Y247311D01*
X563535Y247271D01*
X563555Y247231D01*
X563570Y247196D01*
X563590Y247156D01*
X563690Y247016D01*
X563720Y246986D01*
Y243556D01*
X563730Y243431D01*
X563770Y243306D01*
X563830Y243196D01*
X563910Y243096D01*
X564010Y243016D01*
X564120Y242956D01*
X564245Y242916D01*
X564370Y242906D01*
X564495Y242916D01*
X564620Y242956D01*
X564730Y243016D01*
X564830Y243096D01*
X564910Y243196D01*
X564970Y243306D01*
X565010Y243431D01*
X565020Y243556D01*
Y246986D01*
X565050Y247016D01*
X565150Y247156D01*
X565170Y247196D01*
X565185Y247231D01*
X565205Y247271D01*
X565220Y247311D01*
X565230Y247351D01*
X565245Y247396D01*
X565250Y247436D01*
X565260Y247476D01*
X565265Y247521D01*
Y247561D01*
X565270Y247606D01*
X565265Y247651D01*
Y247691D01*
X565260Y247736D01*
X565250Y247776D01*
X565245Y247816D01*
X565230Y247861D01*
X565220Y247901D01*
X565205Y247941D01*
X565185Y247981D01*
X565170Y248016D01*
X565150Y248056D01*
X565050Y248196D01*
X565020Y248226D01*
Y249356D01*
X565010Y249481D01*
X564970Y249606D01*
X564910Y249716D01*
X564830Y249816D01*
X564730Y249896D01*
X564620Y249956D01*
X564495Y249996D01*
X564370Y250006D01*
G37*
G36*
G01X569095D02*
X568970Y249996D01*
X568845Y249956D01*
X568735Y249896D01*
X568635Y249816D01*
X568555Y249716D01*
X568495Y249606D01*
X568455Y249481D01*
X568445Y249356D01*
Y248226D01*
X568415Y248196D01*
X568315Y248056D01*
X568295Y248016D01*
X568280Y247981D01*
X568260Y247941D01*
X568245Y247901D01*
X568235Y247861D01*
X568220Y247816D01*
X568215Y247776D01*
X568205Y247736D01*
X568200Y247691D01*
Y247651D01*
X568195Y247606D01*
X568200Y247561D01*
Y247521D01*
X568205Y247476D01*
X568215Y247436D01*
X568220Y247396D01*
X568235Y247351D01*
X568245Y247311D01*
X568260Y247271D01*
X568280Y247231D01*
X568295Y247196D01*
X568315Y247156D01*
X568415Y247016D01*
X568445Y246986D01*
Y243556D01*
X568455Y243431D01*
X568495Y243306D01*
X568555Y243196D01*
X568635Y243096D01*
X568735Y243016D01*
X568845Y242956D01*
X568970Y242916D01*
X569095Y242906D01*
X569220Y242916D01*
X569345Y242956D01*
X569455Y243016D01*
X569555Y243096D01*
X569635Y243196D01*
X569695Y243306D01*
X569735Y243431D01*
X569745Y243556D01*
Y246986D01*
X569775Y247016D01*
X569875Y247156D01*
X569895Y247196D01*
X569910Y247231D01*
X569930Y247271D01*
X569945Y247311D01*
X569955Y247351D01*
X569970Y247396D01*
X569975Y247436D01*
X569985Y247476D01*
X569990Y247521D01*
Y247561D01*
X569995Y247606D01*
X569990Y247651D01*
Y247691D01*
X569985Y247736D01*
X569975Y247776D01*
X569970Y247816D01*
X569955Y247861D01*
X569945Y247901D01*
X569930Y247941D01*
X569910Y247981D01*
X569895Y248016D01*
X569875Y248056D01*
X569775Y248196D01*
X569745Y248226D01*
Y249356D01*
X569735Y249481D01*
X569695Y249606D01*
X569635Y249716D01*
X569555Y249816D01*
X569455Y249896D01*
X569345Y249956D01*
X569220Y249996D01*
X569095Y250006D01*
G37*
G36*
G01X573819D02*
X573694Y249996D01*
X573569Y249956D01*
X573459Y249896D01*
X573359Y249816D01*
X573279Y249716D01*
X573219Y249606D01*
X573179Y249481D01*
X573169Y249356D01*
Y248226D01*
X573139Y248196D01*
X573039Y248056D01*
X573019Y248016D01*
X573004Y247981D01*
X572984Y247941D01*
X572969Y247901D01*
X572959Y247861D01*
X572944Y247816D01*
X572939Y247776D01*
X572929Y247736D01*
X572924Y247691D01*
Y247651D01*
X572919Y247606D01*
X572924Y247561D01*
Y247521D01*
X572929Y247476D01*
X572939Y247436D01*
X572944Y247396D01*
X572959Y247351D01*
X572969Y247311D01*
X572984Y247271D01*
X573004Y247231D01*
X573019Y247196D01*
X573039Y247156D01*
X573139Y247016D01*
X573169Y246986D01*
Y243556D01*
X573179Y243431D01*
X573219Y243306D01*
X573279Y243196D01*
X573359Y243096D01*
X573459Y243016D01*
X573569Y242956D01*
X573694Y242916D01*
X573819Y242906D01*
X573944Y242916D01*
X574069Y242956D01*
X574179Y243016D01*
X574279Y243096D01*
X574359Y243196D01*
X574419Y243306D01*
X574459Y243431D01*
X574469Y243556D01*
Y246986D01*
X574499Y247016D01*
X574599Y247156D01*
X574619Y247196D01*
X574634Y247231D01*
X574654Y247271D01*
X574669Y247311D01*
X574679Y247351D01*
X574694Y247396D01*
X574699Y247436D01*
X574709Y247476D01*
X574714Y247521D01*
Y247561D01*
X574719Y247606D01*
X574714Y247651D01*
Y247691D01*
X574709Y247736D01*
X574699Y247776D01*
X574694Y247816D01*
X574679Y247861D01*
X574669Y247901D01*
X574654Y247941D01*
X574634Y247981D01*
X574619Y248016D01*
X574599Y248056D01*
X574499Y248196D01*
X574469Y248226D01*
Y249356D01*
X574459Y249481D01*
X574419Y249606D01*
X574359Y249716D01*
X574279Y249816D01*
X574179Y249896D01*
X574069Y249956D01*
X573944Y249996D01*
X573819Y250006D01*
G37*
G36*
G01X578544D02*
X578419Y249996D01*
X578294Y249956D01*
X578184Y249896D01*
X578084Y249816D01*
X578004Y249716D01*
X577944Y249606D01*
X577904Y249481D01*
X577894Y249356D01*
Y248226D01*
X577864Y248196D01*
X577764Y248056D01*
X577744Y248016D01*
X577729Y247981D01*
X577709Y247941D01*
X577694Y247901D01*
X577684Y247861D01*
X577669Y247816D01*
X577664Y247776D01*
X577654Y247736D01*
X577649Y247691D01*
Y247651D01*
X577644Y247606D01*
X577649Y247561D01*
Y247521D01*
X577654Y247476D01*
X577664Y247436D01*
X577669Y247396D01*
X577684Y247351D01*
X577694Y247311D01*
X577709Y247271D01*
X577729Y247231D01*
X577744Y247196D01*
X577764Y247156D01*
X577864Y247016D01*
X577894Y246986D01*
Y243556D01*
X577904Y243431D01*
X577944Y243306D01*
X578004Y243196D01*
X578084Y243096D01*
X578184Y243016D01*
X578294Y242956D01*
X578419Y242916D01*
X578544Y242906D01*
X578669Y242916D01*
X578794Y242956D01*
X578904Y243016D01*
X579004Y243096D01*
X579084Y243196D01*
X579144Y243306D01*
X579184Y243431D01*
X579194Y243556D01*
Y246986D01*
X579224Y247016D01*
X579324Y247156D01*
X579344Y247196D01*
X579359Y247231D01*
X579379Y247271D01*
X579394Y247311D01*
X579404Y247351D01*
X579419Y247396D01*
X579424Y247436D01*
X579434Y247476D01*
X579439Y247521D01*
Y247561D01*
X579444Y247606D01*
X579439Y247651D01*
Y247691D01*
X579434Y247736D01*
X579424Y247776D01*
X579419Y247816D01*
X579404Y247861D01*
X579394Y247901D01*
X579379Y247941D01*
X579359Y247981D01*
X579344Y248016D01*
X579324Y248056D01*
X579224Y248196D01*
X579194Y248226D01*
Y249356D01*
X579184Y249481D01*
X579144Y249606D01*
X579084Y249716D01*
X579004Y249816D01*
X578904Y249896D01*
X578794Y249956D01*
X578669Y249996D01*
X578544Y250006D01*
G37*
G36*
G01X583268D02*
X583143Y249996D01*
X583018Y249956D01*
X582908Y249896D01*
X582808Y249816D01*
X582728Y249716D01*
X582668Y249606D01*
X582628Y249481D01*
X582618Y249356D01*
Y248226D01*
X582588Y248196D01*
X582488Y248056D01*
X582468Y248016D01*
X582453Y247981D01*
X582433Y247941D01*
X582418Y247901D01*
X582408Y247861D01*
X582393Y247816D01*
X582388Y247776D01*
X582378Y247736D01*
X582373Y247691D01*
Y247651D01*
X582368Y247606D01*
X582373Y247561D01*
Y247521D01*
X582378Y247476D01*
X582388Y247436D01*
X582393Y247396D01*
X582408Y247351D01*
X582418Y247311D01*
X582433Y247271D01*
X582453Y247231D01*
X582468Y247196D01*
X582488Y247156D01*
X582588Y247016D01*
X582618Y246986D01*
Y243556D01*
X582628Y243431D01*
X582668Y243306D01*
X582728Y243196D01*
X582808Y243096D01*
X582908Y243016D01*
X583018Y242956D01*
X583143Y242916D01*
X583268Y242906D01*
X583393Y242916D01*
X583518Y242956D01*
X583628Y243016D01*
X583728Y243096D01*
X583808Y243196D01*
X583868Y243306D01*
X583908Y243431D01*
X583918Y243556D01*
Y246986D01*
X583948Y247016D01*
X584048Y247156D01*
X584068Y247196D01*
X584083Y247231D01*
X584103Y247271D01*
X584118Y247311D01*
X584128Y247351D01*
X584143Y247396D01*
X584148Y247436D01*
X584158Y247476D01*
X584163Y247521D01*
Y247561D01*
X584168Y247606D01*
X584163Y247651D01*
Y247691D01*
X584158Y247736D01*
X584148Y247776D01*
X584143Y247816D01*
X584128Y247861D01*
X584118Y247901D01*
X584103Y247941D01*
X584083Y247981D01*
X584068Y248016D01*
X584048Y248056D01*
X583948Y248196D01*
X583918Y248226D01*
Y249356D01*
X583908Y249481D01*
X583868Y249606D01*
X583808Y249716D01*
X583728Y249816D01*
X583628Y249896D01*
X583518Y249956D01*
X583393Y249996D01*
X583268Y250006D01*
G37*
G36*
G01X587992D02*
X587867Y249996D01*
X587742Y249956D01*
X587632Y249896D01*
X587532Y249816D01*
X587452Y249716D01*
X587392Y249606D01*
X587352Y249481D01*
X587342Y249356D01*
Y248226D01*
X587312Y248196D01*
X587212Y248056D01*
X587192Y248016D01*
X587177Y247981D01*
X587157Y247941D01*
X587142Y247901D01*
X587132Y247861D01*
X587117Y247816D01*
X587112Y247776D01*
X587102Y247736D01*
X587097Y247691D01*
Y247651D01*
X587092Y247606D01*
X587097Y247561D01*
Y247521D01*
X587102Y247476D01*
X587112Y247436D01*
X587117Y247396D01*
X587132Y247351D01*
X587142Y247311D01*
X587157Y247271D01*
X587177Y247231D01*
X587192Y247196D01*
X587212Y247156D01*
X587312Y247016D01*
X587342Y246986D01*
Y243556D01*
X587352Y243431D01*
X587392Y243306D01*
X587452Y243196D01*
X587532Y243096D01*
X587632Y243016D01*
X587742Y242956D01*
X587867Y242916D01*
X587992Y242906D01*
X588117Y242916D01*
X588242Y242956D01*
X588352Y243016D01*
X588452Y243096D01*
X588532Y243196D01*
X588592Y243306D01*
X588632Y243431D01*
X588642Y243556D01*
Y246986D01*
X588672Y247016D01*
X588772Y247156D01*
X588792Y247196D01*
X588807Y247231D01*
X588827Y247271D01*
X588842Y247311D01*
X588852Y247351D01*
X588867Y247396D01*
X588872Y247436D01*
X588882Y247476D01*
X588887Y247521D01*
Y247561D01*
X588892Y247606D01*
X588887Y247651D01*
Y247691D01*
X588882Y247736D01*
X588872Y247776D01*
X588867Y247816D01*
X588852Y247861D01*
X588842Y247901D01*
X588827Y247941D01*
X588807Y247981D01*
X588792Y248016D01*
X588772Y248056D01*
X588672Y248196D01*
X588642Y248226D01*
Y249356D01*
X588632Y249481D01*
X588592Y249606D01*
X588532Y249716D01*
X588452Y249816D01*
X588352Y249896D01*
X588242Y249956D01*
X588117Y249996D01*
X587992Y250006D01*
G37*
G36*
G01X592717D02*
X592592Y249996D01*
X592467Y249956D01*
X592357Y249896D01*
X592257Y249816D01*
X592177Y249716D01*
X592117Y249606D01*
X592077Y249481D01*
X592067Y249356D01*
Y248226D01*
X592037Y248196D01*
X591937Y248056D01*
X591917Y248016D01*
X591902Y247981D01*
X591882Y247941D01*
X591867Y247901D01*
X591857Y247861D01*
X591842Y247816D01*
X591837Y247776D01*
X591827Y247736D01*
X591822Y247691D01*
Y247651D01*
X591817Y247606D01*
X591822Y247561D01*
Y247521D01*
X591827Y247476D01*
X591837Y247436D01*
X591842Y247396D01*
X591857Y247351D01*
X591867Y247311D01*
X591882Y247271D01*
X591902Y247231D01*
X591917Y247196D01*
X591937Y247156D01*
X592037Y247016D01*
X592067Y246986D01*
Y243556D01*
X592077Y243431D01*
X592117Y243306D01*
X592177Y243196D01*
X592257Y243096D01*
X592357Y243016D01*
X592467Y242956D01*
X592592Y242916D01*
X592717Y242906D01*
X592842Y242916D01*
X592967Y242956D01*
X593077Y243016D01*
X593177Y243096D01*
X593257Y243196D01*
X593317Y243306D01*
X593357Y243431D01*
X593367Y243556D01*
Y246986D01*
X593397Y247016D01*
X593497Y247156D01*
X593517Y247196D01*
X593532Y247231D01*
X593552Y247271D01*
X593567Y247311D01*
X593577Y247351D01*
X593592Y247396D01*
X593597Y247436D01*
X593607Y247476D01*
X593612Y247521D01*
Y247561D01*
X593617Y247606D01*
X593612Y247651D01*
Y247691D01*
X593607Y247736D01*
X593597Y247776D01*
X593592Y247816D01*
X593577Y247861D01*
X593567Y247901D01*
X593552Y247941D01*
X593532Y247981D01*
X593517Y248016D01*
X593497Y248056D01*
X593397Y248196D01*
X593367Y248226D01*
Y249356D01*
X593357Y249481D01*
X593317Y249606D01*
X593257Y249716D01*
X593177Y249816D01*
X593077Y249896D01*
X592967Y249956D01*
X592842Y249996D01*
X592717Y250006D01*
G37*
G36*
G01X597441D02*
X597316Y249996D01*
X597191Y249956D01*
X597081Y249896D01*
X596981Y249816D01*
X596901Y249716D01*
X596841Y249606D01*
X596801Y249481D01*
X596791Y249356D01*
Y248226D01*
X596761Y248196D01*
X596661Y248056D01*
X596641Y248016D01*
X596626Y247981D01*
X596606Y247941D01*
X596591Y247901D01*
X596581Y247861D01*
X596566Y247816D01*
X596561Y247776D01*
X596551Y247736D01*
X596546Y247691D01*
Y247651D01*
X596541Y247606D01*
X596546Y247561D01*
Y247521D01*
X596551Y247476D01*
X596561Y247436D01*
X596566Y247396D01*
X596581Y247351D01*
X596591Y247311D01*
X596606Y247271D01*
X596626Y247231D01*
X596641Y247196D01*
X596661Y247156D01*
X596761Y247016D01*
X596791Y246986D01*
Y243556D01*
X596801Y243431D01*
X596841Y243306D01*
X596901Y243196D01*
X596981Y243096D01*
X597081Y243016D01*
X597191Y242956D01*
X597316Y242916D01*
X597441Y242906D01*
X597566Y242916D01*
X597691Y242956D01*
X597801Y243016D01*
X597901Y243096D01*
X597981Y243196D01*
X598041Y243306D01*
X598081Y243431D01*
X598091Y243556D01*
Y246986D01*
X598121Y247016D01*
X598221Y247156D01*
X598241Y247196D01*
X598256Y247231D01*
X598276Y247271D01*
X598291Y247311D01*
X598301Y247351D01*
X598316Y247396D01*
X598321Y247436D01*
X598331Y247476D01*
X598336Y247521D01*
Y247561D01*
X598341Y247606D01*
X598336Y247651D01*
Y247691D01*
X598331Y247736D01*
X598321Y247776D01*
X598316Y247816D01*
X598301Y247861D01*
X598291Y247901D01*
X598276Y247941D01*
X598256Y247981D01*
X598241Y248016D01*
X598221Y248056D01*
X598121Y248196D01*
X598091Y248226D01*
Y249356D01*
X598081Y249481D01*
X598041Y249606D01*
X597981Y249716D01*
X597901Y249816D01*
X597801Y249896D01*
X597691Y249956D01*
X597566Y249996D01*
X597441Y250006D01*
G37*
G36*
G01X602166D02*
X602041Y249996D01*
X601916Y249956D01*
X601806Y249896D01*
X601706Y249816D01*
X601626Y249716D01*
X601566Y249606D01*
X601526Y249481D01*
X601516Y249356D01*
Y248226D01*
X601486Y248196D01*
X601386Y248056D01*
X601366Y248016D01*
X601351Y247981D01*
X601331Y247941D01*
X601316Y247901D01*
X601306Y247861D01*
X601291Y247816D01*
X601286Y247776D01*
X601276Y247736D01*
X601271Y247691D01*
Y247651D01*
X601266Y247606D01*
X601271Y247561D01*
Y247521D01*
X601276Y247476D01*
X601286Y247436D01*
X601291Y247396D01*
X601306Y247351D01*
X601316Y247311D01*
X601331Y247271D01*
X601351Y247231D01*
X601366Y247196D01*
X601386Y247156D01*
X601486Y247016D01*
X601516Y246986D01*
Y243556D01*
X601526Y243431D01*
X601566Y243306D01*
X601626Y243196D01*
X601706Y243096D01*
X601806Y243016D01*
X601916Y242956D01*
X602041Y242916D01*
X602166Y242906D01*
X602291Y242916D01*
X602416Y242956D01*
X602526Y243016D01*
X602626Y243096D01*
X602706Y243196D01*
X602766Y243306D01*
X602806Y243431D01*
X602816Y243556D01*
Y246986D01*
X602846Y247016D01*
X602946Y247156D01*
X602966Y247196D01*
X602981Y247231D01*
X603001Y247271D01*
X603016Y247311D01*
X603026Y247351D01*
X603041Y247396D01*
X603046Y247436D01*
X603056Y247476D01*
X603061Y247521D01*
Y247561D01*
X603066Y247606D01*
X603061Y247651D01*
Y247691D01*
X603056Y247736D01*
X603046Y247776D01*
X603041Y247816D01*
X603026Y247861D01*
X603016Y247901D01*
X603001Y247941D01*
X602981Y247981D01*
X602966Y248016D01*
X602946Y248056D01*
X602846Y248196D01*
X602816Y248226D01*
Y249356D01*
X602806Y249481D01*
X602766Y249606D01*
X602706Y249716D01*
X602626Y249816D01*
X602526Y249896D01*
X602416Y249956D01*
X602291Y249996D01*
X602166Y250006D01*
G37*
G36*
G01X606890D02*
X606765Y249996D01*
X606640Y249956D01*
X606530Y249896D01*
X606430Y249816D01*
X606350Y249716D01*
X606290Y249606D01*
X606250Y249481D01*
X606240Y249356D01*
Y248226D01*
X606210Y248196D01*
X606110Y248056D01*
X606090Y248016D01*
X606075Y247981D01*
X606055Y247941D01*
X606040Y247901D01*
X606030Y247861D01*
X606015Y247816D01*
X606010Y247776D01*
X606000Y247736D01*
X605995Y247691D01*
Y247651D01*
X605990Y247606D01*
X605995Y247561D01*
Y247521D01*
X606000Y247476D01*
X606010Y247436D01*
X606015Y247396D01*
X606030Y247351D01*
X606040Y247311D01*
X606055Y247271D01*
X606075Y247231D01*
X606090Y247196D01*
X606110Y247156D01*
X606210Y247016D01*
X606240Y246986D01*
Y243556D01*
X606250Y243431D01*
X606290Y243306D01*
X606350Y243196D01*
X606430Y243096D01*
X606530Y243016D01*
X606640Y242956D01*
X606765Y242916D01*
X606890Y242906D01*
X607015Y242916D01*
X607140Y242956D01*
X607250Y243016D01*
X607350Y243096D01*
X607430Y243196D01*
X607490Y243306D01*
X607530Y243431D01*
X607540Y243556D01*
Y246986D01*
X607570Y247016D01*
X607670Y247156D01*
X607690Y247196D01*
X607705Y247231D01*
X607725Y247271D01*
X607740Y247311D01*
X607750Y247351D01*
X607765Y247396D01*
X607770Y247436D01*
X607780Y247476D01*
X607785Y247521D01*
Y247561D01*
X607790Y247606D01*
X607785Y247651D01*
Y247691D01*
X607780Y247736D01*
X607770Y247776D01*
X607765Y247816D01*
X607750Y247861D01*
X607740Y247901D01*
X607725Y247941D01*
X607705Y247981D01*
X607690Y248016D01*
X607670Y248056D01*
X607570Y248196D01*
X607540Y248226D01*
Y249356D01*
X607530Y249481D01*
X607490Y249606D01*
X607430Y249716D01*
X607350Y249816D01*
X607250Y249896D01*
X607140Y249956D01*
X607015Y249996D01*
X606890Y250006D01*
G37*
G36*
G01X611614D02*
X611489Y249996D01*
X611364Y249956D01*
X611254Y249896D01*
X611154Y249816D01*
X611074Y249716D01*
X611014Y249606D01*
X610974Y249481D01*
X610964Y249356D01*
Y248226D01*
X610934Y248196D01*
X610834Y248056D01*
X610814Y248016D01*
X610799Y247981D01*
X610779Y247941D01*
X610764Y247901D01*
X610754Y247861D01*
X610739Y247816D01*
X610734Y247776D01*
X610724Y247736D01*
X610719Y247691D01*
Y247651D01*
X610714Y247606D01*
X610719Y247561D01*
Y247521D01*
X610724Y247476D01*
X610734Y247436D01*
X610739Y247396D01*
X610754Y247351D01*
X610764Y247311D01*
X610779Y247271D01*
X610799Y247231D01*
X610814Y247196D01*
X610834Y247156D01*
X610934Y247016D01*
X610964Y246986D01*
Y243556D01*
X610974Y243431D01*
X611014Y243306D01*
X611074Y243196D01*
X611154Y243096D01*
X611254Y243016D01*
X611364Y242956D01*
X611489Y242916D01*
X611614Y242906D01*
X611739Y242916D01*
X611864Y242956D01*
X611974Y243016D01*
X612074Y243096D01*
X612154Y243196D01*
X612214Y243306D01*
X612254Y243431D01*
X612264Y243556D01*
Y246986D01*
X612294Y247016D01*
X612394Y247156D01*
X612414Y247196D01*
X612429Y247231D01*
X612449Y247271D01*
X612464Y247311D01*
X612474Y247351D01*
X612489Y247396D01*
X612494Y247436D01*
X612504Y247476D01*
X612509Y247521D01*
Y247561D01*
X612514Y247606D01*
X612509Y247651D01*
Y247691D01*
X612504Y247736D01*
X612494Y247776D01*
X612489Y247816D01*
X612474Y247861D01*
X612464Y247901D01*
X612449Y247941D01*
X612429Y247981D01*
X612414Y248016D01*
X612394Y248056D01*
X612294Y248196D01*
X612264Y248226D01*
Y249356D01*
X612254Y249481D01*
X612214Y249606D01*
X612154Y249716D01*
X612074Y249816D01*
X611974Y249896D01*
X611864Y249956D01*
X611739Y249996D01*
X611614Y250006D01*
G37*
G36*
G01X616339D02*
X616214Y249996D01*
X616089Y249956D01*
X615979Y249896D01*
X615879Y249816D01*
X615799Y249716D01*
X615739Y249606D01*
X615699Y249481D01*
X615689Y249356D01*
Y248226D01*
X615659Y248196D01*
X615559Y248056D01*
X615539Y248016D01*
X615524Y247981D01*
X615504Y247941D01*
X615489Y247901D01*
X615479Y247861D01*
X615464Y247816D01*
X615459Y247776D01*
X615449Y247736D01*
X615444Y247691D01*
Y247651D01*
X615439Y247606D01*
X615444Y247561D01*
Y247521D01*
X615449Y247476D01*
X615459Y247436D01*
X615464Y247396D01*
X615479Y247351D01*
X615489Y247311D01*
X615504Y247271D01*
X615524Y247231D01*
X615539Y247196D01*
X615559Y247156D01*
X615659Y247016D01*
X615689Y246986D01*
Y243556D01*
X615699Y243431D01*
X615739Y243306D01*
X615799Y243196D01*
X615879Y243096D01*
X615979Y243016D01*
X616089Y242956D01*
X616214Y242916D01*
X616339Y242906D01*
X616464Y242916D01*
X616589Y242956D01*
X616699Y243016D01*
X616799Y243096D01*
X616879Y243196D01*
X616939Y243306D01*
X616979Y243431D01*
X616989Y243556D01*
Y246986D01*
X617019Y247016D01*
X617119Y247156D01*
X617139Y247196D01*
X617154Y247231D01*
X617174Y247271D01*
X617189Y247311D01*
X617199Y247351D01*
X617214Y247396D01*
X617219Y247436D01*
X617229Y247476D01*
X617234Y247521D01*
Y247561D01*
X617239Y247606D01*
X617234Y247651D01*
Y247691D01*
X617229Y247736D01*
X617219Y247776D01*
X617214Y247816D01*
X617199Y247861D01*
X617189Y247901D01*
X617174Y247941D01*
X617154Y247981D01*
X617139Y248016D01*
X617119Y248056D01*
X617019Y248196D01*
X616989Y248226D01*
Y249356D01*
X616979Y249481D01*
X616939Y249606D01*
X616879Y249716D01*
X616799Y249816D01*
X616699Y249896D01*
X616589Y249956D01*
X616464Y249996D01*
X616339Y250006D01*
G37*
G36*
G01X621063D02*
X620938Y249996D01*
X620813Y249956D01*
X620703Y249896D01*
X620603Y249816D01*
X620523Y249716D01*
X620463Y249606D01*
X620423Y249481D01*
X620413Y249356D01*
Y248226D01*
X620383Y248196D01*
X620283Y248056D01*
X620263Y248016D01*
X620248Y247981D01*
X620228Y247941D01*
X620213Y247901D01*
X620203Y247861D01*
X620188Y247816D01*
X620183Y247776D01*
X620173Y247736D01*
X620168Y247691D01*
Y247651D01*
X620163Y247606D01*
X620168Y247561D01*
Y247521D01*
X620173Y247476D01*
X620183Y247436D01*
X620188Y247396D01*
X620203Y247351D01*
X620213Y247311D01*
X620228Y247271D01*
X620248Y247231D01*
X620263Y247196D01*
X620283Y247156D01*
X620383Y247016D01*
X620413Y246986D01*
Y243556D01*
X620423Y243431D01*
X620463Y243306D01*
X620523Y243196D01*
X620603Y243096D01*
X620703Y243016D01*
X620813Y242956D01*
X620938Y242916D01*
X621063Y242906D01*
X621188Y242916D01*
X621313Y242956D01*
X621423Y243016D01*
X621523Y243096D01*
X621603Y243196D01*
X621663Y243306D01*
X621703Y243431D01*
X621713Y243556D01*
Y246986D01*
X621743Y247016D01*
X621843Y247156D01*
X621863Y247196D01*
X621878Y247231D01*
X621898Y247271D01*
X621913Y247311D01*
X621923Y247351D01*
X621938Y247396D01*
X621943Y247436D01*
X621953Y247476D01*
X621958Y247521D01*
Y247561D01*
X621963Y247606D01*
X621958Y247651D01*
Y247691D01*
X621953Y247736D01*
X621943Y247776D01*
X621938Y247816D01*
X621923Y247861D01*
X621913Y247901D01*
X621898Y247941D01*
X621878Y247981D01*
X621863Y248016D01*
X621843Y248056D01*
X621743Y248196D01*
X621713Y248226D01*
Y249356D01*
X621703Y249481D01*
X621663Y249606D01*
X621603Y249716D01*
X621523Y249816D01*
X621423Y249896D01*
X621313Y249956D01*
X621188Y249996D01*
X621063Y250006D01*
G37*
G36*
G01X625788D02*
X625663Y249996D01*
X625538Y249956D01*
X625428Y249896D01*
X625328Y249816D01*
X625248Y249716D01*
X625188Y249606D01*
X625148Y249481D01*
X625138Y249356D01*
Y248226D01*
X625108Y248196D01*
X625008Y248056D01*
X624988Y248016D01*
X624973Y247981D01*
X624953Y247941D01*
X624938Y247901D01*
X624928Y247861D01*
X624913Y247816D01*
X624908Y247776D01*
X624898Y247736D01*
X624893Y247691D01*
Y247651D01*
X624888Y247606D01*
X624893Y247561D01*
Y247521D01*
X624898Y247476D01*
X624908Y247436D01*
X624913Y247396D01*
X624928Y247351D01*
X624938Y247311D01*
X624953Y247271D01*
X624973Y247231D01*
X624988Y247196D01*
X625008Y247156D01*
X625108Y247016D01*
X625138Y246986D01*
Y243556D01*
X625148Y243431D01*
X625188Y243306D01*
X625248Y243196D01*
X625328Y243096D01*
X625428Y243016D01*
X625538Y242956D01*
X625663Y242916D01*
X625788Y242906D01*
X625913Y242916D01*
X626038Y242956D01*
X626148Y243016D01*
X626248Y243096D01*
X626328Y243196D01*
X626388Y243306D01*
X626428Y243431D01*
X626438Y243556D01*
Y246986D01*
X626468Y247016D01*
X626568Y247156D01*
X626588Y247196D01*
X626603Y247231D01*
X626623Y247271D01*
X626638Y247311D01*
X626648Y247351D01*
X626663Y247396D01*
X626668Y247436D01*
X626678Y247476D01*
X626683Y247521D01*
Y247561D01*
X626688Y247606D01*
X626683Y247651D01*
Y247691D01*
X626678Y247736D01*
X626668Y247776D01*
X626663Y247816D01*
X626648Y247861D01*
X626638Y247901D01*
X626623Y247941D01*
X626603Y247981D01*
X626588Y248016D01*
X626568Y248056D01*
X626468Y248196D01*
X626438Y248226D01*
Y249356D01*
X626428Y249481D01*
X626388Y249606D01*
X626328Y249716D01*
X626248Y249816D01*
X626148Y249896D01*
X626038Y249956D01*
X625913Y249996D01*
X625788Y250006D01*
G37*
G36*
G01X630512D02*
X630387Y249996D01*
X630262Y249956D01*
X630152Y249896D01*
X630052Y249816D01*
X629972Y249716D01*
X629912Y249606D01*
X629872Y249481D01*
X629862Y249356D01*
Y248226D01*
X629832Y248196D01*
X629732Y248056D01*
X629712Y248016D01*
X629697Y247981D01*
X629677Y247941D01*
X629662Y247901D01*
X629652Y247861D01*
X629637Y247816D01*
X629632Y247776D01*
X629622Y247736D01*
X629617Y247691D01*
Y247651D01*
X629612Y247606D01*
X629617Y247561D01*
Y247521D01*
X629622Y247476D01*
X629632Y247436D01*
X629637Y247396D01*
X629652Y247351D01*
X629662Y247311D01*
X629677Y247271D01*
X629697Y247231D01*
X629712Y247196D01*
X629732Y247156D01*
X629832Y247016D01*
X629862Y246986D01*
Y243556D01*
X629872Y243431D01*
X629912Y243306D01*
X629972Y243196D01*
X630052Y243096D01*
X630152Y243016D01*
X630262Y242956D01*
X630387Y242916D01*
X630512Y242906D01*
X630637Y242916D01*
X630762Y242956D01*
X630872Y243016D01*
X630972Y243096D01*
X631052Y243196D01*
X631112Y243306D01*
X631152Y243431D01*
X631162Y243556D01*
Y246986D01*
X631192Y247016D01*
X631292Y247156D01*
X631312Y247196D01*
X631327Y247231D01*
X631347Y247271D01*
X631362Y247311D01*
X631372Y247351D01*
X631387Y247396D01*
X631392Y247436D01*
X631402Y247476D01*
X631407Y247521D01*
Y247561D01*
X631412Y247606D01*
X631407Y247651D01*
Y247691D01*
X631402Y247736D01*
X631392Y247776D01*
X631387Y247816D01*
X631372Y247861D01*
X631362Y247901D01*
X631347Y247941D01*
X631327Y247981D01*
X631312Y248016D01*
X631292Y248056D01*
X631192Y248196D01*
X631162Y248226D01*
Y249356D01*
X631152Y249481D01*
X631112Y249606D01*
X631052Y249716D01*
X630972Y249816D01*
X630872Y249896D01*
X630762Y249956D01*
X630637Y249996D01*
X630512Y250006D01*
G37*
G36*
G01X635236D02*
X635111Y249996D01*
X634986Y249956D01*
X634876Y249896D01*
X634776Y249816D01*
X634696Y249716D01*
X634636Y249606D01*
X634596Y249481D01*
X634586Y249356D01*
Y248226D01*
X634556Y248196D01*
X634456Y248056D01*
X634436Y248016D01*
X634421Y247981D01*
X634401Y247941D01*
X634386Y247901D01*
X634376Y247861D01*
X634361Y247816D01*
X634356Y247776D01*
X634346Y247736D01*
X634341Y247691D01*
Y247651D01*
X634336Y247606D01*
X634341Y247561D01*
Y247521D01*
X634346Y247476D01*
X634356Y247436D01*
X634361Y247396D01*
X634376Y247351D01*
X634386Y247311D01*
X634401Y247271D01*
X634421Y247231D01*
X634436Y247196D01*
X634456Y247156D01*
X634556Y247016D01*
X634586Y246986D01*
Y243556D01*
X634596Y243431D01*
X634636Y243306D01*
X634696Y243196D01*
X634776Y243096D01*
X634876Y243016D01*
X634986Y242956D01*
X635111Y242916D01*
X635236Y242906D01*
X635361Y242916D01*
X635486Y242956D01*
X635596Y243016D01*
X635696Y243096D01*
X635776Y243196D01*
X635836Y243306D01*
X635876Y243431D01*
X635886Y243556D01*
Y246986D01*
X635916Y247016D01*
X636016Y247156D01*
X636036Y247196D01*
X636051Y247231D01*
X636071Y247271D01*
X636086Y247311D01*
X636096Y247351D01*
X636111Y247396D01*
X636116Y247436D01*
X636126Y247476D01*
X636131Y247521D01*
Y247561D01*
X636136Y247606D01*
X636131Y247651D01*
Y247691D01*
X636126Y247736D01*
X636116Y247776D01*
X636111Y247816D01*
X636096Y247861D01*
X636086Y247901D01*
X636071Y247941D01*
X636051Y247981D01*
X636036Y248016D01*
X636016Y248056D01*
X635916Y248196D01*
X635886Y248226D01*
Y249356D01*
X635876Y249481D01*
X635836Y249606D01*
X635776Y249716D01*
X635696Y249816D01*
X635596Y249896D01*
X635486Y249956D01*
X635361Y249996D01*
X635236Y250006D01*
G37*
G36*
G01X639961D02*
X639836Y249996D01*
X639711Y249956D01*
X639601Y249896D01*
X639501Y249816D01*
X639421Y249716D01*
X639361Y249606D01*
X639321Y249481D01*
X639311Y249356D01*
Y248226D01*
X639281Y248196D01*
X639181Y248056D01*
X639161Y248016D01*
X639146Y247981D01*
X639126Y247941D01*
X639111Y247901D01*
X639101Y247861D01*
X639086Y247816D01*
X639081Y247776D01*
X639071Y247736D01*
X639066Y247691D01*
Y247651D01*
X639061Y247606D01*
X639066Y247561D01*
Y247521D01*
X639071Y247476D01*
X639081Y247436D01*
X639086Y247396D01*
X639101Y247351D01*
X639111Y247311D01*
X639126Y247271D01*
X639146Y247231D01*
X639161Y247196D01*
X639181Y247156D01*
X639281Y247016D01*
X639311Y246986D01*
Y243556D01*
X639321Y243431D01*
X639361Y243306D01*
X639421Y243196D01*
X639501Y243096D01*
X639601Y243016D01*
X639711Y242956D01*
X639836Y242916D01*
X639961Y242906D01*
X640086Y242916D01*
X640211Y242956D01*
X640321Y243016D01*
X640421Y243096D01*
X640501Y243196D01*
X640561Y243306D01*
X640601Y243431D01*
X640611Y243556D01*
Y246986D01*
X640641Y247016D01*
X640741Y247156D01*
X640761Y247196D01*
X640776Y247231D01*
X640796Y247271D01*
X640811Y247311D01*
X640821Y247351D01*
X640836Y247396D01*
X640841Y247436D01*
X640851Y247476D01*
X640856Y247521D01*
Y247561D01*
X640861Y247606D01*
X640856Y247651D01*
Y247691D01*
X640851Y247736D01*
X640841Y247776D01*
X640836Y247816D01*
X640821Y247861D01*
X640811Y247901D01*
X640796Y247941D01*
X640776Y247981D01*
X640761Y248016D01*
X640741Y248056D01*
X640641Y248196D01*
X640611Y248226D01*
Y249356D01*
X640601Y249481D01*
X640561Y249606D01*
X640501Y249716D01*
X640421Y249816D01*
X640321Y249896D01*
X640211Y249956D01*
X640086Y249996D01*
X639961Y250006D01*
G37*
G36*
G01X644685D02*
X644560Y249996D01*
X644435Y249956D01*
X644325Y249896D01*
X644225Y249816D01*
X644145Y249716D01*
X644085Y249606D01*
X644045Y249481D01*
X644035Y249356D01*
Y248226D01*
X644005Y248196D01*
X643905Y248056D01*
X643885Y248016D01*
X643870Y247981D01*
X643850Y247941D01*
X643835Y247901D01*
X643825Y247861D01*
X643810Y247816D01*
X643805Y247776D01*
X643795Y247736D01*
X643790Y247691D01*
Y247651D01*
X643785Y247606D01*
X643790Y247561D01*
Y247521D01*
X643795Y247476D01*
X643805Y247436D01*
X643810Y247396D01*
X643825Y247351D01*
X643835Y247311D01*
X643850Y247271D01*
X643870Y247231D01*
X643885Y247196D01*
X643905Y247156D01*
X644005Y247016D01*
X644035Y246986D01*
Y243556D01*
X644045Y243431D01*
X644085Y243306D01*
X644145Y243196D01*
X644225Y243096D01*
X644325Y243016D01*
X644435Y242956D01*
X644560Y242916D01*
X644685Y242906D01*
X644810Y242916D01*
X644935Y242956D01*
X645045Y243016D01*
X645145Y243096D01*
X645225Y243196D01*
X645285Y243306D01*
X645325Y243431D01*
X645335Y243556D01*
Y246986D01*
X645365Y247016D01*
X645465Y247156D01*
X645485Y247196D01*
X645500Y247231D01*
X645520Y247271D01*
X645535Y247311D01*
X645545Y247351D01*
X645560Y247396D01*
X645565Y247436D01*
X645575Y247476D01*
X645580Y247521D01*
Y247561D01*
X645585Y247606D01*
X645580Y247651D01*
Y247691D01*
X645575Y247736D01*
X645565Y247776D01*
X645560Y247816D01*
X645545Y247861D01*
X645535Y247901D01*
X645520Y247941D01*
X645500Y247981D01*
X645485Y248016D01*
X645465Y248056D01*
X645365Y248196D01*
X645335Y248226D01*
Y249356D01*
X645325Y249481D01*
X645285Y249606D01*
X645225Y249716D01*
X645145Y249816D01*
X645045Y249896D01*
X644935Y249956D01*
X644810Y249996D01*
X644685Y250006D01*
G37*
G36*
G01X649410D02*
X649285Y249996D01*
X649160Y249956D01*
X649050Y249896D01*
X648950Y249816D01*
X648870Y249716D01*
X648810Y249606D01*
X648770Y249481D01*
X648760Y249356D01*
Y248226D01*
X648730Y248196D01*
X648630Y248056D01*
X648610Y248016D01*
X648595Y247981D01*
X648575Y247941D01*
X648560Y247901D01*
X648550Y247861D01*
X648535Y247816D01*
X648530Y247776D01*
X648520Y247736D01*
X648515Y247691D01*
Y247651D01*
X648510Y247606D01*
X648515Y247561D01*
Y247521D01*
X648520Y247476D01*
X648530Y247436D01*
X648535Y247396D01*
X648550Y247351D01*
X648560Y247311D01*
X648575Y247271D01*
X648595Y247231D01*
X648610Y247196D01*
X648630Y247156D01*
X648730Y247016D01*
X648760Y246986D01*
Y243556D01*
X648770Y243431D01*
X648810Y243306D01*
X648870Y243196D01*
X648950Y243096D01*
X649050Y243016D01*
X649160Y242956D01*
X649285Y242916D01*
X649410Y242906D01*
X649535Y242916D01*
X649660Y242956D01*
X649770Y243016D01*
X649870Y243096D01*
X649950Y243196D01*
X650010Y243306D01*
X650050Y243431D01*
X650060Y243556D01*
Y246986D01*
X650090Y247016D01*
X650190Y247156D01*
X650210Y247196D01*
X650225Y247231D01*
X650245Y247271D01*
X650260Y247311D01*
X650270Y247351D01*
X650285Y247396D01*
X650290Y247436D01*
X650300Y247476D01*
X650305Y247521D01*
Y247561D01*
X650310Y247606D01*
X650305Y247651D01*
Y247691D01*
X650300Y247736D01*
X650290Y247776D01*
X650285Y247816D01*
X650270Y247861D01*
X650260Y247901D01*
X650245Y247941D01*
X650225Y247981D01*
X650210Y248016D01*
X650190Y248056D01*
X650090Y248196D01*
X650060Y248226D01*
Y249356D01*
X650050Y249481D01*
X650010Y249606D01*
X649950Y249716D01*
X649870Y249816D01*
X649770Y249896D01*
X649660Y249956D01*
X649535Y249996D01*
X649410Y250006D01*
G37*
G36*
G01X654134D02*
X654009Y249996D01*
X653884Y249956D01*
X653774Y249896D01*
X653674Y249816D01*
X653594Y249716D01*
X653534Y249606D01*
X653494Y249481D01*
X653484Y249356D01*
Y248226D01*
X653454Y248196D01*
X653354Y248056D01*
X653334Y248016D01*
X653319Y247981D01*
X653299Y247941D01*
X653284Y247901D01*
X653274Y247861D01*
X653259Y247816D01*
X653254Y247776D01*
X653244Y247736D01*
X653239Y247691D01*
Y247651D01*
X653234Y247606D01*
X653239Y247561D01*
Y247521D01*
X653244Y247476D01*
X653254Y247436D01*
X653259Y247396D01*
X653274Y247351D01*
X653284Y247311D01*
X653299Y247271D01*
X653319Y247231D01*
X653334Y247196D01*
X653354Y247156D01*
X653454Y247016D01*
X653484Y246986D01*
Y243556D01*
X653494Y243431D01*
X653534Y243306D01*
X653594Y243196D01*
X653674Y243096D01*
X653774Y243016D01*
X653884Y242956D01*
X654009Y242916D01*
X654134Y242906D01*
X654259Y242916D01*
X654384Y242956D01*
X654494Y243016D01*
X654594Y243096D01*
X654674Y243196D01*
X654734Y243306D01*
X654774Y243431D01*
X654784Y243556D01*
Y246986D01*
X654814Y247016D01*
X654914Y247156D01*
X654934Y247196D01*
X654949Y247231D01*
X654969Y247271D01*
X654984Y247311D01*
X654994Y247351D01*
X655009Y247396D01*
X655014Y247436D01*
X655024Y247476D01*
X655029Y247521D01*
Y247561D01*
X655034Y247606D01*
X655029Y247651D01*
Y247691D01*
X655024Y247736D01*
X655014Y247776D01*
X655009Y247816D01*
X654994Y247861D01*
X654984Y247901D01*
X654969Y247941D01*
X654949Y247981D01*
X654934Y248016D01*
X654914Y248056D01*
X654814Y248196D01*
X654784Y248226D01*
Y249356D01*
X654774Y249481D01*
X654734Y249606D01*
X654674Y249716D01*
X654594Y249816D01*
X654494Y249896D01*
X654384Y249956D01*
X654259Y249996D01*
X654134Y250006D01*
G37*
G36*
G01X668307D02*
X668182Y249996D01*
X668057Y249956D01*
X667947Y249896D01*
X667847Y249816D01*
X667767Y249716D01*
X667707Y249606D01*
X667667Y249481D01*
X667657Y249356D01*
Y248226D01*
X667627Y248196D01*
X667527Y248056D01*
X667507Y248016D01*
X667492Y247981D01*
X667472Y247941D01*
X667457Y247901D01*
X667447Y247861D01*
X667432Y247816D01*
X667427Y247776D01*
X667417Y247736D01*
X667412Y247691D01*
Y247651D01*
X667407Y247606D01*
X667412Y247561D01*
Y247521D01*
X667417Y247476D01*
X667427Y247436D01*
X667432Y247396D01*
X667447Y247351D01*
X667457Y247311D01*
X667472Y247271D01*
X667492Y247231D01*
X667507Y247196D01*
X667527Y247156D01*
X667627Y247016D01*
X667657Y246986D01*
Y243556D01*
X667667Y243431D01*
X667707Y243306D01*
X667767Y243196D01*
X667847Y243096D01*
X667947Y243016D01*
X668057Y242956D01*
X668182Y242916D01*
X668307Y242906D01*
X668432Y242916D01*
X668557Y242956D01*
X668667Y243016D01*
X668767Y243096D01*
X668847Y243196D01*
X668907Y243306D01*
X668947Y243431D01*
X668957Y243556D01*
Y246986D01*
X668987Y247016D01*
X669087Y247156D01*
X669107Y247196D01*
X669122Y247231D01*
X669142Y247271D01*
X669157Y247311D01*
X669167Y247351D01*
X669182Y247396D01*
X669187Y247436D01*
X669197Y247476D01*
X669202Y247521D01*
Y247561D01*
X669207Y247606D01*
X669202Y247651D01*
Y247691D01*
X669197Y247736D01*
X669187Y247776D01*
X669182Y247816D01*
X669167Y247861D01*
X669157Y247901D01*
X669142Y247941D01*
X669122Y247981D01*
X669107Y248016D01*
X669087Y248056D01*
X668987Y248196D01*
X668957Y248226D01*
Y249356D01*
X668947Y249481D01*
X668907Y249606D01*
X668847Y249716D01*
X668767Y249816D01*
X668667Y249896D01*
X668557Y249956D01*
X668432Y249996D01*
X668307Y250006D01*
G37*
G36*
G01X673032D02*
X672907Y249996D01*
X672782Y249956D01*
X672672Y249896D01*
X672572Y249816D01*
X672492Y249716D01*
X672432Y249606D01*
X672392Y249481D01*
X672382Y249356D01*
Y248226D01*
X672352Y248196D01*
X672252Y248056D01*
X672232Y248016D01*
X672217Y247981D01*
X672197Y247941D01*
X672182Y247901D01*
X672172Y247861D01*
X672157Y247816D01*
X672152Y247776D01*
X672142Y247736D01*
X672137Y247691D01*
Y247651D01*
X672132Y247606D01*
X672137Y247561D01*
Y247521D01*
X672142Y247476D01*
X672152Y247436D01*
X672157Y247396D01*
X672172Y247351D01*
X672182Y247311D01*
X672197Y247271D01*
X672217Y247231D01*
X672232Y247196D01*
X672252Y247156D01*
X672352Y247016D01*
X672382Y246986D01*
Y243556D01*
X672392Y243431D01*
X672432Y243306D01*
X672492Y243196D01*
X672572Y243096D01*
X672672Y243016D01*
X672782Y242956D01*
X672907Y242916D01*
X673032Y242906D01*
X673157Y242916D01*
X673282Y242956D01*
X673392Y243016D01*
X673492Y243096D01*
X673572Y243196D01*
X673632Y243306D01*
X673672Y243431D01*
X673682Y243556D01*
Y246986D01*
X673712Y247016D01*
X673812Y247156D01*
X673832Y247196D01*
X673847Y247231D01*
X673867Y247271D01*
X673882Y247311D01*
X673892Y247351D01*
X673907Y247396D01*
X673912Y247436D01*
X673922Y247476D01*
X673927Y247521D01*
Y247561D01*
X673932Y247606D01*
X673927Y247651D01*
Y247691D01*
X673922Y247736D01*
X673912Y247776D01*
X673907Y247816D01*
X673892Y247861D01*
X673882Y247901D01*
X673867Y247941D01*
X673847Y247981D01*
X673832Y248016D01*
X673812Y248056D01*
X673712Y248196D01*
X673682Y248226D01*
Y249356D01*
X673672Y249481D01*
X673632Y249606D01*
X673572Y249716D01*
X673492Y249816D01*
X673392Y249896D01*
X673282Y249956D01*
X673157Y249996D01*
X673032Y250006D01*
G37*
G36*
G01X677756D02*
X677631Y249996D01*
X677506Y249956D01*
X677396Y249896D01*
X677296Y249816D01*
X677216Y249716D01*
X677156Y249606D01*
X677116Y249481D01*
X677106Y249356D01*
Y248226D01*
X677076Y248196D01*
X676976Y248056D01*
X676956Y248016D01*
X676941Y247981D01*
X676921Y247941D01*
X676906Y247901D01*
X676896Y247861D01*
X676881Y247816D01*
X676876Y247776D01*
X676866Y247736D01*
X676861Y247691D01*
Y247651D01*
X676856Y247606D01*
X676861Y247561D01*
Y247521D01*
X676866Y247476D01*
X676876Y247436D01*
X676881Y247396D01*
X676896Y247351D01*
X676906Y247311D01*
X676921Y247271D01*
X676941Y247231D01*
X676956Y247196D01*
X676976Y247156D01*
X677076Y247016D01*
X677106Y246986D01*
Y243556D01*
X677116Y243431D01*
X677156Y243306D01*
X677216Y243196D01*
X677296Y243096D01*
X677396Y243016D01*
X677506Y242956D01*
X677631Y242916D01*
X677756Y242906D01*
X677881Y242916D01*
X678006Y242956D01*
X678116Y243016D01*
X678216Y243096D01*
X678296Y243196D01*
X678356Y243306D01*
X678396Y243431D01*
X678406Y243556D01*
Y246986D01*
X678436Y247016D01*
X678536Y247156D01*
X678556Y247196D01*
X678571Y247231D01*
X678591Y247271D01*
X678606Y247311D01*
X678616Y247351D01*
X678631Y247396D01*
X678636Y247436D01*
X678646Y247476D01*
X678651Y247521D01*
Y247561D01*
X678656Y247606D01*
X678651Y247651D01*
Y247691D01*
X678646Y247736D01*
X678636Y247776D01*
X678631Y247816D01*
X678616Y247861D01*
X678606Y247901D01*
X678591Y247941D01*
X678571Y247981D01*
X678556Y248016D01*
X678536Y248056D01*
X678436Y248196D01*
X678406Y248226D01*
Y249356D01*
X678396Y249481D01*
X678356Y249606D01*
X678296Y249716D01*
X678216Y249816D01*
X678116Y249896D01*
X678006Y249956D01*
X677881Y249996D01*
X677756Y250006D01*
G37*
G36*
G01X682481D02*
X682356Y249996D01*
X682231Y249956D01*
X682121Y249896D01*
X682021Y249816D01*
X681941Y249716D01*
X681881Y249606D01*
X681841Y249481D01*
X681831Y249356D01*
Y248226D01*
X681801Y248196D01*
X681701Y248056D01*
X681681Y248016D01*
X681666Y247981D01*
X681646Y247941D01*
X681631Y247901D01*
X681621Y247861D01*
X681606Y247816D01*
X681601Y247776D01*
X681591Y247736D01*
X681586Y247691D01*
Y247651D01*
X681581Y247606D01*
X681586Y247561D01*
Y247521D01*
X681591Y247476D01*
X681601Y247436D01*
X681606Y247396D01*
X681621Y247351D01*
X681631Y247311D01*
X681646Y247271D01*
X681666Y247231D01*
X681681Y247196D01*
X681701Y247156D01*
X681801Y247016D01*
X681831Y246986D01*
Y243556D01*
X681841Y243431D01*
X681881Y243306D01*
X681941Y243196D01*
X682021Y243096D01*
X682121Y243016D01*
X682231Y242956D01*
X682356Y242916D01*
X682481Y242906D01*
X682606Y242916D01*
X682731Y242956D01*
X682841Y243016D01*
X682941Y243096D01*
X683021Y243196D01*
X683081Y243306D01*
X683121Y243431D01*
X683131Y243556D01*
Y246986D01*
X683161Y247016D01*
X683261Y247156D01*
X683281Y247196D01*
X683296Y247231D01*
X683316Y247271D01*
X683331Y247311D01*
X683341Y247351D01*
X683356Y247396D01*
X683361Y247436D01*
X683371Y247476D01*
X683376Y247521D01*
Y247561D01*
X683381Y247606D01*
X683376Y247651D01*
Y247691D01*
X683371Y247736D01*
X683361Y247776D01*
X683356Y247816D01*
X683341Y247861D01*
X683331Y247901D01*
X683316Y247941D01*
X683296Y247981D01*
X683281Y248016D01*
X683261Y248056D01*
X683161Y248196D01*
X683131Y248226D01*
Y249356D01*
X683121Y249481D01*
X683081Y249606D01*
X683021Y249716D01*
X682941Y249816D01*
X682841Y249896D01*
X682731Y249956D01*
X682606Y249996D01*
X682481Y250006D01*
G37*
G36*
G01X687205D02*
X687080Y249996D01*
X686955Y249956D01*
X686845Y249896D01*
X686745Y249816D01*
X686665Y249716D01*
X686605Y249606D01*
X686565Y249481D01*
X686555Y249356D01*
Y248226D01*
X686525Y248196D01*
X686425Y248056D01*
X686405Y248016D01*
X686390Y247981D01*
X686370Y247941D01*
X686355Y247901D01*
X686345Y247861D01*
X686330Y247816D01*
X686325Y247776D01*
X686315Y247736D01*
X686310Y247691D01*
Y247651D01*
X686305Y247606D01*
X686310Y247561D01*
Y247521D01*
X686315Y247476D01*
X686325Y247436D01*
X686330Y247396D01*
X686345Y247351D01*
X686355Y247311D01*
X686370Y247271D01*
X686390Y247231D01*
X686405Y247196D01*
X686425Y247156D01*
X686525Y247016D01*
X686555Y246986D01*
Y243556D01*
X686565Y243431D01*
X686605Y243306D01*
X686665Y243196D01*
X686745Y243096D01*
X686845Y243016D01*
X686955Y242956D01*
X687080Y242916D01*
X687205Y242906D01*
X687330Y242916D01*
X687455Y242956D01*
X687565Y243016D01*
X687665Y243096D01*
X687745Y243196D01*
X687805Y243306D01*
X687845Y243431D01*
X687855Y243556D01*
Y246986D01*
X687885Y247016D01*
X687985Y247156D01*
X688005Y247196D01*
X688020Y247231D01*
X688040Y247271D01*
X688055Y247311D01*
X688065Y247351D01*
X688080Y247396D01*
X688085Y247436D01*
X688095Y247476D01*
X688100Y247521D01*
Y247561D01*
X688105Y247606D01*
X688100Y247651D01*
Y247691D01*
X688095Y247736D01*
X688085Y247776D01*
X688080Y247816D01*
X688065Y247861D01*
X688055Y247901D01*
X688040Y247941D01*
X688020Y247981D01*
X688005Y248016D01*
X687985Y248056D01*
X687885Y248196D01*
X687855Y248226D01*
Y249356D01*
X687845Y249481D01*
X687805Y249606D01*
X687745Y249716D01*
X687665Y249816D01*
X687565Y249896D01*
X687455Y249956D01*
X687330Y249996D01*
X687205Y250006D01*
G37*
G36*
G01X691929D02*
X691804Y249996D01*
X691679Y249956D01*
X691569Y249896D01*
X691469Y249816D01*
X691389Y249716D01*
X691329Y249606D01*
X691289Y249481D01*
X691279Y249356D01*
Y248226D01*
X691249Y248196D01*
X691149Y248056D01*
X691129Y248016D01*
X691114Y247981D01*
X691094Y247941D01*
X691079Y247901D01*
X691069Y247861D01*
X691054Y247816D01*
X691049Y247776D01*
X691039Y247736D01*
X691034Y247691D01*
Y247651D01*
X691029Y247606D01*
X691034Y247561D01*
Y247521D01*
X691039Y247476D01*
X691049Y247436D01*
X691054Y247396D01*
X691069Y247351D01*
X691079Y247311D01*
X691094Y247271D01*
X691114Y247231D01*
X691129Y247196D01*
X691149Y247156D01*
X691249Y247016D01*
X691279Y246986D01*
Y243556D01*
X691289Y243431D01*
X691329Y243306D01*
X691389Y243196D01*
X691469Y243096D01*
X691569Y243016D01*
X691679Y242956D01*
X691804Y242916D01*
X691929Y242906D01*
X692054Y242916D01*
X692179Y242956D01*
X692289Y243016D01*
X692389Y243096D01*
X692469Y243196D01*
X692529Y243306D01*
X692569Y243431D01*
X692579Y243556D01*
Y246986D01*
X692609Y247016D01*
X692709Y247156D01*
X692729Y247196D01*
X692744Y247231D01*
X692764Y247271D01*
X692779Y247311D01*
X692789Y247351D01*
X692804Y247396D01*
X692809Y247436D01*
X692819Y247476D01*
X692824Y247521D01*
Y247561D01*
X692829Y247606D01*
X692824Y247651D01*
Y247691D01*
X692819Y247736D01*
X692809Y247776D01*
X692804Y247816D01*
X692789Y247861D01*
X692779Y247901D01*
X692764Y247941D01*
X692744Y247981D01*
X692729Y248016D01*
X692709Y248056D01*
X692609Y248196D01*
X692579Y248226D01*
Y249356D01*
X692569Y249481D01*
X692529Y249606D01*
X692469Y249716D01*
X692389Y249816D01*
X692289Y249896D01*
X692179Y249956D01*
X692054Y249996D01*
X691929Y250006D01*
G37*
G36*
G01X696654D02*
X696529Y249996D01*
X696404Y249956D01*
X696294Y249896D01*
X696194Y249816D01*
X696114Y249716D01*
X696054Y249606D01*
X696014Y249481D01*
X696004Y249356D01*
Y248226D01*
X695974Y248196D01*
X695874Y248056D01*
X695854Y248016D01*
X695839Y247981D01*
X695819Y247941D01*
X695804Y247901D01*
X695794Y247861D01*
X695779Y247816D01*
X695774Y247776D01*
X695764Y247736D01*
X695759Y247691D01*
Y247651D01*
X695754Y247606D01*
X695759Y247561D01*
Y247521D01*
X695764Y247476D01*
X695774Y247436D01*
X695779Y247396D01*
X695794Y247351D01*
X695804Y247311D01*
X695819Y247271D01*
X695839Y247231D01*
X695854Y247196D01*
X695874Y247156D01*
X695974Y247016D01*
X696004Y246986D01*
Y243556D01*
X696014Y243431D01*
X696054Y243306D01*
X696114Y243196D01*
X696194Y243096D01*
X696294Y243016D01*
X696404Y242956D01*
X696529Y242916D01*
X696654Y242906D01*
X696779Y242916D01*
X696904Y242956D01*
X697014Y243016D01*
X697114Y243096D01*
X697194Y243196D01*
X697254Y243306D01*
X697294Y243431D01*
X697304Y243556D01*
Y246986D01*
X697334Y247016D01*
X697434Y247156D01*
X697454Y247196D01*
X697469Y247231D01*
X697489Y247271D01*
X697504Y247311D01*
X697514Y247351D01*
X697529Y247396D01*
X697534Y247436D01*
X697544Y247476D01*
X697549Y247521D01*
Y247561D01*
X697554Y247606D01*
X697549Y247651D01*
Y247691D01*
X697544Y247736D01*
X697534Y247776D01*
X697529Y247816D01*
X697514Y247861D01*
X697504Y247901D01*
X697489Y247941D01*
X697469Y247981D01*
X697454Y248016D01*
X697434Y248056D01*
X697334Y248196D01*
X697304Y248226D01*
Y249356D01*
X697294Y249481D01*
X697254Y249606D01*
X697194Y249716D01*
X697114Y249816D01*
X697014Y249896D01*
X696904Y249956D01*
X696779Y249996D01*
X696654Y250006D01*
G37*
G36*
G01X701378D02*
X701253Y249996D01*
X701128Y249956D01*
X701018Y249896D01*
X700918Y249816D01*
X700838Y249716D01*
X700778Y249606D01*
X700738Y249481D01*
X700728Y249356D01*
Y248226D01*
X700698Y248196D01*
X700598Y248056D01*
X700578Y248016D01*
X700563Y247981D01*
X700543Y247941D01*
X700528Y247901D01*
X700518Y247861D01*
X700503Y247816D01*
X700498Y247776D01*
X700488Y247736D01*
X700483Y247691D01*
Y247651D01*
X700478Y247606D01*
X700483Y247561D01*
Y247521D01*
X700488Y247476D01*
X700498Y247436D01*
X700503Y247396D01*
X700518Y247351D01*
X700528Y247311D01*
X700543Y247271D01*
X700563Y247231D01*
X700578Y247196D01*
X700598Y247156D01*
X700698Y247016D01*
X700728Y246986D01*
Y243556D01*
X700738Y243431D01*
X700778Y243306D01*
X700838Y243196D01*
X700918Y243096D01*
X701018Y243016D01*
X701128Y242956D01*
X701253Y242916D01*
X701378Y242906D01*
X701503Y242916D01*
X701628Y242956D01*
X701738Y243016D01*
X701838Y243096D01*
X701918Y243196D01*
X701978Y243306D01*
X702018Y243431D01*
X702028Y243556D01*
Y246986D01*
X702058Y247016D01*
X702158Y247156D01*
X702178Y247196D01*
X702193Y247231D01*
X702213Y247271D01*
X702228Y247311D01*
X702238Y247351D01*
X702253Y247396D01*
X702258Y247436D01*
X702268Y247476D01*
X702273Y247521D01*
Y247561D01*
X702278Y247606D01*
X702273Y247651D01*
Y247691D01*
X702268Y247736D01*
X702258Y247776D01*
X702253Y247816D01*
X702238Y247861D01*
X702228Y247901D01*
X702213Y247941D01*
X702193Y247981D01*
X702178Y248016D01*
X702158Y248056D01*
X702058Y248196D01*
X702028Y248226D01*
Y249356D01*
X702018Y249481D01*
X701978Y249606D01*
X701918Y249716D01*
X701838Y249816D01*
X701738Y249896D01*
X701628Y249956D01*
X701503Y249996D01*
X701378Y250006D01*
G37*
G36*
G01X706103D02*
X705978Y249996D01*
X705853Y249956D01*
X705743Y249896D01*
X705643Y249816D01*
X705563Y249716D01*
X705503Y249606D01*
X705463Y249481D01*
X705453Y249356D01*
Y248226D01*
X705423Y248196D01*
X705323Y248056D01*
X705303Y248016D01*
X705288Y247981D01*
X705268Y247941D01*
X705253Y247901D01*
X705243Y247861D01*
X705228Y247816D01*
X705223Y247776D01*
X705213Y247736D01*
X705208Y247691D01*
Y247651D01*
X705203Y247606D01*
X705208Y247561D01*
Y247521D01*
X705213Y247476D01*
X705223Y247436D01*
X705228Y247396D01*
X705243Y247351D01*
X705253Y247311D01*
X705268Y247271D01*
X705288Y247231D01*
X705303Y247196D01*
X705323Y247156D01*
X705423Y247016D01*
X705453Y246986D01*
Y243556D01*
X705463Y243431D01*
X705503Y243306D01*
X705563Y243196D01*
X705643Y243096D01*
X705743Y243016D01*
X705853Y242956D01*
X705978Y242916D01*
X706103Y242906D01*
X706228Y242916D01*
X706353Y242956D01*
X706463Y243016D01*
X706563Y243096D01*
X706643Y243196D01*
X706703Y243306D01*
X706743Y243431D01*
X706753Y243556D01*
Y246986D01*
X706783Y247016D01*
X706883Y247156D01*
X706903Y247196D01*
X706918Y247231D01*
X706938Y247271D01*
X706953Y247311D01*
X706963Y247351D01*
X706978Y247396D01*
X706983Y247436D01*
X706993Y247476D01*
X706998Y247521D01*
Y247561D01*
X707003Y247606D01*
X706998Y247651D01*
Y247691D01*
X706993Y247736D01*
X706983Y247776D01*
X706978Y247816D01*
X706963Y247861D01*
X706953Y247901D01*
X706938Y247941D01*
X706918Y247981D01*
X706903Y248016D01*
X706883Y248056D01*
X706783Y248196D01*
X706753Y248226D01*
Y249356D01*
X706743Y249481D01*
X706703Y249606D01*
X706643Y249716D01*
X706563Y249816D01*
X706463Y249896D01*
X706353Y249956D01*
X706228Y249996D01*
X706103Y250006D01*
G37*
G36*
G01X710827D02*
X710702Y249996D01*
X710577Y249956D01*
X710467Y249896D01*
X710367Y249816D01*
X710287Y249716D01*
X710227Y249606D01*
X710187Y249481D01*
X710177Y249356D01*
Y248226D01*
X710147Y248196D01*
X710047Y248056D01*
X710027Y248016D01*
X710012Y247981D01*
X709992Y247941D01*
X709977Y247901D01*
X709967Y247861D01*
X709952Y247816D01*
X709947Y247776D01*
X709937Y247736D01*
X709932Y247691D01*
Y247651D01*
X709927Y247606D01*
X709932Y247561D01*
Y247521D01*
X709937Y247476D01*
X709947Y247436D01*
X709952Y247396D01*
X709967Y247351D01*
X709977Y247311D01*
X709992Y247271D01*
X710012Y247231D01*
X710027Y247196D01*
X710047Y247156D01*
X710147Y247016D01*
X710177Y246986D01*
Y243556D01*
X710187Y243431D01*
X710227Y243306D01*
X710287Y243196D01*
X710367Y243096D01*
X710467Y243016D01*
X710577Y242956D01*
X710702Y242916D01*
X710827Y242906D01*
X710952Y242916D01*
X711077Y242956D01*
X711187Y243016D01*
X711287Y243096D01*
X711367Y243196D01*
X711427Y243306D01*
X711467Y243431D01*
X711477Y243556D01*
Y246986D01*
X711507Y247016D01*
X711607Y247156D01*
X711627Y247196D01*
X711642Y247231D01*
X711662Y247271D01*
X711677Y247311D01*
X711687Y247351D01*
X711702Y247396D01*
X711707Y247436D01*
X711717Y247476D01*
X711722Y247521D01*
Y247561D01*
X711727Y247606D01*
X711722Y247651D01*
Y247691D01*
X711717Y247736D01*
X711707Y247776D01*
X711702Y247816D01*
X711687Y247861D01*
X711677Y247901D01*
X711662Y247941D01*
X711642Y247981D01*
X711627Y248016D01*
X711607Y248056D01*
X711507Y248196D01*
X711477Y248226D01*
Y249356D01*
X711467Y249481D01*
X711427Y249606D01*
X711367Y249716D01*
X711287Y249816D01*
X711187Y249896D01*
X711077Y249956D01*
X710952Y249996D01*
X710827Y250006D01*
G37*
G36*
G01X715551D02*
X715426Y249996D01*
X715301Y249956D01*
X715191Y249896D01*
X715091Y249816D01*
X715011Y249716D01*
X714951Y249606D01*
X714911Y249481D01*
X714901Y249356D01*
Y248226D01*
X714871Y248196D01*
X714771Y248056D01*
X714751Y248016D01*
X714736Y247981D01*
X714716Y247941D01*
X714701Y247901D01*
X714691Y247861D01*
X714676Y247816D01*
X714671Y247776D01*
X714661Y247736D01*
X714656Y247691D01*
Y247651D01*
X714651Y247606D01*
X714656Y247561D01*
Y247521D01*
X714661Y247476D01*
X714671Y247436D01*
X714676Y247396D01*
X714691Y247351D01*
X714701Y247311D01*
X714716Y247271D01*
X714736Y247231D01*
X714751Y247196D01*
X714771Y247156D01*
X714871Y247016D01*
X714901Y246986D01*
Y243556D01*
X714911Y243431D01*
X714951Y243306D01*
X715011Y243196D01*
X715091Y243096D01*
X715191Y243016D01*
X715301Y242956D01*
X715426Y242916D01*
X715551Y242906D01*
X715676Y242916D01*
X715801Y242956D01*
X715911Y243016D01*
X716011Y243096D01*
X716091Y243196D01*
X716151Y243306D01*
X716191Y243431D01*
X716201Y243556D01*
Y246986D01*
X716231Y247016D01*
X716331Y247156D01*
X716351Y247196D01*
X716366Y247231D01*
X716386Y247271D01*
X716401Y247311D01*
X716411Y247351D01*
X716426Y247396D01*
X716431Y247436D01*
X716441Y247476D01*
X716446Y247521D01*
Y247561D01*
X716451Y247606D01*
X716446Y247651D01*
Y247691D01*
X716441Y247736D01*
X716431Y247776D01*
X716426Y247816D01*
X716411Y247861D01*
X716401Y247901D01*
X716386Y247941D01*
X716366Y247981D01*
X716351Y248016D01*
X716331Y248056D01*
X716231Y248196D01*
X716201Y248226D01*
Y249356D01*
X716191Y249481D01*
X716151Y249606D01*
X716091Y249716D01*
X716011Y249816D01*
X715911Y249896D01*
X715801Y249956D01*
X715676Y249996D01*
X715551Y250006D01*
G37*
G36*
G01X720276D02*
X720151Y249996D01*
X720026Y249956D01*
X719916Y249896D01*
X719816Y249816D01*
X719736Y249716D01*
X719676Y249606D01*
X719636Y249481D01*
X719626Y249356D01*
Y248226D01*
X719596Y248196D01*
X719496Y248056D01*
X719476Y248016D01*
X719461Y247981D01*
X719441Y247941D01*
X719426Y247901D01*
X719416Y247861D01*
X719401Y247816D01*
X719396Y247776D01*
X719386Y247736D01*
X719381Y247691D01*
Y247651D01*
X719376Y247606D01*
X719381Y247561D01*
Y247521D01*
X719386Y247476D01*
X719396Y247436D01*
X719401Y247396D01*
X719416Y247351D01*
X719426Y247311D01*
X719441Y247271D01*
X719461Y247231D01*
X719476Y247196D01*
X719496Y247156D01*
X719596Y247016D01*
X719626Y246986D01*
Y243556D01*
X719636Y243431D01*
X719676Y243306D01*
X719736Y243196D01*
X719816Y243096D01*
X719916Y243016D01*
X720026Y242956D01*
X720151Y242916D01*
X720276Y242906D01*
X720401Y242916D01*
X720526Y242956D01*
X720636Y243016D01*
X720736Y243096D01*
X720816Y243196D01*
X720876Y243306D01*
X720916Y243431D01*
X720926Y243556D01*
Y246986D01*
X720956Y247016D01*
X721056Y247156D01*
X721076Y247196D01*
X721091Y247231D01*
X721111Y247271D01*
X721126Y247311D01*
X721136Y247351D01*
X721151Y247396D01*
X721156Y247436D01*
X721166Y247476D01*
X721171Y247521D01*
Y247561D01*
X721176Y247606D01*
X721171Y247651D01*
Y247691D01*
X721166Y247736D01*
X721156Y247776D01*
X721151Y247816D01*
X721136Y247861D01*
X721126Y247901D01*
X721111Y247941D01*
X721091Y247981D01*
X721076Y248016D01*
X721056Y248056D01*
X720956Y248196D01*
X720926Y248226D01*
Y249356D01*
X720916Y249481D01*
X720876Y249606D01*
X720816Y249716D01*
X720736Y249816D01*
X720636Y249896D01*
X720526Y249956D01*
X720401Y249996D01*
X720276Y250006D01*
G37*
G36*
G01X725000D02*
X724875Y249996D01*
X724750Y249956D01*
X724640Y249896D01*
X724540Y249816D01*
X724460Y249716D01*
X724400Y249606D01*
X724360Y249481D01*
X724350Y249356D01*
Y248226D01*
X724320Y248196D01*
X724220Y248056D01*
X724200Y248016D01*
X724185Y247981D01*
X724165Y247941D01*
X724150Y247901D01*
X724140Y247861D01*
X724125Y247816D01*
X724120Y247776D01*
X724110Y247736D01*
X724105Y247691D01*
Y247651D01*
X724100Y247606D01*
X724105Y247561D01*
Y247521D01*
X724110Y247476D01*
X724120Y247436D01*
X724125Y247396D01*
X724140Y247351D01*
X724150Y247311D01*
X724165Y247271D01*
X724185Y247231D01*
X724200Y247196D01*
X724220Y247156D01*
X724320Y247016D01*
X724350Y246986D01*
Y243556D01*
X724360Y243431D01*
X724400Y243306D01*
X724460Y243196D01*
X724540Y243096D01*
X724640Y243016D01*
X724750Y242956D01*
X724875Y242916D01*
X725000Y242906D01*
X725125Y242916D01*
X725250Y242956D01*
X725360Y243016D01*
X725460Y243096D01*
X725540Y243196D01*
X725600Y243306D01*
X725640Y243431D01*
X725650Y243556D01*
Y246986D01*
X725680Y247016D01*
X725780Y247156D01*
X725800Y247196D01*
X725815Y247231D01*
X725835Y247271D01*
X725850Y247311D01*
X725860Y247351D01*
X725875Y247396D01*
X725880Y247436D01*
X725890Y247476D01*
X725895Y247521D01*
Y247561D01*
X725900Y247606D01*
X725895Y247651D01*
Y247691D01*
X725890Y247736D01*
X725880Y247776D01*
X725875Y247816D01*
X725860Y247861D01*
X725850Y247901D01*
X725835Y247941D01*
X725815Y247981D01*
X725800Y248016D01*
X725780Y248056D01*
X725680Y248196D01*
X725650Y248226D01*
Y249356D01*
X725640Y249481D01*
X725600Y249606D01*
X725540Y249716D01*
X725460Y249816D01*
X725360Y249896D01*
X725250Y249956D01*
X725125Y249996D01*
X725000Y250006D01*
G37*
G36*
G01X729725D02*
X729600Y249996D01*
X729475Y249956D01*
X729365Y249896D01*
X729265Y249816D01*
X729185Y249716D01*
X729125Y249606D01*
X729085Y249481D01*
X729075Y249356D01*
Y248226D01*
X729045Y248196D01*
X728945Y248056D01*
X728925Y248016D01*
X728910Y247981D01*
X728890Y247941D01*
X728875Y247901D01*
X728865Y247861D01*
X728850Y247816D01*
X728845Y247776D01*
X728835Y247736D01*
X728830Y247691D01*
Y247651D01*
X728825Y247606D01*
X728830Y247561D01*
Y247521D01*
X728835Y247476D01*
X728845Y247436D01*
X728850Y247396D01*
X728865Y247351D01*
X728875Y247311D01*
X728890Y247271D01*
X728910Y247231D01*
X728925Y247196D01*
X728945Y247156D01*
X729045Y247016D01*
X729075Y246986D01*
Y243556D01*
X729085Y243431D01*
X729125Y243306D01*
X729185Y243196D01*
X729265Y243096D01*
X729365Y243016D01*
X729475Y242956D01*
X729600Y242916D01*
X729725Y242906D01*
X729850Y242916D01*
X729975Y242956D01*
X730085Y243016D01*
X730185Y243096D01*
X730265Y243196D01*
X730325Y243306D01*
X730365Y243431D01*
X730375Y243556D01*
Y246986D01*
X730405Y247016D01*
X730505Y247156D01*
X730525Y247196D01*
X730540Y247231D01*
X730560Y247271D01*
X730575Y247311D01*
X730585Y247351D01*
X730600Y247396D01*
X730605Y247436D01*
X730615Y247476D01*
X730620Y247521D01*
Y247561D01*
X730625Y247606D01*
X730620Y247651D01*
Y247691D01*
X730615Y247736D01*
X730605Y247776D01*
X730600Y247816D01*
X730585Y247861D01*
X730575Y247901D01*
X730560Y247941D01*
X730540Y247981D01*
X730525Y248016D01*
X730505Y248056D01*
X730405Y248196D01*
X730375Y248226D01*
Y249356D01*
X730365Y249481D01*
X730325Y249606D01*
X730265Y249716D01*
X730185Y249816D01*
X730085Y249896D01*
X729975Y249956D01*
X729850Y249996D01*
X729725Y250006D01*
G37*
G36*
G01X734449D02*
X734324Y249996D01*
X734199Y249956D01*
X734089Y249896D01*
X733989Y249816D01*
X733909Y249716D01*
X733849Y249606D01*
X733809Y249481D01*
X733799Y249356D01*
Y248226D01*
X733769Y248196D01*
X733669Y248056D01*
X733649Y248016D01*
X733634Y247981D01*
X733614Y247941D01*
X733599Y247901D01*
X733589Y247861D01*
X733574Y247816D01*
X733569Y247776D01*
X733559Y247736D01*
X733554Y247691D01*
Y247651D01*
X733549Y247606D01*
X733554Y247561D01*
Y247521D01*
X733559Y247476D01*
X733569Y247436D01*
X733574Y247396D01*
X733589Y247351D01*
X733599Y247311D01*
X733614Y247271D01*
X733634Y247231D01*
X733649Y247196D01*
X733669Y247156D01*
X733769Y247016D01*
X733799Y246986D01*
Y243556D01*
X733809Y243431D01*
X733849Y243306D01*
X733909Y243196D01*
X733989Y243096D01*
X734089Y243016D01*
X734199Y242956D01*
X734324Y242916D01*
X734449Y242906D01*
X734574Y242916D01*
X734699Y242956D01*
X734809Y243016D01*
X734909Y243096D01*
X734989Y243196D01*
X735049Y243306D01*
X735089Y243431D01*
X735099Y243556D01*
Y246986D01*
X735129Y247016D01*
X735229Y247156D01*
X735249Y247196D01*
X735264Y247231D01*
X735284Y247271D01*
X735299Y247311D01*
X735309Y247351D01*
X735324Y247396D01*
X735329Y247436D01*
X735339Y247476D01*
X735344Y247521D01*
Y247561D01*
X735349Y247606D01*
X735344Y247651D01*
Y247691D01*
X735339Y247736D01*
X735329Y247776D01*
X735324Y247816D01*
X735309Y247861D01*
X735299Y247901D01*
X735284Y247941D01*
X735264Y247981D01*
X735249Y248016D01*
X735229Y248056D01*
X735129Y248196D01*
X735099Y248226D01*
Y249356D01*
X735089Y249481D01*
X735049Y249606D01*
X734989Y249716D01*
X734909Y249816D01*
X734809Y249896D01*
X734699Y249956D01*
X734574Y249996D01*
X734449Y250006D01*
G37*
G36*
G01X739173D02*
X739048Y249996D01*
X738923Y249956D01*
X738813Y249896D01*
X738713Y249816D01*
X738633Y249716D01*
X738573Y249606D01*
X738533Y249481D01*
X738523Y249356D01*
Y248226D01*
X738493Y248196D01*
X738393Y248056D01*
X738373Y248016D01*
X738358Y247981D01*
X738338Y247941D01*
X738323Y247901D01*
X738313Y247861D01*
X738298Y247816D01*
X738293Y247776D01*
X738283Y247736D01*
X738278Y247691D01*
Y247651D01*
X738273Y247606D01*
X738278Y247561D01*
Y247521D01*
X738283Y247476D01*
X738293Y247436D01*
X738298Y247396D01*
X738313Y247351D01*
X738323Y247311D01*
X738338Y247271D01*
X738358Y247231D01*
X738373Y247196D01*
X738393Y247156D01*
X738493Y247016D01*
X738523Y246986D01*
Y243556D01*
X738533Y243431D01*
X738573Y243306D01*
X738633Y243196D01*
X738713Y243096D01*
X738813Y243016D01*
X738923Y242956D01*
X739048Y242916D01*
X739173Y242906D01*
X739298Y242916D01*
X739423Y242956D01*
X739533Y243016D01*
X739633Y243096D01*
X739713Y243196D01*
X739773Y243306D01*
X739813Y243431D01*
X739823Y243556D01*
Y246986D01*
X739853Y247016D01*
X739953Y247156D01*
X739973Y247196D01*
X739988Y247231D01*
X740008Y247271D01*
X740023Y247311D01*
X740033Y247351D01*
X740048Y247396D01*
X740053Y247436D01*
X740063Y247476D01*
X740068Y247521D01*
Y247561D01*
X740073Y247606D01*
X740068Y247651D01*
Y247691D01*
X740063Y247736D01*
X740053Y247776D01*
X740048Y247816D01*
X740033Y247861D01*
X740023Y247901D01*
X740008Y247941D01*
X739988Y247981D01*
X739973Y248016D01*
X739953Y248056D01*
X739853Y248196D01*
X739823Y248226D01*
Y249356D01*
X739813Y249481D01*
X739773Y249606D01*
X739713Y249716D01*
X739633Y249816D01*
X739533Y249896D01*
X739423Y249956D01*
X739298Y249996D01*
X739173Y250006D01*
G37*
G36*
G01X743898D02*
X743773Y249996D01*
X743648Y249956D01*
X743538Y249896D01*
X743438Y249816D01*
X743358Y249716D01*
X743298Y249606D01*
X743258Y249481D01*
X743248Y249356D01*
Y248226D01*
X743218Y248196D01*
X743118Y248056D01*
X743098Y248016D01*
X743083Y247981D01*
X743063Y247941D01*
X743048Y247901D01*
X743038Y247861D01*
X743023Y247816D01*
X743018Y247776D01*
X743008Y247736D01*
X743003Y247691D01*
Y247651D01*
X742998Y247606D01*
X743003Y247561D01*
Y247521D01*
X743008Y247476D01*
X743018Y247436D01*
X743023Y247396D01*
X743038Y247351D01*
X743048Y247311D01*
X743063Y247271D01*
X743083Y247231D01*
X743098Y247196D01*
X743118Y247156D01*
X743218Y247016D01*
X743248Y246986D01*
Y243556D01*
X743258Y243431D01*
X743298Y243306D01*
X743358Y243196D01*
X743438Y243096D01*
X743538Y243016D01*
X743648Y242956D01*
X743773Y242916D01*
X743898Y242906D01*
X744023Y242916D01*
X744148Y242956D01*
X744258Y243016D01*
X744358Y243096D01*
X744438Y243196D01*
X744498Y243306D01*
X744538Y243431D01*
X744548Y243556D01*
Y246986D01*
X744578Y247016D01*
X744678Y247156D01*
X744698Y247196D01*
X744713Y247231D01*
X744733Y247271D01*
X744748Y247311D01*
X744758Y247351D01*
X744773Y247396D01*
X744778Y247436D01*
X744788Y247476D01*
X744793Y247521D01*
Y247561D01*
X744798Y247606D01*
X744793Y247651D01*
Y247691D01*
X744788Y247736D01*
X744778Y247776D01*
X744773Y247816D01*
X744758Y247861D01*
X744748Y247901D01*
X744733Y247941D01*
X744713Y247981D01*
X744698Y248016D01*
X744678Y248056D01*
X744578Y248196D01*
X744548Y248226D01*
Y249356D01*
X744538Y249481D01*
X744498Y249606D01*
X744438Y249716D01*
X744358Y249816D01*
X744258Y249896D01*
X744148Y249956D01*
X744023Y249996D01*
X743898Y250006D01*
G37*
G36*
G01X748622D02*
X748497Y249996D01*
X748372Y249956D01*
X748262Y249896D01*
X748162Y249816D01*
X748082Y249716D01*
X748022Y249606D01*
X747982Y249481D01*
X747972Y249356D01*
Y248226D01*
X747942Y248196D01*
X747842Y248056D01*
X747822Y248016D01*
X747807Y247981D01*
X747787Y247941D01*
X747772Y247901D01*
X747762Y247861D01*
X747747Y247816D01*
X747742Y247776D01*
X747732Y247736D01*
X747727Y247691D01*
Y247651D01*
X747722Y247606D01*
X747727Y247561D01*
Y247521D01*
X747732Y247476D01*
X747742Y247436D01*
X747747Y247396D01*
X747762Y247351D01*
X747772Y247311D01*
X747787Y247271D01*
X747807Y247231D01*
X747822Y247196D01*
X747842Y247156D01*
X747942Y247016D01*
X747972Y246986D01*
Y243556D01*
X747982Y243431D01*
X748022Y243306D01*
X748082Y243196D01*
X748162Y243096D01*
X748262Y243016D01*
X748372Y242956D01*
X748497Y242916D01*
X748622Y242906D01*
X748747Y242916D01*
X748872Y242956D01*
X748982Y243016D01*
X749082Y243096D01*
X749162Y243196D01*
X749222Y243306D01*
X749262Y243431D01*
X749272Y243556D01*
Y246986D01*
X749302Y247016D01*
X749402Y247156D01*
X749422Y247196D01*
X749437Y247231D01*
X749457Y247271D01*
X749472Y247311D01*
X749482Y247351D01*
X749497Y247396D01*
X749502Y247436D01*
X749512Y247476D01*
X749517Y247521D01*
Y247561D01*
X749522Y247606D01*
X749517Y247651D01*
Y247691D01*
X749512Y247736D01*
X749502Y247776D01*
X749497Y247816D01*
X749482Y247861D01*
X749472Y247901D01*
X749457Y247941D01*
X749437Y247981D01*
X749422Y248016D01*
X749402Y248056D01*
X749302Y248196D01*
X749272Y248226D01*
Y249356D01*
X749262Y249481D01*
X749222Y249606D01*
X749162Y249716D01*
X749082Y249816D01*
X748982Y249896D01*
X748872Y249956D01*
X748747Y249996D01*
X748622Y250006D01*
G37*
G54D57*
X346500Y67700D03*
Y78300D03*
X365000Y260700D03*
Y271300D03*
X777000Y146900D03*
Y157500D03*
G54D48*
X271795Y79984D03*
Y78016D03*
X282205D03*
Y79984D03*
G54D39*
X169485Y198021D03*
Y196446D03*
Y194871D03*
Y193296D03*
Y191722D03*
Y190147D03*
Y188572D03*
Y186997D03*
Y185422D03*
Y199596D03*
X191607Y185422D03*
Y186997D03*
Y188572D03*
Y190147D03*
Y191722D03*
Y193296D03*
Y194871D03*
Y196446D03*
Y198021D03*
Y199596D03*
G54D84*
X804400Y212800D03*
X794600D03*
G54D85*
G01X10636Y-27865D02*
G02I-12000J0D01*
G01X14636D02*
X-17364D01*
G01X5486D02*
G02I-6850J0D01*
G01X-1364Y-43865D02*
Y-11865D01*
G01X14636Y-43865D02*
Y-123865D01*
G01D02*
X1309236D01*
G01X14636Y-79365D02*
X1309236D01*
G01X14636Y-43865D02*
X1309236D01*
G01X521736D02*
Y-123865D01*
G01X659236Y-43865D02*
Y-123865D01*
G01X774236Y-43865D02*
Y-123865D01*
G01X941736Y-43865D02*
Y-123865D01*
G01X1111736Y-43865D02*
Y-123865D01*
G01X1309236Y-43865D02*
Y-123865D01*
G01X1341236Y-27865D02*
X1309236D01*
G01X1337236D02*
G02I-12000J0D01*
G01X1332086D02*
G02I-6850J0D01*
G01X1325236Y-43865D02*
Y-11865D01*
G54D67*
X439441Y260531D03*
Y264469D03*
G54D49*
X270000Y97650D03*
G36*
G01X499410Y282290D02*
X499285Y282280D01*
X499160Y282240D01*
X499050Y282180D01*
X498950Y282100D01*
X498870Y282000D01*
X498810Y281890D01*
X498770Y281765D01*
X498760Y281640D01*
Y279210D01*
X498730Y279180D01*
X498630Y279040D01*
X498610Y279000D01*
X498595Y278965D01*
X498575Y278925D01*
X498560Y278885D01*
X498550Y278845D01*
X498535Y278800D01*
X498530Y278760D01*
X498520Y278720D01*
X498515Y278675D01*
Y278635D01*
X498510Y278590D01*
X498515Y278545D01*
Y278505D01*
X498520Y278460D01*
X498530Y278420D01*
X498535Y278380D01*
X498550Y278335D01*
X498560Y278295D01*
X498575Y278255D01*
X498595Y278215D01*
X498610Y278180D01*
X498630Y278140D01*
X498730Y278000D01*
X498760Y277970D01*
Y275840D01*
X498770Y275715D01*
X498810Y275590D01*
X498870Y275480D01*
X498950Y275380D01*
X499050Y275300D01*
X499160Y275240D01*
X499285Y275200D01*
X499410Y275190D01*
X499535Y275200D01*
X499660Y275240D01*
X499770Y275300D01*
X499870Y275380D01*
X499950Y275480D01*
X500010Y275590D01*
X500050Y275715D01*
X500060Y275840D01*
Y277965D01*
X500090Y277995D01*
X500115Y278030D01*
X500145Y278065D01*
X500165Y278100D01*
X500190Y278135D01*
X500230Y278215D01*
X500275Y278335D01*
X500285Y278375D01*
X500295Y278420D01*
X500300Y278460D01*
X500310Y278505D01*
Y278675D01*
X500300Y278720D01*
X500295Y278760D01*
X500285Y278805D01*
X500275Y278845D01*
X500230Y278965D01*
X500190Y279045D01*
X500165Y279080D01*
X500145Y279115D01*
X500115Y279150D01*
X500090Y279185D01*
X500060Y279215D01*
Y281640D01*
X500050Y281765D01*
X500010Y281890D01*
X499950Y282000D01*
X499870Y282100D01*
X499770Y282180D01*
X499660Y282240D01*
X499535Y282280D01*
X499410Y282290D01*
G37*
G36*
G01X504134D02*
X504009Y282280D01*
X503884Y282240D01*
X503774Y282180D01*
X503674Y282100D01*
X503594Y282000D01*
X503534Y281890D01*
X503494Y281765D01*
X503484Y281640D01*
Y279210D01*
X503454Y279180D01*
X503354Y279040D01*
X503334Y279000D01*
X503319Y278965D01*
X503299Y278925D01*
X503284Y278885D01*
X503274Y278845D01*
X503259Y278800D01*
X503254Y278760D01*
X503244Y278720D01*
X503239Y278675D01*
Y278635D01*
X503234Y278590D01*
X503239Y278545D01*
Y278505D01*
X503244Y278460D01*
X503254Y278420D01*
X503259Y278380D01*
X503274Y278335D01*
X503284Y278295D01*
X503299Y278255D01*
X503319Y278215D01*
X503334Y278180D01*
X503354Y278140D01*
X503454Y278000D01*
X503484Y277970D01*
Y275840D01*
X503494Y275715D01*
X503534Y275590D01*
X503594Y275480D01*
X503674Y275380D01*
X503774Y275300D01*
X503884Y275240D01*
X504009Y275200D01*
X504134Y275190D01*
X504259Y275200D01*
X504384Y275240D01*
X504494Y275300D01*
X504594Y275380D01*
X504674Y275480D01*
X504734Y275590D01*
X504774Y275715D01*
X504784Y275840D01*
Y277965D01*
X504814Y277995D01*
X504839Y278030D01*
X504869Y278065D01*
X504889Y278100D01*
X504914Y278135D01*
X504954Y278215D01*
X504999Y278335D01*
X505009Y278375D01*
X505019Y278420D01*
X505024Y278460D01*
X505034Y278505D01*
Y278675D01*
X505024Y278720D01*
X505019Y278760D01*
X505009Y278805D01*
X504999Y278845D01*
X504954Y278965D01*
X504914Y279045D01*
X504889Y279080D01*
X504869Y279115D01*
X504839Y279150D01*
X504814Y279185D01*
X504784Y279215D01*
Y281640D01*
X504774Y281765D01*
X504734Y281890D01*
X504674Y282000D01*
X504594Y282100D01*
X504494Y282180D01*
X504384Y282240D01*
X504259Y282280D01*
X504134Y282290D01*
G37*
G36*
G01X508859D02*
X508734Y282280D01*
X508609Y282240D01*
X508499Y282180D01*
X508399Y282100D01*
X508319Y282000D01*
X508259Y281890D01*
X508219Y281765D01*
X508209Y281640D01*
Y279210D01*
X508179Y279180D01*
X508079Y279040D01*
X508059Y279000D01*
X508044Y278965D01*
X508024Y278925D01*
X508009Y278885D01*
X507999Y278845D01*
X507984Y278800D01*
X507979Y278760D01*
X507969Y278720D01*
X507964Y278675D01*
Y278635D01*
X507959Y278590D01*
X507964Y278545D01*
Y278505D01*
X507969Y278460D01*
X507979Y278420D01*
X507984Y278380D01*
X507999Y278335D01*
X508009Y278295D01*
X508024Y278255D01*
X508044Y278215D01*
X508059Y278180D01*
X508079Y278140D01*
X508179Y278000D01*
X508209Y277970D01*
Y275840D01*
X508219Y275715D01*
X508259Y275590D01*
X508319Y275480D01*
X508399Y275380D01*
X508499Y275300D01*
X508609Y275240D01*
X508734Y275200D01*
X508859Y275190D01*
X508984Y275200D01*
X509109Y275240D01*
X509219Y275300D01*
X509319Y275380D01*
X509399Y275480D01*
X509459Y275590D01*
X509499Y275715D01*
X509509Y275840D01*
Y277965D01*
X509539Y277995D01*
X509564Y278030D01*
X509594Y278065D01*
X509614Y278100D01*
X509639Y278135D01*
X509679Y278215D01*
X509724Y278335D01*
X509734Y278375D01*
X509744Y278420D01*
X509749Y278460D01*
X509759Y278505D01*
Y278675D01*
X509749Y278720D01*
X509744Y278760D01*
X509734Y278805D01*
X509724Y278845D01*
X509679Y278965D01*
X509639Y279045D01*
X509614Y279080D01*
X509594Y279115D01*
X509564Y279150D01*
X509539Y279185D01*
X509509Y279215D01*
Y281640D01*
X509499Y281765D01*
X509459Y281890D01*
X509399Y282000D01*
X509319Y282100D01*
X509219Y282180D01*
X509109Y282240D01*
X508984Y282280D01*
X508859Y282290D01*
G37*
G36*
G01X513583D02*
X513458Y282280D01*
X513333Y282240D01*
X513223Y282180D01*
X513123Y282100D01*
X513043Y282000D01*
X512983Y281890D01*
X512943Y281765D01*
X512933Y281640D01*
Y279210D01*
X512903Y279180D01*
X512803Y279040D01*
X512783Y279000D01*
X512768Y278965D01*
X512748Y278925D01*
X512733Y278885D01*
X512723Y278845D01*
X512708Y278800D01*
X512703Y278760D01*
X512693Y278720D01*
X512688Y278675D01*
Y278635D01*
X512683Y278590D01*
X512688Y278545D01*
Y278505D01*
X512693Y278460D01*
X512703Y278420D01*
X512708Y278380D01*
X512723Y278335D01*
X512733Y278295D01*
X512748Y278255D01*
X512768Y278215D01*
X512783Y278180D01*
X512803Y278140D01*
X512903Y278000D01*
X512933Y277970D01*
Y275840D01*
X512943Y275715D01*
X512983Y275590D01*
X513043Y275480D01*
X513123Y275380D01*
X513223Y275300D01*
X513333Y275240D01*
X513458Y275200D01*
X513583Y275190D01*
X513708Y275200D01*
X513833Y275240D01*
X513943Y275300D01*
X514043Y275380D01*
X514123Y275480D01*
X514183Y275590D01*
X514223Y275715D01*
X514233Y275840D01*
Y277965D01*
X514263Y277995D01*
X514288Y278030D01*
X514318Y278065D01*
X514338Y278100D01*
X514363Y278135D01*
X514403Y278215D01*
X514448Y278335D01*
X514458Y278375D01*
X514468Y278420D01*
X514473Y278460D01*
X514483Y278505D01*
Y278675D01*
X514473Y278720D01*
X514468Y278760D01*
X514458Y278805D01*
X514448Y278845D01*
X514403Y278965D01*
X514363Y279045D01*
X514338Y279080D01*
X514318Y279115D01*
X514288Y279150D01*
X514263Y279185D01*
X514233Y279215D01*
Y281640D01*
X514223Y281765D01*
X514183Y281890D01*
X514123Y282000D01*
X514043Y282100D01*
X513943Y282180D01*
X513833Y282240D01*
X513708Y282280D01*
X513583Y282290D01*
G37*
G36*
G01X518307D02*
X518182Y282280D01*
X518057Y282240D01*
X517947Y282180D01*
X517847Y282100D01*
X517767Y282000D01*
X517707Y281890D01*
X517667Y281765D01*
X517657Y281640D01*
Y279210D01*
X517627Y279180D01*
X517527Y279040D01*
X517507Y279000D01*
X517492Y278965D01*
X517472Y278925D01*
X517457Y278885D01*
X517447Y278845D01*
X517432Y278800D01*
X517427Y278760D01*
X517417Y278720D01*
X517412Y278675D01*
Y278635D01*
X517407Y278590D01*
X517412Y278545D01*
Y278505D01*
X517417Y278460D01*
X517427Y278420D01*
X517432Y278380D01*
X517447Y278335D01*
X517457Y278295D01*
X517472Y278255D01*
X517492Y278215D01*
X517507Y278180D01*
X517527Y278140D01*
X517627Y278000D01*
X517657Y277970D01*
Y275840D01*
X517667Y275715D01*
X517707Y275590D01*
X517767Y275480D01*
X517847Y275380D01*
X517947Y275300D01*
X518057Y275240D01*
X518182Y275200D01*
X518307Y275190D01*
X518432Y275200D01*
X518557Y275240D01*
X518667Y275300D01*
X518767Y275380D01*
X518847Y275480D01*
X518907Y275590D01*
X518947Y275715D01*
X518957Y275840D01*
Y277965D01*
X518987Y277995D01*
X519012Y278030D01*
X519042Y278065D01*
X519062Y278100D01*
X519087Y278135D01*
X519127Y278215D01*
X519172Y278335D01*
X519182Y278375D01*
X519192Y278420D01*
X519197Y278460D01*
X519207Y278505D01*
Y278675D01*
X519197Y278720D01*
X519192Y278760D01*
X519182Y278805D01*
X519172Y278845D01*
X519127Y278965D01*
X519087Y279045D01*
X519062Y279080D01*
X519042Y279115D01*
X519012Y279150D01*
X518987Y279185D01*
X518957Y279215D01*
Y281640D01*
X518947Y281765D01*
X518907Y281890D01*
X518847Y282000D01*
X518767Y282100D01*
X518667Y282180D01*
X518557Y282240D01*
X518432Y282280D01*
X518307Y282290D01*
G37*
G36*
G01X523032D02*
X522907Y282280D01*
X522782Y282240D01*
X522672Y282180D01*
X522572Y282100D01*
X522492Y282000D01*
X522432Y281890D01*
X522392Y281765D01*
X522382Y281640D01*
Y279210D01*
X522352Y279180D01*
X522252Y279040D01*
X522232Y279000D01*
X522217Y278965D01*
X522197Y278925D01*
X522182Y278885D01*
X522172Y278845D01*
X522157Y278800D01*
X522152Y278760D01*
X522142Y278720D01*
X522137Y278675D01*
Y278635D01*
X522132Y278590D01*
X522137Y278545D01*
Y278505D01*
X522142Y278460D01*
X522152Y278420D01*
X522157Y278380D01*
X522172Y278335D01*
X522182Y278295D01*
X522197Y278255D01*
X522217Y278215D01*
X522232Y278180D01*
X522252Y278140D01*
X522352Y278000D01*
X522382Y277970D01*
Y275840D01*
X522392Y275715D01*
X522432Y275590D01*
X522492Y275480D01*
X522572Y275380D01*
X522672Y275300D01*
X522782Y275240D01*
X522907Y275200D01*
X523032Y275190D01*
X523157Y275200D01*
X523282Y275240D01*
X523392Y275300D01*
X523492Y275380D01*
X523572Y275480D01*
X523632Y275590D01*
X523672Y275715D01*
X523682Y275840D01*
Y277965D01*
X523712Y277995D01*
X523737Y278030D01*
X523767Y278065D01*
X523787Y278100D01*
X523812Y278135D01*
X523852Y278215D01*
X523897Y278335D01*
X523907Y278375D01*
X523917Y278420D01*
X523922Y278460D01*
X523932Y278505D01*
Y278675D01*
X523922Y278720D01*
X523917Y278760D01*
X523907Y278805D01*
X523897Y278845D01*
X523852Y278965D01*
X523812Y279045D01*
X523787Y279080D01*
X523767Y279115D01*
X523737Y279150D01*
X523712Y279185D01*
X523682Y279215D01*
Y281640D01*
X523672Y281765D01*
X523632Y281890D01*
X523572Y282000D01*
X523492Y282100D01*
X523392Y282180D01*
X523282Y282240D01*
X523157Y282280D01*
X523032Y282290D01*
G37*
G36*
G01X527756D02*
X527631Y282280D01*
X527506Y282240D01*
X527396Y282180D01*
X527296Y282100D01*
X527216Y282000D01*
X527156Y281890D01*
X527116Y281765D01*
X527106Y281640D01*
Y279210D01*
X527076Y279180D01*
X526976Y279040D01*
X526956Y279000D01*
X526941Y278965D01*
X526921Y278925D01*
X526906Y278885D01*
X526896Y278845D01*
X526881Y278800D01*
X526876Y278760D01*
X526866Y278720D01*
X526861Y278675D01*
Y278635D01*
X526856Y278590D01*
X526861Y278545D01*
Y278505D01*
X526866Y278460D01*
X526876Y278420D01*
X526881Y278380D01*
X526896Y278335D01*
X526906Y278295D01*
X526921Y278255D01*
X526941Y278215D01*
X526956Y278180D01*
X526976Y278140D01*
X527076Y278000D01*
X527106Y277970D01*
Y275840D01*
X527116Y275715D01*
X527156Y275590D01*
X527216Y275480D01*
X527296Y275380D01*
X527396Y275300D01*
X527506Y275240D01*
X527631Y275200D01*
X527756Y275190D01*
X527881Y275200D01*
X528006Y275240D01*
X528116Y275300D01*
X528216Y275380D01*
X528296Y275480D01*
X528356Y275590D01*
X528396Y275715D01*
X528406Y275840D01*
Y277965D01*
X528436Y277995D01*
X528461Y278030D01*
X528491Y278065D01*
X528511Y278100D01*
X528536Y278135D01*
X528576Y278215D01*
X528621Y278335D01*
X528631Y278375D01*
X528641Y278420D01*
X528646Y278460D01*
X528656Y278505D01*
Y278675D01*
X528646Y278720D01*
X528641Y278760D01*
X528631Y278805D01*
X528621Y278845D01*
X528576Y278965D01*
X528536Y279045D01*
X528511Y279080D01*
X528491Y279115D01*
X528461Y279150D01*
X528436Y279185D01*
X528406Y279215D01*
Y281640D01*
X528396Y281765D01*
X528356Y281890D01*
X528296Y282000D01*
X528216Y282100D01*
X528116Y282180D01*
X528006Y282240D01*
X527881Y282280D01*
X527756Y282290D01*
G37*
G36*
G01X532481D02*
X532356Y282280D01*
X532231Y282240D01*
X532121Y282180D01*
X532021Y282100D01*
X531941Y282000D01*
X531881Y281890D01*
X531841Y281765D01*
X531831Y281640D01*
Y279210D01*
X531801Y279180D01*
X531701Y279040D01*
X531681Y279000D01*
X531666Y278965D01*
X531646Y278925D01*
X531631Y278885D01*
X531621Y278845D01*
X531606Y278800D01*
X531601Y278760D01*
X531591Y278720D01*
X531586Y278675D01*
Y278635D01*
X531581Y278590D01*
X531586Y278545D01*
Y278505D01*
X531591Y278460D01*
X531601Y278420D01*
X531606Y278380D01*
X531621Y278335D01*
X531631Y278295D01*
X531646Y278255D01*
X531666Y278215D01*
X531681Y278180D01*
X531701Y278140D01*
X531801Y278000D01*
X531831Y277970D01*
Y275840D01*
X531841Y275715D01*
X531881Y275590D01*
X531941Y275480D01*
X532021Y275380D01*
X532121Y275300D01*
X532231Y275240D01*
X532356Y275200D01*
X532481Y275190D01*
X532606Y275200D01*
X532731Y275240D01*
X532841Y275300D01*
X532941Y275380D01*
X533021Y275480D01*
X533081Y275590D01*
X533121Y275715D01*
X533131Y275840D01*
Y277965D01*
X533161Y277995D01*
X533186Y278030D01*
X533216Y278065D01*
X533236Y278100D01*
X533261Y278135D01*
X533301Y278215D01*
X533346Y278335D01*
X533356Y278375D01*
X533366Y278420D01*
X533371Y278460D01*
X533381Y278505D01*
Y278675D01*
X533371Y278720D01*
X533366Y278760D01*
X533356Y278805D01*
X533346Y278845D01*
X533301Y278965D01*
X533261Y279045D01*
X533236Y279080D01*
X533216Y279115D01*
X533186Y279150D01*
X533161Y279185D01*
X533131Y279215D01*
Y281640D01*
X533121Y281765D01*
X533081Y281890D01*
X533021Y282000D01*
X532941Y282100D01*
X532841Y282180D01*
X532731Y282240D01*
X532606Y282280D01*
X532481Y282290D01*
G37*
G36*
G01X537205D02*
X537080Y282280D01*
X536955Y282240D01*
X536845Y282180D01*
X536745Y282100D01*
X536665Y282000D01*
X536605Y281890D01*
X536565Y281765D01*
X536555Y281640D01*
Y279210D01*
X536525Y279180D01*
X536425Y279040D01*
X536405Y279000D01*
X536390Y278965D01*
X536370Y278925D01*
X536355Y278885D01*
X536345Y278845D01*
X536330Y278800D01*
X536325Y278760D01*
X536315Y278720D01*
X536310Y278675D01*
Y278635D01*
X536305Y278590D01*
X536310Y278545D01*
Y278505D01*
X536315Y278460D01*
X536325Y278420D01*
X536330Y278380D01*
X536345Y278335D01*
X536355Y278295D01*
X536370Y278255D01*
X536390Y278215D01*
X536405Y278180D01*
X536425Y278140D01*
X536525Y278000D01*
X536555Y277970D01*
Y275840D01*
X536565Y275715D01*
X536605Y275590D01*
X536665Y275480D01*
X536745Y275380D01*
X536845Y275300D01*
X536955Y275240D01*
X537080Y275200D01*
X537205Y275190D01*
X537330Y275200D01*
X537455Y275240D01*
X537565Y275300D01*
X537665Y275380D01*
X537745Y275480D01*
X537805Y275590D01*
X537845Y275715D01*
X537855Y275840D01*
Y277965D01*
X537885Y277995D01*
X537910Y278030D01*
X537940Y278065D01*
X537960Y278100D01*
X537985Y278135D01*
X538025Y278215D01*
X538070Y278335D01*
X538080Y278375D01*
X538090Y278420D01*
X538095Y278460D01*
X538105Y278505D01*
Y278675D01*
X538095Y278720D01*
X538090Y278760D01*
X538080Y278805D01*
X538070Y278845D01*
X538025Y278965D01*
X537985Y279045D01*
X537960Y279080D01*
X537940Y279115D01*
X537910Y279150D01*
X537885Y279185D01*
X537855Y279215D01*
Y281640D01*
X537845Y281765D01*
X537805Y281890D01*
X537745Y282000D01*
X537665Y282100D01*
X537565Y282180D01*
X537455Y282240D01*
X537330Y282280D01*
X537205Y282290D01*
G37*
G36*
G01X541929D02*
X541804Y282280D01*
X541679Y282240D01*
X541569Y282180D01*
X541469Y282100D01*
X541389Y282000D01*
X541329Y281890D01*
X541289Y281765D01*
X541279Y281640D01*
Y279210D01*
X541249Y279180D01*
X541149Y279040D01*
X541129Y279000D01*
X541114Y278965D01*
X541094Y278925D01*
X541079Y278885D01*
X541069Y278845D01*
X541054Y278800D01*
X541049Y278760D01*
X541039Y278720D01*
X541034Y278675D01*
Y278635D01*
X541029Y278590D01*
X541034Y278545D01*
Y278505D01*
X541039Y278460D01*
X541049Y278420D01*
X541054Y278380D01*
X541069Y278335D01*
X541079Y278295D01*
X541094Y278255D01*
X541114Y278215D01*
X541129Y278180D01*
X541149Y278140D01*
X541249Y278000D01*
X541279Y277970D01*
Y275840D01*
X541289Y275715D01*
X541329Y275590D01*
X541389Y275480D01*
X541469Y275380D01*
X541569Y275300D01*
X541679Y275240D01*
X541804Y275200D01*
X541929Y275190D01*
X542054Y275200D01*
X542179Y275240D01*
X542289Y275300D01*
X542389Y275380D01*
X542469Y275480D01*
X542529Y275590D01*
X542569Y275715D01*
X542579Y275840D01*
Y277965D01*
X542609Y277995D01*
X542634Y278030D01*
X542664Y278065D01*
X542684Y278100D01*
X542709Y278135D01*
X542749Y278215D01*
X542794Y278335D01*
X542804Y278375D01*
X542814Y278420D01*
X542819Y278460D01*
X542829Y278505D01*
Y278675D01*
X542819Y278720D01*
X542814Y278760D01*
X542804Y278805D01*
X542794Y278845D01*
X542749Y278965D01*
X542709Y279045D01*
X542684Y279080D01*
X542664Y279115D01*
X542634Y279150D01*
X542609Y279185D01*
X542579Y279215D01*
Y281640D01*
X542569Y281765D01*
X542529Y281890D01*
X542469Y282000D01*
X542389Y282100D01*
X542289Y282180D01*
X542179Y282240D01*
X542054Y282280D01*
X541929Y282290D01*
G37*
G36*
G01X546654D02*
X546529Y282280D01*
X546404Y282240D01*
X546294Y282180D01*
X546194Y282100D01*
X546114Y282000D01*
X546054Y281890D01*
X546014Y281765D01*
X546004Y281640D01*
Y279210D01*
X545974Y279180D01*
X545874Y279040D01*
X545854Y279000D01*
X545839Y278965D01*
X545819Y278925D01*
X545804Y278885D01*
X545794Y278845D01*
X545779Y278800D01*
X545774Y278760D01*
X545764Y278720D01*
X545759Y278675D01*
Y278635D01*
X545754Y278590D01*
X545759Y278545D01*
Y278505D01*
X545764Y278460D01*
X545774Y278420D01*
X545779Y278380D01*
X545794Y278335D01*
X545804Y278295D01*
X545819Y278255D01*
X545839Y278215D01*
X545854Y278180D01*
X545874Y278140D01*
X545974Y278000D01*
X546004Y277970D01*
Y275840D01*
X546014Y275715D01*
X546054Y275590D01*
X546114Y275480D01*
X546194Y275380D01*
X546294Y275300D01*
X546404Y275240D01*
X546529Y275200D01*
X546654Y275190D01*
X546779Y275200D01*
X546904Y275240D01*
X547014Y275300D01*
X547114Y275380D01*
X547194Y275480D01*
X547254Y275590D01*
X547294Y275715D01*
X547304Y275840D01*
Y277965D01*
X547334Y277995D01*
X547359Y278030D01*
X547389Y278065D01*
X547409Y278100D01*
X547434Y278135D01*
X547474Y278215D01*
X547519Y278335D01*
X547529Y278375D01*
X547539Y278420D01*
X547544Y278460D01*
X547554Y278505D01*
Y278675D01*
X547544Y278720D01*
X547539Y278760D01*
X547529Y278805D01*
X547519Y278845D01*
X547474Y278965D01*
X547434Y279045D01*
X547409Y279080D01*
X547389Y279115D01*
X547359Y279150D01*
X547334Y279185D01*
X547304Y279215D01*
Y281640D01*
X547294Y281765D01*
X547254Y281890D01*
X547194Y282000D01*
X547114Y282100D01*
X547014Y282180D01*
X546904Y282240D01*
X546779Y282280D01*
X546654Y282290D01*
G37*
G36*
G01X551378D02*
X551253Y282280D01*
X551128Y282240D01*
X551018Y282180D01*
X550918Y282100D01*
X550838Y282000D01*
X550778Y281890D01*
X550738Y281765D01*
X550728Y281640D01*
Y279210D01*
X550698Y279180D01*
X550598Y279040D01*
X550578Y279000D01*
X550563Y278965D01*
X550543Y278925D01*
X550528Y278885D01*
X550518Y278845D01*
X550503Y278800D01*
X550498Y278760D01*
X550488Y278720D01*
X550483Y278675D01*
Y278635D01*
X550478Y278590D01*
X550483Y278545D01*
Y278505D01*
X550488Y278460D01*
X550498Y278420D01*
X550503Y278380D01*
X550518Y278335D01*
X550528Y278295D01*
X550543Y278255D01*
X550563Y278215D01*
X550578Y278180D01*
X550598Y278140D01*
X550698Y278000D01*
X550728Y277970D01*
Y275840D01*
X550738Y275715D01*
X550778Y275590D01*
X550838Y275480D01*
X550918Y275380D01*
X551018Y275300D01*
X551128Y275240D01*
X551253Y275200D01*
X551378Y275190D01*
X551503Y275200D01*
X551628Y275240D01*
X551738Y275300D01*
X551838Y275380D01*
X551918Y275480D01*
X551978Y275590D01*
X552018Y275715D01*
X552028Y275840D01*
Y277965D01*
X552058Y277995D01*
X552083Y278030D01*
X552113Y278065D01*
X552133Y278100D01*
X552158Y278135D01*
X552198Y278215D01*
X552243Y278335D01*
X552253Y278375D01*
X552263Y278420D01*
X552268Y278460D01*
X552278Y278505D01*
Y278675D01*
X552268Y278720D01*
X552263Y278760D01*
X552253Y278805D01*
X552243Y278845D01*
X552198Y278965D01*
X552158Y279045D01*
X552133Y279080D01*
X552113Y279115D01*
X552083Y279150D01*
X552058Y279185D01*
X552028Y279215D01*
Y281640D01*
X552018Y281765D01*
X551978Y281890D01*
X551918Y282000D01*
X551838Y282100D01*
X551738Y282180D01*
X551628Y282240D01*
X551503Y282280D01*
X551378Y282290D01*
G37*
G36*
G01X556103D02*
X555978Y282280D01*
X555853Y282240D01*
X555743Y282180D01*
X555643Y282100D01*
X555563Y282000D01*
X555503Y281890D01*
X555463Y281765D01*
X555453Y281640D01*
Y279210D01*
X555423Y279180D01*
X555323Y279040D01*
X555303Y279000D01*
X555288Y278965D01*
X555268Y278925D01*
X555253Y278885D01*
X555243Y278845D01*
X555228Y278800D01*
X555223Y278760D01*
X555213Y278720D01*
X555208Y278675D01*
Y278635D01*
X555203Y278590D01*
X555208Y278545D01*
Y278505D01*
X555213Y278460D01*
X555223Y278420D01*
X555228Y278380D01*
X555243Y278335D01*
X555253Y278295D01*
X555268Y278255D01*
X555288Y278215D01*
X555303Y278180D01*
X555323Y278140D01*
X555423Y278000D01*
X555453Y277970D01*
Y275840D01*
X555463Y275715D01*
X555503Y275590D01*
X555563Y275480D01*
X555643Y275380D01*
X555743Y275300D01*
X555853Y275240D01*
X555978Y275200D01*
X556103Y275190D01*
X556228Y275200D01*
X556353Y275240D01*
X556463Y275300D01*
X556563Y275380D01*
X556643Y275480D01*
X556703Y275590D01*
X556743Y275715D01*
X556753Y275840D01*
Y277965D01*
X556783Y277995D01*
X556808Y278030D01*
X556838Y278065D01*
X556858Y278100D01*
X556883Y278135D01*
X556923Y278215D01*
X556968Y278335D01*
X556978Y278375D01*
X556988Y278420D01*
X556993Y278460D01*
X557003Y278505D01*
Y278675D01*
X556993Y278720D01*
X556988Y278760D01*
X556978Y278805D01*
X556968Y278845D01*
X556923Y278965D01*
X556883Y279045D01*
X556858Y279080D01*
X556838Y279115D01*
X556808Y279150D01*
X556783Y279185D01*
X556753Y279215D01*
Y281640D01*
X556743Y281765D01*
X556703Y281890D01*
X556643Y282000D01*
X556563Y282100D01*
X556463Y282180D01*
X556353Y282240D01*
X556228Y282280D01*
X556103Y282290D01*
G37*
G36*
G01X560827D02*
X560702Y282280D01*
X560577Y282240D01*
X560467Y282180D01*
X560367Y282100D01*
X560287Y282000D01*
X560227Y281890D01*
X560187Y281765D01*
X560177Y281640D01*
Y279210D01*
X560147Y279180D01*
X560047Y279040D01*
X560027Y279000D01*
X560012Y278965D01*
X559992Y278925D01*
X559977Y278885D01*
X559967Y278845D01*
X559952Y278800D01*
X559947Y278760D01*
X559937Y278720D01*
X559932Y278675D01*
Y278635D01*
X559927Y278590D01*
X559932Y278545D01*
Y278505D01*
X559937Y278460D01*
X559947Y278420D01*
X559952Y278380D01*
X559967Y278335D01*
X559977Y278295D01*
X559992Y278255D01*
X560012Y278215D01*
X560027Y278180D01*
X560047Y278140D01*
X560147Y278000D01*
X560177Y277970D01*
Y275840D01*
X560187Y275715D01*
X560227Y275590D01*
X560287Y275480D01*
X560367Y275380D01*
X560467Y275300D01*
X560577Y275240D01*
X560702Y275200D01*
X560827Y275190D01*
X560952Y275200D01*
X561077Y275240D01*
X561187Y275300D01*
X561287Y275380D01*
X561367Y275480D01*
X561427Y275590D01*
X561467Y275715D01*
X561477Y275840D01*
Y277965D01*
X561507Y277995D01*
X561532Y278030D01*
X561562Y278065D01*
X561582Y278100D01*
X561607Y278135D01*
X561647Y278215D01*
X561692Y278335D01*
X561702Y278375D01*
X561712Y278420D01*
X561717Y278460D01*
X561727Y278505D01*
Y278675D01*
X561717Y278720D01*
X561712Y278760D01*
X561702Y278805D01*
X561692Y278845D01*
X561647Y278965D01*
X561607Y279045D01*
X561582Y279080D01*
X561562Y279115D01*
X561532Y279150D01*
X561507Y279185D01*
X561477Y279215D01*
Y281640D01*
X561467Y281765D01*
X561427Y281890D01*
X561367Y282000D01*
X561287Y282100D01*
X561187Y282180D01*
X561077Y282240D01*
X560952Y282280D01*
X560827Y282290D01*
G37*
G36*
G01X565551D02*
X565426Y282280D01*
X565301Y282240D01*
X565191Y282180D01*
X565091Y282100D01*
X565011Y282000D01*
X564951Y281890D01*
X564911Y281765D01*
X564901Y281640D01*
Y279210D01*
X564871Y279180D01*
X564771Y279040D01*
X564751Y279000D01*
X564736Y278965D01*
X564716Y278925D01*
X564701Y278885D01*
X564691Y278845D01*
X564676Y278800D01*
X564671Y278760D01*
X564661Y278720D01*
X564656Y278675D01*
Y278635D01*
X564651Y278590D01*
X564656Y278545D01*
Y278505D01*
X564661Y278460D01*
X564671Y278420D01*
X564676Y278380D01*
X564691Y278335D01*
X564701Y278295D01*
X564716Y278255D01*
X564736Y278215D01*
X564751Y278180D01*
X564771Y278140D01*
X564871Y278000D01*
X564901Y277970D01*
Y275840D01*
X564911Y275715D01*
X564951Y275590D01*
X565011Y275480D01*
X565091Y275380D01*
X565191Y275300D01*
X565301Y275240D01*
X565426Y275200D01*
X565551Y275190D01*
X565676Y275200D01*
X565801Y275240D01*
X565911Y275300D01*
X566011Y275380D01*
X566091Y275480D01*
X566151Y275590D01*
X566191Y275715D01*
X566201Y275840D01*
Y277965D01*
X566231Y277995D01*
X566256Y278030D01*
X566286Y278065D01*
X566306Y278100D01*
X566331Y278135D01*
X566371Y278215D01*
X566416Y278335D01*
X566426Y278375D01*
X566436Y278420D01*
X566441Y278460D01*
X566451Y278505D01*
Y278675D01*
X566441Y278720D01*
X566436Y278760D01*
X566426Y278805D01*
X566416Y278845D01*
X566371Y278965D01*
X566331Y279045D01*
X566306Y279080D01*
X566286Y279115D01*
X566256Y279150D01*
X566231Y279185D01*
X566201Y279215D01*
Y281640D01*
X566191Y281765D01*
X566151Y281890D01*
X566091Y282000D01*
X566011Y282100D01*
X565911Y282180D01*
X565801Y282240D01*
X565676Y282280D01*
X565551Y282290D01*
G37*
G36*
G01X570276D02*
X570151Y282280D01*
X570026Y282240D01*
X569916Y282180D01*
X569816Y282100D01*
X569736Y282000D01*
X569676Y281890D01*
X569636Y281765D01*
X569626Y281640D01*
Y279210D01*
X569596Y279180D01*
X569496Y279040D01*
X569476Y279000D01*
X569461Y278965D01*
X569441Y278925D01*
X569426Y278885D01*
X569416Y278845D01*
X569401Y278800D01*
X569396Y278760D01*
X569386Y278720D01*
X569381Y278675D01*
Y278635D01*
X569376Y278590D01*
X569381Y278545D01*
Y278505D01*
X569386Y278460D01*
X569396Y278420D01*
X569401Y278380D01*
X569416Y278335D01*
X569426Y278295D01*
X569441Y278255D01*
X569461Y278215D01*
X569476Y278180D01*
X569496Y278140D01*
X569596Y278000D01*
X569626Y277970D01*
Y275840D01*
X569636Y275715D01*
X569676Y275590D01*
X569736Y275480D01*
X569816Y275380D01*
X569916Y275300D01*
X570026Y275240D01*
X570151Y275200D01*
X570276Y275190D01*
X570401Y275200D01*
X570526Y275240D01*
X570636Y275300D01*
X570736Y275380D01*
X570816Y275480D01*
X570876Y275590D01*
X570916Y275715D01*
X570926Y275840D01*
Y277965D01*
X570956Y277995D01*
X570981Y278030D01*
X571011Y278065D01*
X571031Y278100D01*
X571056Y278135D01*
X571096Y278215D01*
X571141Y278335D01*
X571151Y278375D01*
X571161Y278420D01*
X571166Y278460D01*
X571176Y278505D01*
Y278675D01*
X571166Y278720D01*
X571161Y278760D01*
X571151Y278805D01*
X571141Y278845D01*
X571096Y278965D01*
X571056Y279045D01*
X571031Y279080D01*
X571011Y279115D01*
X570981Y279150D01*
X570956Y279185D01*
X570926Y279215D01*
Y281640D01*
X570916Y281765D01*
X570876Y281890D01*
X570816Y282000D01*
X570736Y282100D01*
X570636Y282180D01*
X570526Y282240D01*
X570401Y282280D01*
X570276Y282290D01*
G37*
G36*
G01X575000D02*
X574875Y282280D01*
X574750Y282240D01*
X574640Y282180D01*
X574540Y282100D01*
X574460Y282000D01*
X574400Y281890D01*
X574360Y281765D01*
X574350Y281640D01*
Y279210D01*
X574320Y279180D01*
X574220Y279040D01*
X574200Y279000D01*
X574185Y278965D01*
X574165Y278925D01*
X574150Y278885D01*
X574140Y278845D01*
X574125Y278800D01*
X574120Y278760D01*
X574110Y278720D01*
X574105Y278675D01*
Y278635D01*
X574100Y278590D01*
X574105Y278545D01*
Y278505D01*
X574110Y278460D01*
X574120Y278420D01*
X574125Y278380D01*
X574140Y278335D01*
X574150Y278295D01*
X574165Y278255D01*
X574185Y278215D01*
X574200Y278180D01*
X574220Y278140D01*
X574320Y278000D01*
X574350Y277970D01*
Y275840D01*
X574360Y275715D01*
X574400Y275590D01*
X574460Y275480D01*
X574540Y275380D01*
X574640Y275300D01*
X574750Y275240D01*
X574875Y275200D01*
X575000Y275190D01*
X575125Y275200D01*
X575250Y275240D01*
X575360Y275300D01*
X575460Y275380D01*
X575540Y275480D01*
X575600Y275590D01*
X575640Y275715D01*
X575650Y275840D01*
Y277965D01*
X575680Y277995D01*
X575705Y278030D01*
X575735Y278065D01*
X575755Y278100D01*
X575780Y278135D01*
X575820Y278215D01*
X575865Y278335D01*
X575875Y278375D01*
X575885Y278420D01*
X575890Y278460D01*
X575900Y278505D01*
Y278675D01*
X575890Y278720D01*
X575885Y278760D01*
X575875Y278805D01*
X575865Y278845D01*
X575820Y278965D01*
X575780Y279045D01*
X575755Y279080D01*
X575735Y279115D01*
X575705Y279150D01*
X575680Y279185D01*
X575650Y279215D01*
Y281640D01*
X575640Y281765D01*
X575600Y281890D01*
X575540Y282000D01*
X575460Y282100D01*
X575360Y282180D01*
X575250Y282240D01*
X575125Y282280D01*
X575000Y282290D01*
G37*
G36*
G01X579725D02*
X579600Y282280D01*
X579475Y282240D01*
X579365Y282180D01*
X579265Y282100D01*
X579185Y282000D01*
X579125Y281890D01*
X579085Y281765D01*
X579075Y281640D01*
Y279210D01*
X579045Y279180D01*
X578945Y279040D01*
X578925Y279000D01*
X578910Y278965D01*
X578890Y278925D01*
X578875Y278885D01*
X578865Y278845D01*
X578850Y278800D01*
X578845Y278760D01*
X578835Y278720D01*
X578830Y278675D01*
Y278635D01*
X578825Y278590D01*
X578830Y278545D01*
Y278505D01*
X578835Y278460D01*
X578845Y278420D01*
X578850Y278380D01*
X578865Y278335D01*
X578875Y278295D01*
X578890Y278255D01*
X578910Y278215D01*
X578925Y278180D01*
X578945Y278140D01*
X579045Y278000D01*
X579075Y277970D01*
Y275840D01*
X579085Y275715D01*
X579125Y275590D01*
X579185Y275480D01*
X579265Y275380D01*
X579365Y275300D01*
X579475Y275240D01*
X579600Y275200D01*
X579725Y275190D01*
X579850Y275200D01*
X579975Y275240D01*
X580085Y275300D01*
X580185Y275380D01*
X580265Y275480D01*
X580325Y275590D01*
X580365Y275715D01*
X580375Y275840D01*
Y277965D01*
X580405Y277995D01*
X580430Y278030D01*
X580460Y278065D01*
X580480Y278100D01*
X580505Y278135D01*
X580545Y278215D01*
X580590Y278335D01*
X580600Y278375D01*
X580610Y278420D01*
X580615Y278460D01*
X580625Y278505D01*
Y278675D01*
X580615Y278720D01*
X580610Y278760D01*
X580600Y278805D01*
X580590Y278845D01*
X580545Y278965D01*
X580505Y279045D01*
X580480Y279080D01*
X580460Y279115D01*
X580430Y279150D01*
X580405Y279185D01*
X580375Y279215D01*
Y281640D01*
X580365Y281765D01*
X580325Y281890D01*
X580265Y282000D01*
X580185Y282100D01*
X580085Y282180D01*
X579975Y282240D01*
X579850Y282280D01*
X579725Y282290D01*
G37*
G36*
G01X584449D02*
X584324Y282280D01*
X584199Y282240D01*
X584089Y282180D01*
X583989Y282100D01*
X583909Y282000D01*
X583849Y281890D01*
X583809Y281765D01*
X583799Y281640D01*
Y279210D01*
X583769Y279180D01*
X583669Y279040D01*
X583649Y279000D01*
X583634Y278965D01*
X583614Y278925D01*
X583599Y278885D01*
X583589Y278845D01*
X583574Y278800D01*
X583569Y278760D01*
X583559Y278720D01*
X583554Y278675D01*
Y278635D01*
X583549Y278590D01*
X583554Y278545D01*
Y278505D01*
X583559Y278460D01*
X583569Y278420D01*
X583574Y278380D01*
X583589Y278335D01*
X583599Y278295D01*
X583614Y278255D01*
X583634Y278215D01*
X583649Y278180D01*
X583669Y278140D01*
X583769Y278000D01*
X583799Y277970D01*
Y275840D01*
X583809Y275715D01*
X583849Y275590D01*
X583909Y275480D01*
X583989Y275380D01*
X584089Y275300D01*
X584199Y275240D01*
X584324Y275200D01*
X584449Y275190D01*
X584574Y275200D01*
X584699Y275240D01*
X584809Y275300D01*
X584909Y275380D01*
X584989Y275480D01*
X585049Y275590D01*
X585089Y275715D01*
X585099Y275840D01*
Y277965D01*
X585129Y277995D01*
X585154Y278030D01*
X585184Y278065D01*
X585204Y278100D01*
X585229Y278135D01*
X585269Y278215D01*
X585314Y278335D01*
X585324Y278375D01*
X585334Y278420D01*
X585339Y278460D01*
X585349Y278505D01*
Y278675D01*
X585339Y278720D01*
X585334Y278760D01*
X585324Y278805D01*
X585314Y278845D01*
X585269Y278965D01*
X585229Y279045D01*
X585204Y279080D01*
X585184Y279115D01*
X585154Y279150D01*
X585129Y279185D01*
X585099Y279215D01*
Y281640D01*
X585089Y281765D01*
X585049Y281890D01*
X584989Y282000D01*
X584909Y282100D01*
X584809Y282180D01*
X584699Y282240D01*
X584574Y282280D01*
X584449Y282290D01*
G37*
G36*
G01X589173D02*
X589048Y282280D01*
X588923Y282240D01*
X588813Y282180D01*
X588713Y282100D01*
X588633Y282000D01*
X588573Y281890D01*
X588533Y281765D01*
X588523Y281640D01*
Y279210D01*
X588493Y279180D01*
X588393Y279040D01*
X588373Y279000D01*
X588358Y278965D01*
X588338Y278925D01*
X588323Y278885D01*
X588313Y278845D01*
X588298Y278800D01*
X588293Y278760D01*
X588283Y278720D01*
X588278Y278675D01*
Y278635D01*
X588273Y278590D01*
X588278Y278545D01*
Y278505D01*
X588283Y278460D01*
X588293Y278420D01*
X588298Y278380D01*
X588313Y278335D01*
X588323Y278295D01*
X588338Y278255D01*
X588358Y278215D01*
X588373Y278180D01*
X588393Y278140D01*
X588493Y278000D01*
X588523Y277970D01*
Y275840D01*
X588533Y275715D01*
X588573Y275590D01*
X588633Y275480D01*
X588713Y275380D01*
X588813Y275300D01*
X588923Y275240D01*
X589048Y275200D01*
X589173Y275190D01*
X589298Y275200D01*
X589423Y275240D01*
X589533Y275300D01*
X589633Y275380D01*
X589713Y275480D01*
X589773Y275590D01*
X589813Y275715D01*
X589823Y275840D01*
Y277965D01*
X589853Y277995D01*
X589878Y278030D01*
X589908Y278065D01*
X589928Y278100D01*
X589953Y278135D01*
X589993Y278215D01*
X590038Y278335D01*
X590048Y278375D01*
X590058Y278420D01*
X590063Y278460D01*
X590073Y278505D01*
Y278675D01*
X590063Y278720D01*
X590058Y278760D01*
X590048Y278805D01*
X590038Y278845D01*
X589993Y278965D01*
X589953Y279045D01*
X589928Y279080D01*
X589908Y279115D01*
X589878Y279150D01*
X589853Y279185D01*
X589823Y279215D01*
Y281640D01*
X589813Y281765D01*
X589773Y281890D01*
X589713Y282000D01*
X589633Y282100D01*
X589533Y282180D01*
X589423Y282240D01*
X589298Y282280D01*
X589173Y282290D01*
G37*
G36*
G01X593898D02*
X593773Y282280D01*
X593648Y282240D01*
X593538Y282180D01*
X593438Y282100D01*
X593358Y282000D01*
X593298Y281890D01*
X593258Y281765D01*
X593248Y281640D01*
Y279210D01*
X593218Y279180D01*
X593118Y279040D01*
X593098Y279000D01*
X593083Y278965D01*
X593063Y278925D01*
X593048Y278885D01*
X593038Y278845D01*
X593023Y278800D01*
X593018Y278760D01*
X593008Y278720D01*
X593003Y278675D01*
Y278635D01*
X592998Y278590D01*
X593003Y278545D01*
Y278505D01*
X593008Y278460D01*
X593018Y278420D01*
X593023Y278380D01*
X593038Y278335D01*
X593048Y278295D01*
X593063Y278255D01*
X593083Y278215D01*
X593098Y278180D01*
X593118Y278140D01*
X593218Y278000D01*
X593248Y277970D01*
Y275840D01*
X593258Y275715D01*
X593298Y275590D01*
X593358Y275480D01*
X593438Y275380D01*
X593538Y275300D01*
X593648Y275240D01*
X593773Y275200D01*
X593898Y275190D01*
X594023Y275200D01*
X594148Y275240D01*
X594258Y275300D01*
X594358Y275380D01*
X594438Y275480D01*
X594498Y275590D01*
X594538Y275715D01*
X594548Y275840D01*
Y277965D01*
X594578Y277995D01*
X594603Y278030D01*
X594633Y278065D01*
X594653Y278100D01*
X594678Y278135D01*
X594718Y278215D01*
X594763Y278335D01*
X594773Y278375D01*
X594783Y278420D01*
X594788Y278460D01*
X594798Y278505D01*
Y278675D01*
X594788Y278720D01*
X594783Y278760D01*
X594773Y278805D01*
X594763Y278845D01*
X594718Y278965D01*
X594678Y279045D01*
X594653Y279080D01*
X594633Y279115D01*
X594603Y279150D01*
X594578Y279185D01*
X594548Y279215D01*
Y281640D01*
X594538Y281765D01*
X594498Y281890D01*
X594438Y282000D01*
X594358Y282100D01*
X594258Y282180D01*
X594148Y282240D01*
X594023Y282280D01*
X593898Y282290D01*
G37*
G36*
G01X598622D02*
X598497Y282280D01*
X598372Y282240D01*
X598262Y282180D01*
X598162Y282100D01*
X598082Y282000D01*
X598022Y281890D01*
X597982Y281765D01*
X597972Y281640D01*
Y279210D01*
X597942Y279180D01*
X597842Y279040D01*
X597822Y279000D01*
X597807Y278965D01*
X597787Y278925D01*
X597772Y278885D01*
X597762Y278845D01*
X597747Y278800D01*
X597742Y278760D01*
X597732Y278720D01*
X597727Y278675D01*
Y278635D01*
X597722Y278590D01*
X597727Y278545D01*
Y278505D01*
X597732Y278460D01*
X597742Y278420D01*
X597747Y278380D01*
X597762Y278335D01*
X597772Y278295D01*
X597787Y278255D01*
X597807Y278215D01*
X597822Y278180D01*
X597842Y278140D01*
X597942Y278000D01*
X597972Y277970D01*
Y275840D01*
X597982Y275715D01*
X598022Y275590D01*
X598082Y275480D01*
X598162Y275380D01*
X598262Y275300D01*
X598372Y275240D01*
X598497Y275200D01*
X598622Y275190D01*
X598747Y275200D01*
X598872Y275240D01*
X598982Y275300D01*
X599082Y275380D01*
X599162Y275480D01*
X599222Y275590D01*
X599262Y275715D01*
X599272Y275840D01*
Y277965D01*
X599302Y277995D01*
X599327Y278030D01*
X599357Y278065D01*
X599377Y278100D01*
X599402Y278135D01*
X599442Y278215D01*
X599487Y278335D01*
X599497Y278375D01*
X599507Y278420D01*
X599512Y278460D01*
X599522Y278505D01*
Y278675D01*
X599512Y278720D01*
X599507Y278760D01*
X599497Y278805D01*
X599487Y278845D01*
X599442Y278965D01*
X599402Y279045D01*
X599377Y279080D01*
X599357Y279115D01*
X599327Y279150D01*
X599302Y279185D01*
X599272Y279215D01*
Y281640D01*
X599262Y281765D01*
X599222Y281890D01*
X599162Y282000D01*
X599082Y282100D01*
X598982Y282180D01*
X598872Y282240D01*
X598747Y282280D01*
X598622Y282290D01*
G37*
G36*
G01X603347D02*
X603222Y282280D01*
X603097Y282240D01*
X602987Y282180D01*
X602887Y282100D01*
X602807Y282000D01*
X602747Y281890D01*
X602707Y281765D01*
X602697Y281640D01*
Y279210D01*
X602667Y279180D01*
X602567Y279040D01*
X602547Y279000D01*
X602532Y278965D01*
X602512Y278925D01*
X602497Y278885D01*
X602487Y278845D01*
X602472Y278800D01*
X602467Y278760D01*
X602457Y278720D01*
X602452Y278675D01*
Y278635D01*
X602447Y278590D01*
X602452Y278545D01*
Y278505D01*
X602457Y278460D01*
X602467Y278420D01*
X602472Y278380D01*
X602487Y278335D01*
X602497Y278295D01*
X602512Y278255D01*
X602532Y278215D01*
X602547Y278180D01*
X602567Y278140D01*
X602667Y278000D01*
X602697Y277970D01*
Y275840D01*
X602707Y275715D01*
X602747Y275590D01*
X602807Y275480D01*
X602887Y275380D01*
X602987Y275300D01*
X603097Y275240D01*
X603222Y275200D01*
X603347Y275190D01*
X603472Y275200D01*
X603597Y275240D01*
X603707Y275300D01*
X603807Y275380D01*
X603887Y275480D01*
X603947Y275590D01*
X603987Y275715D01*
X603997Y275840D01*
Y277965D01*
X604027Y277995D01*
X604052Y278030D01*
X604082Y278065D01*
X604102Y278100D01*
X604127Y278135D01*
X604167Y278215D01*
X604212Y278335D01*
X604222Y278375D01*
X604232Y278420D01*
X604237Y278460D01*
X604247Y278505D01*
Y278675D01*
X604237Y278720D01*
X604232Y278760D01*
X604222Y278805D01*
X604212Y278845D01*
X604167Y278965D01*
X604127Y279045D01*
X604102Y279080D01*
X604082Y279115D01*
X604052Y279150D01*
X604027Y279185D01*
X603997Y279215D01*
Y281640D01*
X603987Y281765D01*
X603947Y281890D01*
X603887Y282000D01*
X603807Y282100D01*
X603707Y282180D01*
X603597Y282240D01*
X603472Y282280D01*
X603347Y282290D01*
G37*
G36*
G01X608071D02*
X607946Y282280D01*
X607821Y282240D01*
X607711Y282180D01*
X607611Y282100D01*
X607531Y282000D01*
X607471Y281890D01*
X607431Y281765D01*
X607421Y281640D01*
Y279210D01*
X607391Y279180D01*
X607291Y279040D01*
X607271Y279000D01*
X607256Y278965D01*
X607236Y278925D01*
X607221Y278885D01*
X607211Y278845D01*
X607196Y278800D01*
X607191Y278760D01*
X607181Y278720D01*
X607176Y278675D01*
Y278635D01*
X607171Y278590D01*
X607176Y278545D01*
Y278505D01*
X607181Y278460D01*
X607191Y278420D01*
X607196Y278380D01*
X607211Y278335D01*
X607221Y278295D01*
X607236Y278255D01*
X607256Y278215D01*
X607271Y278180D01*
X607291Y278140D01*
X607391Y278000D01*
X607421Y277970D01*
Y275840D01*
X607431Y275715D01*
X607471Y275590D01*
X607531Y275480D01*
X607611Y275380D01*
X607711Y275300D01*
X607821Y275240D01*
X607946Y275200D01*
X608071Y275190D01*
X608196Y275200D01*
X608321Y275240D01*
X608431Y275300D01*
X608531Y275380D01*
X608611Y275480D01*
X608671Y275590D01*
X608711Y275715D01*
X608721Y275840D01*
Y277965D01*
X608751Y277995D01*
X608776Y278030D01*
X608806Y278065D01*
X608826Y278100D01*
X608851Y278135D01*
X608891Y278215D01*
X608936Y278335D01*
X608946Y278375D01*
X608956Y278420D01*
X608961Y278460D01*
X608971Y278505D01*
Y278675D01*
X608961Y278720D01*
X608956Y278760D01*
X608946Y278805D01*
X608936Y278845D01*
X608891Y278965D01*
X608851Y279045D01*
X608826Y279080D01*
X608806Y279115D01*
X608776Y279150D01*
X608751Y279185D01*
X608721Y279215D01*
Y281640D01*
X608711Y281765D01*
X608671Y281890D01*
X608611Y282000D01*
X608531Y282100D01*
X608431Y282180D01*
X608321Y282240D01*
X608196Y282280D01*
X608071Y282290D01*
G37*
G36*
G01X612796D02*
X612671Y282280D01*
X612546Y282240D01*
X612436Y282180D01*
X612336Y282100D01*
X612256Y282000D01*
X612196Y281890D01*
X612156Y281765D01*
X612146Y281640D01*
Y279210D01*
X612116Y279180D01*
X612016Y279040D01*
X611996Y279000D01*
X611981Y278965D01*
X611961Y278925D01*
X611946Y278885D01*
X611936Y278845D01*
X611921Y278800D01*
X611916Y278760D01*
X611906Y278720D01*
X611901Y278675D01*
Y278635D01*
X611896Y278590D01*
X611901Y278545D01*
Y278505D01*
X611906Y278460D01*
X611916Y278420D01*
X611921Y278380D01*
X611936Y278335D01*
X611946Y278295D01*
X611961Y278255D01*
X611981Y278215D01*
X611996Y278180D01*
X612016Y278140D01*
X612116Y278000D01*
X612146Y277970D01*
Y275840D01*
X612156Y275715D01*
X612196Y275590D01*
X612256Y275480D01*
X612336Y275380D01*
X612436Y275300D01*
X612546Y275240D01*
X612671Y275200D01*
X612796Y275190D01*
X612921Y275200D01*
X613046Y275240D01*
X613156Y275300D01*
X613256Y275380D01*
X613336Y275480D01*
X613396Y275590D01*
X613436Y275715D01*
X613446Y275840D01*
Y277965D01*
X613476Y277995D01*
X613501Y278030D01*
X613531Y278065D01*
X613551Y278100D01*
X613576Y278135D01*
X613616Y278215D01*
X613661Y278335D01*
X613671Y278375D01*
X613681Y278420D01*
X613686Y278460D01*
X613696Y278505D01*
Y278675D01*
X613686Y278720D01*
X613681Y278760D01*
X613671Y278805D01*
X613661Y278845D01*
X613616Y278965D01*
X613576Y279045D01*
X613551Y279080D01*
X613531Y279115D01*
X613501Y279150D01*
X613476Y279185D01*
X613446Y279215D01*
Y281640D01*
X613436Y281765D01*
X613396Y281890D01*
X613336Y282000D01*
X613256Y282100D01*
X613156Y282180D01*
X613046Y282240D01*
X612921Y282280D01*
X612796Y282290D01*
G37*
G36*
G01X617520D02*
X617395Y282280D01*
X617270Y282240D01*
X617160Y282180D01*
X617060Y282100D01*
X616980Y282000D01*
X616920Y281890D01*
X616880Y281765D01*
X616870Y281640D01*
Y279210D01*
X616840Y279180D01*
X616740Y279040D01*
X616720Y279000D01*
X616705Y278965D01*
X616685Y278925D01*
X616670Y278885D01*
X616660Y278845D01*
X616645Y278800D01*
X616640Y278760D01*
X616630Y278720D01*
X616625Y278675D01*
Y278635D01*
X616620Y278590D01*
X616625Y278545D01*
Y278505D01*
X616630Y278460D01*
X616640Y278420D01*
X616645Y278380D01*
X616660Y278335D01*
X616670Y278295D01*
X616685Y278255D01*
X616705Y278215D01*
X616720Y278180D01*
X616740Y278140D01*
X616840Y278000D01*
X616870Y277970D01*
Y275840D01*
X616880Y275715D01*
X616920Y275590D01*
X616980Y275480D01*
X617060Y275380D01*
X617160Y275300D01*
X617270Y275240D01*
X617395Y275200D01*
X617520Y275190D01*
X617645Y275200D01*
X617770Y275240D01*
X617880Y275300D01*
X617980Y275380D01*
X618060Y275480D01*
X618120Y275590D01*
X618160Y275715D01*
X618170Y275840D01*
Y277965D01*
X618200Y277995D01*
X618225Y278030D01*
X618255Y278065D01*
X618275Y278100D01*
X618300Y278135D01*
X618340Y278215D01*
X618385Y278335D01*
X618395Y278375D01*
X618405Y278420D01*
X618410Y278460D01*
X618420Y278505D01*
Y278675D01*
X618410Y278720D01*
X618405Y278760D01*
X618395Y278805D01*
X618385Y278845D01*
X618340Y278965D01*
X618300Y279045D01*
X618275Y279080D01*
X618255Y279115D01*
X618225Y279150D01*
X618200Y279185D01*
X618170Y279215D01*
Y281640D01*
X618160Y281765D01*
X618120Y281890D01*
X618060Y282000D01*
X617980Y282100D01*
X617880Y282180D01*
X617770Y282240D01*
X617645Y282280D01*
X617520Y282290D01*
G37*
G36*
G01X622244D02*
X622119Y282280D01*
X621994Y282240D01*
X621884Y282180D01*
X621784Y282100D01*
X621704Y282000D01*
X621644Y281890D01*
X621604Y281765D01*
X621594Y281640D01*
Y279210D01*
X621564Y279180D01*
X621464Y279040D01*
X621444Y279000D01*
X621429Y278965D01*
X621409Y278925D01*
X621394Y278885D01*
X621384Y278845D01*
X621369Y278800D01*
X621364Y278760D01*
X621354Y278720D01*
X621349Y278675D01*
Y278635D01*
X621344Y278590D01*
X621349Y278545D01*
Y278505D01*
X621354Y278460D01*
X621364Y278420D01*
X621369Y278380D01*
X621384Y278335D01*
X621394Y278295D01*
X621409Y278255D01*
X621429Y278215D01*
X621444Y278180D01*
X621464Y278140D01*
X621564Y278000D01*
X621594Y277970D01*
Y275840D01*
X621604Y275715D01*
X621644Y275590D01*
X621704Y275480D01*
X621784Y275380D01*
X621884Y275300D01*
X621994Y275240D01*
X622119Y275200D01*
X622244Y275190D01*
X622369Y275200D01*
X622494Y275240D01*
X622604Y275300D01*
X622704Y275380D01*
X622784Y275480D01*
X622844Y275590D01*
X622884Y275715D01*
X622894Y275840D01*
Y277965D01*
X622924Y277995D01*
X622949Y278030D01*
X622979Y278065D01*
X622999Y278100D01*
X623024Y278135D01*
X623064Y278215D01*
X623109Y278335D01*
X623119Y278375D01*
X623129Y278420D01*
X623134Y278460D01*
X623144Y278505D01*
Y278675D01*
X623134Y278720D01*
X623129Y278760D01*
X623119Y278805D01*
X623109Y278845D01*
X623064Y278965D01*
X623024Y279045D01*
X622999Y279080D01*
X622979Y279115D01*
X622949Y279150D01*
X622924Y279185D01*
X622894Y279215D01*
Y281640D01*
X622884Y281765D01*
X622844Y281890D01*
X622784Y282000D01*
X622704Y282100D01*
X622604Y282180D01*
X622494Y282240D01*
X622369Y282280D01*
X622244Y282290D01*
G37*
G36*
G01X626969D02*
X626844Y282280D01*
X626719Y282240D01*
X626609Y282180D01*
X626509Y282100D01*
X626429Y282000D01*
X626369Y281890D01*
X626329Y281765D01*
X626319Y281640D01*
Y279210D01*
X626289Y279180D01*
X626189Y279040D01*
X626169Y279000D01*
X626154Y278965D01*
X626134Y278925D01*
X626119Y278885D01*
X626109Y278845D01*
X626094Y278800D01*
X626089Y278760D01*
X626079Y278720D01*
X626074Y278675D01*
Y278635D01*
X626069Y278590D01*
X626074Y278545D01*
Y278505D01*
X626079Y278460D01*
X626089Y278420D01*
X626094Y278380D01*
X626109Y278335D01*
X626119Y278295D01*
X626134Y278255D01*
X626154Y278215D01*
X626169Y278180D01*
X626189Y278140D01*
X626289Y278000D01*
X626319Y277970D01*
Y275840D01*
X626329Y275715D01*
X626369Y275590D01*
X626429Y275480D01*
X626509Y275380D01*
X626609Y275300D01*
X626719Y275240D01*
X626844Y275200D01*
X626969Y275190D01*
X627094Y275200D01*
X627219Y275240D01*
X627329Y275300D01*
X627429Y275380D01*
X627509Y275480D01*
X627569Y275590D01*
X627609Y275715D01*
X627619Y275840D01*
Y277965D01*
X627649Y277995D01*
X627674Y278030D01*
X627704Y278065D01*
X627724Y278100D01*
X627749Y278135D01*
X627789Y278215D01*
X627834Y278335D01*
X627844Y278375D01*
X627854Y278420D01*
X627859Y278460D01*
X627869Y278505D01*
Y278675D01*
X627859Y278720D01*
X627854Y278760D01*
X627844Y278805D01*
X627834Y278845D01*
X627789Y278965D01*
X627749Y279045D01*
X627724Y279080D01*
X627704Y279115D01*
X627674Y279150D01*
X627649Y279185D01*
X627619Y279215D01*
Y281640D01*
X627609Y281765D01*
X627569Y281890D01*
X627509Y282000D01*
X627429Y282100D01*
X627329Y282180D01*
X627219Y282240D01*
X627094Y282280D01*
X626969Y282290D01*
G37*
G36*
G01X631693D02*
X631568Y282280D01*
X631443Y282240D01*
X631333Y282180D01*
X631233Y282100D01*
X631153Y282000D01*
X631093Y281890D01*
X631053Y281765D01*
X631043Y281640D01*
Y279210D01*
X631013Y279180D01*
X630913Y279040D01*
X630893Y279000D01*
X630878Y278965D01*
X630858Y278925D01*
X630843Y278885D01*
X630833Y278845D01*
X630818Y278800D01*
X630813Y278760D01*
X630803Y278720D01*
X630798Y278675D01*
Y278635D01*
X630793Y278590D01*
X630798Y278545D01*
Y278505D01*
X630803Y278460D01*
X630813Y278420D01*
X630818Y278380D01*
X630833Y278335D01*
X630843Y278295D01*
X630858Y278255D01*
X630878Y278215D01*
X630893Y278180D01*
X630913Y278140D01*
X631013Y278000D01*
X631043Y277970D01*
Y275840D01*
X631053Y275715D01*
X631093Y275590D01*
X631153Y275480D01*
X631233Y275380D01*
X631333Y275300D01*
X631443Y275240D01*
X631568Y275200D01*
X631693Y275190D01*
X631818Y275200D01*
X631943Y275240D01*
X632053Y275300D01*
X632153Y275380D01*
X632233Y275480D01*
X632293Y275590D01*
X632333Y275715D01*
X632343Y275840D01*
Y277965D01*
X632373Y277995D01*
X632398Y278030D01*
X632428Y278065D01*
X632448Y278100D01*
X632473Y278135D01*
X632513Y278215D01*
X632558Y278335D01*
X632568Y278375D01*
X632578Y278420D01*
X632583Y278460D01*
X632593Y278505D01*
Y278675D01*
X632583Y278720D01*
X632578Y278760D01*
X632568Y278805D01*
X632558Y278845D01*
X632513Y278965D01*
X632473Y279045D01*
X632448Y279080D01*
X632428Y279115D01*
X632398Y279150D01*
X632373Y279185D01*
X632343Y279215D01*
Y281640D01*
X632333Y281765D01*
X632293Y281890D01*
X632233Y282000D01*
X632153Y282100D01*
X632053Y282180D01*
X631943Y282240D01*
X631818Y282280D01*
X631693Y282290D01*
G37*
G36*
G01X636418D02*
X636293Y282280D01*
X636168Y282240D01*
X636058Y282180D01*
X635958Y282100D01*
X635878Y282000D01*
X635818Y281890D01*
X635778Y281765D01*
X635768Y281640D01*
Y279210D01*
X635738Y279180D01*
X635638Y279040D01*
X635618Y279000D01*
X635603Y278965D01*
X635583Y278925D01*
X635568Y278885D01*
X635558Y278845D01*
X635543Y278800D01*
X635538Y278760D01*
X635528Y278720D01*
X635523Y278675D01*
Y278635D01*
X635518Y278590D01*
X635523Y278545D01*
Y278505D01*
X635528Y278460D01*
X635538Y278420D01*
X635543Y278380D01*
X635558Y278335D01*
X635568Y278295D01*
X635583Y278255D01*
X635603Y278215D01*
X635618Y278180D01*
X635638Y278140D01*
X635738Y278000D01*
X635768Y277970D01*
Y275840D01*
X635778Y275715D01*
X635818Y275590D01*
X635878Y275480D01*
X635958Y275380D01*
X636058Y275300D01*
X636168Y275240D01*
X636293Y275200D01*
X636418Y275190D01*
X636543Y275200D01*
X636668Y275240D01*
X636778Y275300D01*
X636878Y275380D01*
X636958Y275480D01*
X637018Y275590D01*
X637058Y275715D01*
X637068Y275840D01*
Y277965D01*
X637098Y277995D01*
X637123Y278030D01*
X637153Y278065D01*
X637173Y278100D01*
X637198Y278135D01*
X637238Y278215D01*
X637283Y278335D01*
X637293Y278375D01*
X637303Y278420D01*
X637308Y278460D01*
X637318Y278505D01*
Y278675D01*
X637308Y278720D01*
X637303Y278760D01*
X637293Y278805D01*
X637283Y278845D01*
X637238Y278965D01*
X637198Y279045D01*
X637173Y279080D01*
X637153Y279115D01*
X637123Y279150D01*
X637098Y279185D01*
X637068Y279215D01*
Y281640D01*
X637058Y281765D01*
X637018Y281890D01*
X636958Y282000D01*
X636878Y282100D01*
X636778Y282180D01*
X636668Y282240D01*
X636543Y282280D01*
X636418Y282290D01*
G37*
G36*
G01X641142D02*
X641017Y282280D01*
X640892Y282240D01*
X640782Y282180D01*
X640682Y282100D01*
X640602Y282000D01*
X640542Y281890D01*
X640502Y281765D01*
X640492Y281640D01*
Y279210D01*
X640462Y279180D01*
X640362Y279040D01*
X640342Y279000D01*
X640327Y278965D01*
X640307Y278925D01*
X640292Y278885D01*
X640282Y278845D01*
X640267Y278800D01*
X640262Y278760D01*
X640252Y278720D01*
X640247Y278675D01*
Y278635D01*
X640242Y278590D01*
X640247Y278545D01*
Y278505D01*
X640252Y278460D01*
X640262Y278420D01*
X640267Y278380D01*
X640282Y278335D01*
X640292Y278295D01*
X640307Y278255D01*
X640327Y278215D01*
X640342Y278180D01*
X640362Y278140D01*
X640462Y278000D01*
X640492Y277970D01*
Y275840D01*
X640502Y275715D01*
X640542Y275590D01*
X640602Y275480D01*
X640682Y275380D01*
X640782Y275300D01*
X640892Y275240D01*
X641017Y275200D01*
X641142Y275190D01*
X641267Y275200D01*
X641392Y275240D01*
X641502Y275300D01*
X641602Y275380D01*
X641682Y275480D01*
X641742Y275590D01*
X641782Y275715D01*
X641792Y275840D01*
Y277965D01*
X641822Y277995D01*
X641847Y278030D01*
X641877Y278065D01*
X641897Y278100D01*
X641922Y278135D01*
X641962Y278215D01*
X642007Y278335D01*
X642017Y278375D01*
X642027Y278420D01*
X642032Y278460D01*
X642042Y278505D01*
Y278675D01*
X642032Y278720D01*
X642027Y278760D01*
X642017Y278805D01*
X642007Y278845D01*
X641962Y278965D01*
X641922Y279045D01*
X641897Y279080D01*
X641877Y279115D01*
X641847Y279150D01*
X641822Y279185D01*
X641792Y279215D01*
Y281640D01*
X641782Y281765D01*
X641742Y281890D01*
X641682Y282000D01*
X641602Y282100D01*
X641502Y282180D01*
X641392Y282240D01*
X641267Y282280D01*
X641142Y282290D01*
G37*
G36*
G01X645866D02*
X645741Y282280D01*
X645616Y282240D01*
X645506Y282180D01*
X645406Y282100D01*
X645326Y282000D01*
X645266Y281890D01*
X645226Y281765D01*
X645216Y281640D01*
Y279210D01*
X645186Y279180D01*
X645086Y279040D01*
X645066Y279000D01*
X645051Y278965D01*
X645031Y278925D01*
X645016Y278885D01*
X645006Y278845D01*
X644991Y278800D01*
X644986Y278760D01*
X644976Y278720D01*
X644971Y278675D01*
Y278635D01*
X644966Y278590D01*
X644971Y278545D01*
Y278505D01*
X644976Y278460D01*
X644986Y278420D01*
X644991Y278380D01*
X645006Y278335D01*
X645016Y278295D01*
X645031Y278255D01*
X645051Y278215D01*
X645066Y278180D01*
X645086Y278140D01*
X645186Y278000D01*
X645216Y277970D01*
Y275840D01*
X645226Y275715D01*
X645266Y275590D01*
X645326Y275480D01*
X645406Y275380D01*
X645506Y275300D01*
X645616Y275240D01*
X645741Y275200D01*
X645866Y275190D01*
X645991Y275200D01*
X646116Y275240D01*
X646226Y275300D01*
X646326Y275380D01*
X646406Y275480D01*
X646466Y275590D01*
X646506Y275715D01*
X646516Y275840D01*
Y277965D01*
X646546Y277995D01*
X646571Y278030D01*
X646601Y278065D01*
X646621Y278100D01*
X646646Y278135D01*
X646686Y278215D01*
X646731Y278335D01*
X646741Y278375D01*
X646751Y278420D01*
X646756Y278460D01*
X646766Y278505D01*
Y278675D01*
X646756Y278720D01*
X646751Y278760D01*
X646741Y278805D01*
X646731Y278845D01*
X646686Y278965D01*
X646646Y279045D01*
X646621Y279080D01*
X646601Y279115D01*
X646571Y279150D01*
X646546Y279185D01*
X646516Y279215D01*
Y281640D01*
X646506Y281765D01*
X646466Y281890D01*
X646406Y282000D01*
X646326Y282100D01*
X646226Y282180D01*
X646116Y282240D01*
X645991Y282280D01*
X645866Y282290D01*
G37*
G36*
G01X650591D02*
X650466Y282280D01*
X650341Y282240D01*
X650231Y282180D01*
X650131Y282100D01*
X650051Y282000D01*
X649991Y281890D01*
X649951Y281765D01*
X649941Y281640D01*
Y279210D01*
X649911Y279180D01*
X649811Y279040D01*
X649791Y279000D01*
X649776Y278965D01*
X649756Y278925D01*
X649741Y278885D01*
X649731Y278845D01*
X649716Y278800D01*
X649711Y278760D01*
X649701Y278720D01*
X649696Y278675D01*
Y278635D01*
X649691Y278590D01*
X649696Y278545D01*
Y278505D01*
X649701Y278460D01*
X649711Y278420D01*
X649716Y278380D01*
X649731Y278335D01*
X649741Y278295D01*
X649756Y278255D01*
X649776Y278215D01*
X649791Y278180D01*
X649811Y278140D01*
X649911Y278000D01*
X649941Y277970D01*
Y275840D01*
X649951Y275715D01*
X649991Y275590D01*
X650051Y275480D01*
X650131Y275380D01*
X650231Y275300D01*
X650341Y275240D01*
X650466Y275200D01*
X650591Y275190D01*
X650716Y275200D01*
X650841Y275240D01*
X650951Y275300D01*
X651051Y275380D01*
X651131Y275480D01*
X651191Y275590D01*
X651231Y275715D01*
X651241Y275840D01*
Y277965D01*
X651271Y277995D01*
X651296Y278030D01*
X651326Y278065D01*
X651346Y278100D01*
X651371Y278135D01*
X651411Y278215D01*
X651456Y278335D01*
X651466Y278375D01*
X651476Y278420D01*
X651481Y278460D01*
X651491Y278505D01*
Y278675D01*
X651481Y278720D01*
X651476Y278760D01*
X651466Y278805D01*
X651456Y278845D01*
X651411Y278965D01*
X651371Y279045D01*
X651346Y279080D01*
X651326Y279115D01*
X651296Y279150D01*
X651271Y279185D01*
X651241Y279215D01*
Y281640D01*
X651231Y281765D01*
X651191Y281890D01*
X651131Y282000D01*
X651051Y282100D01*
X650951Y282180D01*
X650841Y282240D01*
X650716Y282280D01*
X650591Y282290D01*
G37*
G36*
G01X664764D02*
X664639Y282280D01*
X664514Y282240D01*
X664404Y282180D01*
X664304Y282100D01*
X664224Y282000D01*
X664164Y281890D01*
X664124Y281765D01*
X664114Y281640D01*
Y279210D01*
X664084Y279180D01*
X663984Y279040D01*
X663964Y279000D01*
X663949Y278965D01*
X663929Y278925D01*
X663914Y278885D01*
X663904Y278845D01*
X663889Y278800D01*
X663884Y278760D01*
X663874Y278720D01*
X663869Y278675D01*
Y278635D01*
X663864Y278590D01*
X663869Y278545D01*
Y278505D01*
X663874Y278460D01*
X663884Y278420D01*
X663889Y278380D01*
X663904Y278335D01*
X663914Y278295D01*
X663929Y278255D01*
X663949Y278215D01*
X663964Y278180D01*
X663984Y278140D01*
X664084Y278000D01*
X664114Y277970D01*
Y275840D01*
X664124Y275715D01*
X664164Y275590D01*
X664224Y275480D01*
X664304Y275380D01*
X664404Y275300D01*
X664514Y275240D01*
X664639Y275200D01*
X664764Y275190D01*
X664889Y275200D01*
X665014Y275240D01*
X665124Y275300D01*
X665224Y275380D01*
X665304Y275480D01*
X665364Y275590D01*
X665404Y275715D01*
X665414Y275840D01*
Y277965D01*
X665444Y277995D01*
X665469Y278030D01*
X665499Y278065D01*
X665519Y278100D01*
X665544Y278135D01*
X665584Y278215D01*
X665629Y278335D01*
X665639Y278375D01*
X665649Y278420D01*
X665654Y278460D01*
X665664Y278505D01*
Y278675D01*
X665654Y278720D01*
X665649Y278760D01*
X665639Y278805D01*
X665629Y278845D01*
X665584Y278965D01*
X665544Y279045D01*
X665519Y279080D01*
X665499Y279115D01*
X665469Y279150D01*
X665444Y279185D01*
X665414Y279215D01*
Y281640D01*
X665404Y281765D01*
X665364Y281890D01*
X665304Y282000D01*
X665224Y282100D01*
X665124Y282180D01*
X665014Y282240D01*
X664889Y282280D01*
X664764Y282290D01*
G37*
G36*
G01X669488D02*
X669363Y282280D01*
X669238Y282240D01*
X669128Y282180D01*
X669028Y282100D01*
X668948Y282000D01*
X668888Y281890D01*
X668848Y281765D01*
X668838Y281640D01*
Y279210D01*
X668808Y279180D01*
X668708Y279040D01*
X668688Y279000D01*
X668673Y278965D01*
X668653Y278925D01*
X668638Y278885D01*
X668628Y278845D01*
X668613Y278800D01*
X668608Y278760D01*
X668598Y278720D01*
X668593Y278675D01*
Y278635D01*
X668588Y278590D01*
X668593Y278545D01*
Y278505D01*
X668598Y278460D01*
X668608Y278420D01*
X668613Y278380D01*
X668628Y278335D01*
X668638Y278295D01*
X668653Y278255D01*
X668673Y278215D01*
X668688Y278180D01*
X668708Y278140D01*
X668808Y278000D01*
X668838Y277970D01*
Y275840D01*
X668848Y275715D01*
X668888Y275590D01*
X668948Y275480D01*
X669028Y275380D01*
X669128Y275300D01*
X669238Y275240D01*
X669363Y275200D01*
X669488Y275190D01*
X669613Y275200D01*
X669738Y275240D01*
X669848Y275300D01*
X669948Y275380D01*
X670028Y275480D01*
X670088Y275590D01*
X670128Y275715D01*
X670138Y275840D01*
Y277965D01*
X670168Y277995D01*
X670193Y278030D01*
X670223Y278065D01*
X670243Y278100D01*
X670268Y278135D01*
X670308Y278215D01*
X670353Y278335D01*
X670363Y278375D01*
X670373Y278420D01*
X670378Y278460D01*
X670388Y278505D01*
Y278675D01*
X670378Y278720D01*
X670373Y278760D01*
X670363Y278805D01*
X670353Y278845D01*
X670308Y278965D01*
X670268Y279045D01*
X670243Y279080D01*
X670223Y279115D01*
X670193Y279150D01*
X670168Y279185D01*
X670138Y279215D01*
Y281640D01*
X670128Y281765D01*
X670088Y281890D01*
X670028Y282000D01*
X669948Y282100D01*
X669848Y282180D01*
X669738Y282240D01*
X669613Y282280D01*
X669488Y282290D01*
G37*
G36*
G01X674213D02*
X674088Y282280D01*
X673963Y282240D01*
X673853Y282180D01*
X673753Y282100D01*
X673673Y282000D01*
X673613Y281890D01*
X673573Y281765D01*
X673563Y281640D01*
Y279210D01*
X673533Y279180D01*
X673433Y279040D01*
X673413Y279000D01*
X673398Y278965D01*
X673378Y278925D01*
X673363Y278885D01*
X673353Y278845D01*
X673338Y278800D01*
X673333Y278760D01*
X673323Y278720D01*
X673318Y278675D01*
Y278635D01*
X673313Y278590D01*
X673318Y278545D01*
Y278505D01*
X673323Y278460D01*
X673333Y278420D01*
X673338Y278380D01*
X673353Y278335D01*
X673363Y278295D01*
X673378Y278255D01*
X673398Y278215D01*
X673413Y278180D01*
X673433Y278140D01*
X673533Y278000D01*
X673563Y277970D01*
Y275840D01*
X673573Y275715D01*
X673613Y275590D01*
X673673Y275480D01*
X673753Y275380D01*
X673853Y275300D01*
X673963Y275240D01*
X674088Y275200D01*
X674213Y275190D01*
X674338Y275200D01*
X674463Y275240D01*
X674573Y275300D01*
X674673Y275380D01*
X674753Y275480D01*
X674813Y275590D01*
X674853Y275715D01*
X674863Y275840D01*
Y277965D01*
X674893Y277995D01*
X674918Y278030D01*
X674948Y278065D01*
X674968Y278100D01*
X674993Y278135D01*
X675033Y278215D01*
X675078Y278335D01*
X675088Y278375D01*
X675098Y278420D01*
X675103Y278460D01*
X675113Y278505D01*
Y278675D01*
X675103Y278720D01*
X675098Y278760D01*
X675088Y278805D01*
X675078Y278845D01*
X675033Y278965D01*
X674993Y279045D01*
X674968Y279080D01*
X674948Y279115D01*
X674918Y279150D01*
X674893Y279185D01*
X674863Y279215D01*
Y281640D01*
X674853Y281765D01*
X674813Y281890D01*
X674753Y282000D01*
X674673Y282100D01*
X674573Y282180D01*
X674463Y282240D01*
X674338Y282280D01*
X674213Y282290D01*
G37*
G36*
G01X678937D02*
X678812Y282280D01*
X678687Y282240D01*
X678577Y282180D01*
X678477Y282100D01*
X678397Y282000D01*
X678337Y281890D01*
X678297Y281765D01*
X678287Y281640D01*
Y279210D01*
X678257Y279180D01*
X678157Y279040D01*
X678137Y279000D01*
X678122Y278965D01*
X678102Y278925D01*
X678087Y278885D01*
X678077Y278845D01*
X678062Y278800D01*
X678057Y278760D01*
X678047Y278720D01*
X678042Y278675D01*
Y278635D01*
X678037Y278590D01*
X678042Y278545D01*
Y278505D01*
X678047Y278460D01*
X678057Y278420D01*
X678062Y278380D01*
X678077Y278335D01*
X678087Y278295D01*
X678102Y278255D01*
X678122Y278215D01*
X678137Y278180D01*
X678157Y278140D01*
X678257Y278000D01*
X678287Y277970D01*
Y275840D01*
X678297Y275715D01*
X678337Y275590D01*
X678397Y275480D01*
X678477Y275380D01*
X678577Y275300D01*
X678687Y275240D01*
X678812Y275200D01*
X678937Y275190D01*
X679062Y275200D01*
X679187Y275240D01*
X679297Y275300D01*
X679397Y275380D01*
X679477Y275480D01*
X679537Y275590D01*
X679577Y275715D01*
X679587Y275840D01*
Y277965D01*
X679617Y277995D01*
X679642Y278030D01*
X679672Y278065D01*
X679692Y278100D01*
X679717Y278135D01*
X679757Y278215D01*
X679802Y278335D01*
X679812Y278375D01*
X679822Y278420D01*
X679827Y278460D01*
X679837Y278505D01*
Y278675D01*
X679827Y278720D01*
X679822Y278760D01*
X679812Y278805D01*
X679802Y278845D01*
X679757Y278965D01*
X679717Y279045D01*
X679692Y279080D01*
X679672Y279115D01*
X679642Y279150D01*
X679617Y279185D01*
X679587Y279215D01*
Y281640D01*
X679577Y281765D01*
X679537Y281890D01*
X679477Y282000D01*
X679397Y282100D01*
X679297Y282180D01*
X679187Y282240D01*
X679062Y282280D01*
X678937Y282290D01*
G37*
G36*
G01X683662D02*
X683537Y282280D01*
X683412Y282240D01*
X683302Y282180D01*
X683202Y282100D01*
X683122Y282000D01*
X683062Y281890D01*
X683022Y281765D01*
X683012Y281640D01*
Y279210D01*
X682982Y279180D01*
X682882Y279040D01*
X682862Y279000D01*
X682847Y278965D01*
X682827Y278925D01*
X682812Y278885D01*
X682802Y278845D01*
X682787Y278800D01*
X682782Y278760D01*
X682772Y278720D01*
X682767Y278675D01*
Y278635D01*
X682762Y278590D01*
X682767Y278545D01*
Y278505D01*
X682772Y278460D01*
X682782Y278420D01*
X682787Y278380D01*
X682802Y278335D01*
X682812Y278295D01*
X682827Y278255D01*
X682847Y278215D01*
X682862Y278180D01*
X682882Y278140D01*
X682982Y278000D01*
X683012Y277970D01*
Y275840D01*
X683022Y275715D01*
X683062Y275590D01*
X683122Y275480D01*
X683202Y275380D01*
X683302Y275300D01*
X683412Y275240D01*
X683537Y275200D01*
X683662Y275190D01*
X683787Y275200D01*
X683912Y275240D01*
X684022Y275300D01*
X684122Y275380D01*
X684202Y275480D01*
X684262Y275590D01*
X684302Y275715D01*
X684312Y275840D01*
Y277965D01*
X684342Y277995D01*
X684367Y278030D01*
X684397Y278065D01*
X684417Y278100D01*
X684442Y278135D01*
X684482Y278215D01*
X684527Y278335D01*
X684537Y278375D01*
X684547Y278420D01*
X684552Y278460D01*
X684562Y278505D01*
Y278675D01*
X684552Y278720D01*
X684547Y278760D01*
X684537Y278805D01*
X684527Y278845D01*
X684482Y278965D01*
X684442Y279045D01*
X684417Y279080D01*
X684397Y279115D01*
X684367Y279150D01*
X684342Y279185D01*
X684312Y279215D01*
Y281640D01*
X684302Y281765D01*
X684262Y281890D01*
X684202Y282000D01*
X684122Y282100D01*
X684022Y282180D01*
X683912Y282240D01*
X683787Y282280D01*
X683662Y282290D01*
G37*
G36*
G01X688386D02*
X688261Y282280D01*
X688136Y282240D01*
X688026Y282180D01*
X687926Y282100D01*
X687846Y282000D01*
X687786Y281890D01*
X687746Y281765D01*
X687736Y281640D01*
Y279210D01*
X687706Y279180D01*
X687606Y279040D01*
X687586Y279000D01*
X687571Y278965D01*
X687551Y278925D01*
X687536Y278885D01*
X687526Y278845D01*
X687511Y278800D01*
X687506Y278760D01*
X687496Y278720D01*
X687491Y278675D01*
Y278635D01*
X687486Y278590D01*
X687491Y278545D01*
Y278505D01*
X687496Y278460D01*
X687506Y278420D01*
X687511Y278380D01*
X687526Y278335D01*
X687536Y278295D01*
X687551Y278255D01*
X687571Y278215D01*
X687586Y278180D01*
X687606Y278140D01*
X687706Y278000D01*
X687736Y277970D01*
Y275840D01*
X687746Y275715D01*
X687786Y275590D01*
X687846Y275480D01*
X687926Y275380D01*
X688026Y275300D01*
X688136Y275240D01*
X688261Y275200D01*
X688386Y275190D01*
X688511Y275200D01*
X688636Y275240D01*
X688746Y275300D01*
X688846Y275380D01*
X688926Y275480D01*
X688986Y275590D01*
X689026Y275715D01*
X689036Y275840D01*
Y277965D01*
X689066Y277995D01*
X689091Y278030D01*
X689121Y278065D01*
X689141Y278100D01*
X689166Y278135D01*
X689206Y278215D01*
X689251Y278335D01*
X689261Y278375D01*
X689271Y278420D01*
X689276Y278460D01*
X689286Y278505D01*
Y278675D01*
X689276Y278720D01*
X689271Y278760D01*
X689261Y278805D01*
X689251Y278845D01*
X689206Y278965D01*
X689166Y279045D01*
X689141Y279080D01*
X689121Y279115D01*
X689091Y279150D01*
X689066Y279185D01*
X689036Y279215D01*
Y281640D01*
X689026Y281765D01*
X688986Y281890D01*
X688926Y282000D01*
X688846Y282100D01*
X688746Y282180D01*
X688636Y282240D01*
X688511Y282280D01*
X688386Y282290D01*
G37*
G36*
G01X693110D02*
X692985Y282280D01*
X692860Y282240D01*
X692750Y282180D01*
X692650Y282100D01*
X692570Y282000D01*
X692510Y281890D01*
X692470Y281765D01*
X692460Y281640D01*
Y279210D01*
X692430Y279180D01*
X692330Y279040D01*
X692310Y279000D01*
X692295Y278965D01*
X692275Y278925D01*
X692260Y278885D01*
X692250Y278845D01*
X692235Y278800D01*
X692230Y278760D01*
X692220Y278720D01*
X692215Y278675D01*
Y278635D01*
X692210Y278590D01*
X692215Y278545D01*
Y278505D01*
X692220Y278460D01*
X692230Y278420D01*
X692235Y278380D01*
X692250Y278335D01*
X692260Y278295D01*
X692275Y278255D01*
X692295Y278215D01*
X692310Y278180D01*
X692330Y278140D01*
X692430Y278000D01*
X692460Y277970D01*
Y275840D01*
X692470Y275715D01*
X692510Y275590D01*
X692570Y275480D01*
X692650Y275380D01*
X692750Y275300D01*
X692860Y275240D01*
X692985Y275200D01*
X693110Y275190D01*
X693235Y275200D01*
X693360Y275240D01*
X693470Y275300D01*
X693570Y275380D01*
X693650Y275480D01*
X693710Y275590D01*
X693750Y275715D01*
X693760Y275840D01*
Y277965D01*
X693790Y277995D01*
X693815Y278030D01*
X693845Y278065D01*
X693865Y278100D01*
X693890Y278135D01*
X693930Y278215D01*
X693975Y278335D01*
X693985Y278375D01*
X693995Y278420D01*
X694000Y278460D01*
X694010Y278505D01*
Y278675D01*
X694000Y278720D01*
X693995Y278760D01*
X693985Y278805D01*
X693975Y278845D01*
X693930Y278965D01*
X693890Y279045D01*
X693865Y279080D01*
X693845Y279115D01*
X693815Y279150D01*
X693790Y279185D01*
X693760Y279215D01*
Y281640D01*
X693750Y281765D01*
X693710Y281890D01*
X693650Y282000D01*
X693570Y282100D01*
X693470Y282180D01*
X693360Y282240D01*
X693235Y282280D01*
X693110Y282290D01*
G37*
G36*
G01X697835D02*
X697710Y282280D01*
X697585Y282240D01*
X697475Y282180D01*
X697375Y282100D01*
X697295Y282000D01*
X697235Y281890D01*
X697195Y281765D01*
X697185Y281640D01*
Y279210D01*
X697155Y279180D01*
X697055Y279040D01*
X697035Y279000D01*
X697020Y278965D01*
X697000Y278925D01*
X696985Y278885D01*
X696975Y278845D01*
X696960Y278800D01*
X696955Y278760D01*
X696945Y278720D01*
X696940Y278675D01*
Y278635D01*
X696935Y278590D01*
X696940Y278545D01*
Y278505D01*
X696945Y278460D01*
X696955Y278420D01*
X696960Y278380D01*
X696975Y278335D01*
X696985Y278295D01*
X697000Y278255D01*
X697020Y278215D01*
X697035Y278180D01*
X697055Y278140D01*
X697155Y278000D01*
X697185Y277970D01*
Y275840D01*
X697195Y275715D01*
X697235Y275590D01*
X697295Y275480D01*
X697375Y275380D01*
X697475Y275300D01*
X697585Y275240D01*
X697710Y275200D01*
X697835Y275190D01*
X697960Y275200D01*
X698085Y275240D01*
X698195Y275300D01*
X698295Y275380D01*
X698375Y275480D01*
X698435Y275590D01*
X698475Y275715D01*
X698485Y275840D01*
Y277965D01*
X698515Y277995D01*
X698540Y278030D01*
X698570Y278065D01*
X698590Y278100D01*
X698615Y278135D01*
X698655Y278215D01*
X698700Y278335D01*
X698710Y278375D01*
X698720Y278420D01*
X698725Y278460D01*
X698735Y278505D01*
Y278675D01*
X698725Y278720D01*
X698720Y278760D01*
X698710Y278805D01*
X698700Y278845D01*
X698655Y278965D01*
X698615Y279045D01*
X698590Y279080D01*
X698570Y279115D01*
X698540Y279150D01*
X698515Y279185D01*
X698485Y279215D01*
Y281640D01*
X698475Y281765D01*
X698435Y281890D01*
X698375Y282000D01*
X698295Y282100D01*
X698195Y282180D01*
X698085Y282240D01*
X697960Y282280D01*
X697835Y282290D01*
G37*
G36*
G01X702559D02*
X702434Y282280D01*
X702309Y282240D01*
X702199Y282180D01*
X702099Y282100D01*
X702019Y282000D01*
X701959Y281890D01*
X701919Y281765D01*
X701909Y281640D01*
Y279210D01*
X701879Y279180D01*
X701779Y279040D01*
X701759Y279000D01*
X701744Y278965D01*
X701724Y278925D01*
X701709Y278885D01*
X701699Y278845D01*
X701684Y278800D01*
X701679Y278760D01*
X701669Y278720D01*
X701664Y278675D01*
Y278635D01*
X701659Y278590D01*
X701664Y278545D01*
Y278505D01*
X701669Y278460D01*
X701679Y278420D01*
X701684Y278380D01*
X701699Y278335D01*
X701709Y278295D01*
X701724Y278255D01*
X701744Y278215D01*
X701759Y278180D01*
X701779Y278140D01*
X701879Y278000D01*
X701909Y277970D01*
Y275840D01*
X701919Y275715D01*
X701959Y275590D01*
X702019Y275480D01*
X702099Y275380D01*
X702199Y275300D01*
X702309Y275240D01*
X702434Y275200D01*
X702559Y275190D01*
X702684Y275200D01*
X702809Y275240D01*
X702919Y275300D01*
X703019Y275380D01*
X703099Y275480D01*
X703159Y275590D01*
X703199Y275715D01*
X703209Y275840D01*
Y277965D01*
X703239Y277995D01*
X703264Y278030D01*
X703294Y278065D01*
X703314Y278100D01*
X703339Y278135D01*
X703379Y278215D01*
X703424Y278335D01*
X703434Y278375D01*
X703444Y278420D01*
X703449Y278460D01*
X703459Y278505D01*
Y278675D01*
X703449Y278720D01*
X703444Y278760D01*
X703434Y278805D01*
X703424Y278845D01*
X703379Y278965D01*
X703339Y279045D01*
X703314Y279080D01*
X703294Y279115D01*
X703264Y279150D01*
X703239Y279185D01*
X703209Y279215D01*
Y281640D01*
X703199Y281765D01*
X703159Y281890D01*
X703099Y282000D01*
X703019Y282100D01*
X702919Y282180D01*
X702809Y282240D01*
X702684Y282280D01*
X702559Y282290D01*
G37*
G36*
G01X707284D02*
X707159Y282280D01*
X707034Y282240D01*
X706924Y282180D01*
X706824Y282100D01*
X706744Y282000D01*
X706684Y281890D01*
X706644Y281765D01*
X706634Y281640D01*
Y279210D01*
X706604Y279180D01*
X706504Y279040D01*
X706484Y279000D01*
X706469Y278965D01*
X706449Y278925D01*
X706434Y278885D01*
X706424Y278845D01*
X706409Y278800D01*
X706404Y278760D01*
X706394Y278720D01*
X706389Y278675D01*
Y278635D01*
X706384Y278590D01*
X706389Y278545D01*
Y278505D01*
X706394Y278460D01*
X706404Y278420D01*
X706409Y278380D01*
X706424Y278335D01*
X706434Y278295D01*
X706449Y278255D01*
X706469Y278215D01*
X706484Y278180D01*
X706504Y278140D01*
X706604Y278000D01*
X706634Y277970D01*
Y275840D01*
X706644Y275715D01*
X706684Y275590D01*
X706744Y275480D01*
X706824Y275380D01*
X706924Y275300D01*
X707034Y275240D01*
X707159Y275200D01*
X707284Y275190D01*
X707409Y275200D01*
X707534Y275240D01*
X707644Y275300D01*
X707744Y275380D01*
X707824Y275480D01*
X707884Y275590D01*
X707924Y275715D01*
X707934Y275840D01*
Y277965D01*
X707964Y277995D01*
X707989Y278030D01*
X708019Y278065D01*
X708039Y278100D01*
X708064Y278135D01*
X708104Y278215D01*
X708149Y278335D01*
X708159Y278375D01*
X708169Y278420D01*
X708174Y278460D01*
X708184Y278505D01*
Y278675D01*
X708174Y278720D01*
X708169Y278760D01*
X708159Y278805D01*
X708149Y278845D01*
X708104Y278965D01*
X708064Y279045D01*
X708039Y279080D01*
X708019Y279115D01*
X707989Y279150D01*
X707964Y279185D01*
X707934Y279215D01*
Y281640D01*
X707924Y281765D01*
X707884Y281890D01*
X707824Y282000D01*
X707744Y282100D01*
X707644Y282180D01*
X707534Y282240D01*
X707409Y282280D01*
X707284Y282290D01*
G37*
G36*
G01X712008D02*
X711883Y282280D01*
X711758Y282240D01*
X711648Y282180D01*
X711548Y282100D01*
X711468Y282000D01*
X711408Y281890D01*
X711368Y281765D01*
X711358Y281640D01*
Y279210D01*
X711328Y279180D01*
X711228Y279040D01*
X711208Y279000D01*
X711193Y278965D01*
X711173Y278925D01*
X711158Y278885D01*
X711148Y278845D01*
X711133Y278800D01*
X711128Y278760D01*
X711118Y278720D01*
X711113Y278675D01*
Y278635D01*
X711108Y278590D01*
X711113Y278545D01*
Y278505D01*
X711118Y278460D01*
X711128Y278420D01*
X711133Y278380D01*
X711148Y278335D01*
X711158Y278295D01*
X711173Y278255D01*
X711193Y278215D01*
X711208Y278180D01*
X711228Y278140D01*
X711328Y278000D01*
X711358Y277970D01*
Y275840D01*
X711368Y275715D01*
X711408Y275590D01*
X711468Y275480D01*
X711548Y275380D01*
X711648Y275300D01*
X711758Y275240D01*
X711883Y275200D01*
X712008Y275190D01*
X712133Y275200D01*
X712258Y275240D01*
X712368Y275300D01*
X712468Y275380D01*
X712548Y275480D01*
X712608Y275590D01*
X712648Y275715D01*
X712658Y275840D01*
Y277965D01*
X712688Y277995D01*
X712713Y278030D01*
X712743Y278065D01*
X712763Y278100D01*
X712788Y278135D01*
X712828Y278215D01*
X712873Y278335D01*
X712883Y278375D01*
X712893Y278420D01*
X712898Y278460D01*
X712908Y278505D01*
Y278675D01*
X712898Y278720D01*
X712893Y278760D01*
X712883Y278805D01*
X712873Y278845D01*
X712828Y278965D01*
X712788Y279045D01*
X712763Y279080D01*
X712743Y279115D01*
X712713Y279150D01*
X712688Y279185D01*
X712658Y279215D01*
Y281640D01*
X712648Y281765D01*
X712608Y281890D01*
X712548Y282000D01*
X712468Y282100D01*
X712368Y282180D01*
X712258Y282240D01*
X712133Y282280D01*
X712008Y282290D01*
G37*
G36*
G01X716733D02*
X716608Y282280D01*
X716483Y282240D01*
X716373Y282180D01*
X716273Y282100D01*
X716193Y282000D01*
X716133Y281890D01*
X716093Y281765D01*
X716083Y281640D01*
Y279210D01*
X716053Y279180D01*
X715953Y279040D01*
X715933Y279000D01*
X715918Y278965D01*
X715898Y278925D01*
X715883Y278885D01*
X715873Y278845D01*
X715858Y278800D01*
X715853Y278760D01*
X715843Y278720D01*
X715838Y278675D01*
Y278635D01*
X715833Y278590D01*
X715838Y278545D01*
Y278505D01*
X715843Y278460D01*
X715853Y278420D01*
X715858Y278380D01*
X715873Y278335D01*
X715883Y278295D01*
X715898Y278255D01*
X715918Y278215D01*
X715933Y278180D01*
X715953Y278140D01*
X716053Y278000D01*
X716083Y277970D01*
Y275840D01*
X716093Y275715D01*
X716133Y275590D01*
X716193Y275480D01*
X716273Y275380D01*
X716373Y275300D01*
X716483Y275240D01*
X716608Y275200D01*
X716733Y275190D01*
X716858Y275200D01*
X716983Y275240D01*
X717093Y275300D01*
X717193Y275380D01*
X717273Y275480D01*
X717333Y275590D01*
X717373Y275715D01*
X717383Y275840D01*
Y277965D01*
X717413Y277995D01*
X717438Y278030D01*
X717468Y278065D01*
X717488Y278100D01*
X717513Y278135D01*
X717553Y278215D01*
X717598Y278335D01*
X717608Y278375D01*
X717618Y278420D01*
X717623Y278460D01*
X717633Y278505D01*
Y278675D01*
X717623Y278720D01*
X717618Y278760D01*
X717608Y278805D01*
X717598Y278845D01*
X717553Y278965D01*
X717513Y279045D01*
X717488Y279080D01*
X717468Y279115D01*
X717438Y279150D01*
X717413Y279185D01*
X717383Y279215D01*
Y281640D01*
X717373Y281765D01*
X717333Y281890D01*
X717273Y282000D01*
X717193Y282100D01*
X717093Y282180D01*
X716983Y282240D01*
X716858Y282280D01*
X716733Y282290D01*
G37*
G36*
G01X721457D02*
X721332Y282280D01*
X721207Y282240D01*
X721097Y282180D01*
X720997Y282100D01*
X720917Y282000D01*
X720857Y281890D01*
X720817Y281765D01*
X720807Y281640D01*
Y279210D01*
X720777Y279180D01*
X720677Y279040D01*
X720657Y279000D01*
X720642Y278965D01*
X720622Y278925D01*
X720607Y278885D01*
X720597Y278845D01*
X720582Y278800D01*
X720577Y278760D01*
X720567Y278720D01*
X720562Y278675D01*
Y278635D01*
X720557Y278590D01*
X720562Y278545D01*
Y278505D01*
X720567Y278460D01*
X720577Y278420D01*
X720582Y278380D01*
X720597Y278335D01*
X720607Y278295D01*
X720622Y278255D01*
X720642Y278215D01*
X720657Y278180D01*
X720677Y278140D01*
X720777Y278000D01*
X720807Y277970D01*
Y275840D01*
X720817Y275715D01*
X720857Y275590D01*
X720917Y275480D01*
X720997Y275380D01*
X721097Y275300D01*
X721207Y275240D01*
X721332Y275200D01*
X721457Y275190D01*
X721582Y275200D01*
X721707Y275240D01*
X721817Y275300D01*
X721917Y275380D01*
X721997Y275480D01*
X722057Y275590D01*
X722097Y275715D01*
X722107Y275840D01*
Y277965D01*
X722137Y277995D01*
X722162Y278030D01*
X722192Y278065D01*
X722212Y278100D01*
X722237Y278135D01*
X722277Y278215D01*
X722322Y278335D01*
X722332Y278375D01*
X722342Y278420D01*
X722347Y278460D01*
X722357Y278505D01*
Y278675D01*
X722347Y278720D01*
X722342Y278760D01*
X722332Y278805D01*
X722322Y278845D01*
X722277Y278965D01*
X722237Y279045D01*
X722212Y279080D01*
X722192Y279115D01*
X722162Y279150D01*
X722137Y279185D01*
X722107Y279215D01*
Y281640D01*
X722097Y281765D01*
X722057Y281890D01*
X721997Y282000D01*
X721917Y282100D01*
X721817Y282180D01*
X721707Y282240D01*
X721582Y282280D01*
X721457Y282290D01*
G37*
G36*
G01X726181D02*
X726056Y282280D01*
X725931Y282240D01*
X725821Y282180D01*
X725721Y282100D01*
X725641Y282000D01*
X725581Y281890D01*
X725541Y281765D01*
X725531Y281640D01*
Y279210D01*
X725501Y279180D01*
X725401Y279040D01*
X725381Y279000D01*
X725366Y278965D01*
X725346Y278925D01*
X725331Y278885D01*
X725321Y278845D01*
X725306Y278800D01*
X725301Y278760D01*
X725291Y278720D01*
X725286Y278675D01*
Y278635D01*
X725281Y278590D01*
X725286Y278545D01*
Y278505D01*
X725291Y278460D01*
X725301Y278420D01*
X725306Y278380D01*
X725321Y278335D01*
X725331Y278295D01*
X725346Y278255D01*
X725366Y278215D01*
X725381Y278180D01*
X725401Y278140D01*
X725501Y278000D01*
X725531Y277970D01*
Y275840D01*
X725541Y275715D01*
X725581Y275590D01*
X725641Y275480D01*
X725721Y275380D01*
X725821Y275300D01*
X725931Y275240D01*
X726056Y275200D01*
X726181Y275190D01*
X726306Y275200D01*
X726431Y275240D01*
X726541Y275300D01*
X726641Y275380D01*
X726721Y275480D01*
X726781Y275590D01*
X726821Y275715D01*
X726831Y275840D01*
Y277965D01*
X726861Y277995D01*
X726886Y278030D01*
X726916Y278065D01*
X726936Y278100D01*
X726961Y278135D01*
X727001Y278215D01*
X727046Y278335D01*
X727056Y278375D01*
X727066Y278420D01*
X727071Y278460D01*
X727081Y278505D01*
Y278675D01*
X727071Y278720D01*
X727066Y278760D01*
X727056Y278805D01*
X727046Y278845D01*
X727001Y278965D01*
X726961Y279045D01*
X726936Y279080D01*
X726916Y279115D01*
X726886Y279150D01*
X726861Y279185D01*
X726831Y279215D01*
Y281640D01*
X726821Y281765D01*
X726781Y281890D01*
X726721Y282000D01*
X726641Y282100D01*
X726541Y282180D01*
X726431Y282240D01*
X726306Y282280D01*
X726181Y282290D01*
G37*
G36*
G01X730906D02*
X730781Y282280D01*
X730656Y282240D01*
X730546Y282180D01*
X730446Y282100D01*
X730366Y282000D01*
X730306Y281890D01*
X730266Y281765D01*
X730256Y281640D01*
Y279210D01*
X730226Y279180D01*
X730126Y279040D01*
X730106Y279000D01*
X730091Y278965D01*
X730071Y278925D01*
X730056Y278885D01*
X730046Y278845D01*
X730031Y278800D01*
X730026Y278760D01*
X730016Y278720D01*
X730011Y278675D01*
Y278635D01*
X730006Y278590D01*
X730011Y278545D01*
Y278505D01*
X730016Y278460D01*
X730026Y278420D01*
X730031Y278380D01*
X730046Y278335D01*
X730056Y278295D01*
X730071Y278255D01*
X730091Y278215D01*
X730106Y278180D01*
X730126Y278140D01*
X730226Y278000D01*
X730256Y277970D01*
Y275840D01*
X730266Y275715D01*
X730306Y275590D01*
X730366Y275480D01*
X730446Y275380D01*
X730546Y275300D01*
X730656Y275240D01*
X730781Y275200D01*
X730906Y275190D01*
X731031Y275200D01*
X731156Y275240D01*
X731266Y275300D01*
X731366Y275380D01*
X731446Y275480D01*
X731506Y275590D01*
X731546Y275715D01*
X731556Y275840D01*
Y277965D01*
X731586Y277995D01*
X731611Y278030D01*
X731641Y278065D01*
X731661Y278100D01*
X731686Y278135D01*
X731726Y278215D01*
X731771Y278335D01*
X731781Y278375D01*
X731791Y278420D01*
X731796Y278460D01*
X731806Y278505D01*
Y278675D01*
X731796Y278720D01*
X731791Y278760D01*
X731781Y278805D01*
X731771Y278845D01*
X731726Y278965D01*
X731686Y279045D01*
X731661Y279080D01*
X731641Y279115D01*
X731611Y279150D01*
X731586Y279185D01*
X731556Y279215D01*
Y281640D01*
X731546Y281765D01*
X731506Y281890D01*
X731446Y282000D01*
X731366Y282100D01*
X731266Y282180D01*
X731156Y282240D01*
X731031Y282280D01*
X730906Y282290D01*
G37*
G36*
G01X735630D02*
X735505Y282280D01*
X735380Y282240D01*
X735270Y282180D01*
X735170Y282100D01*
X735090Y282000D01*
X735030Y281890D01*
X734990Y281765D01*
X734980Y281640D01*
Y279210D01*
X734950Y279180D01*
X734850Y279040D01*
X734830Y279000D01*
X734815Y278965D01*
X734795Y278925D01*
X734780Y278885D01*
X734770Y278845D01*
X734755Y278800D01*
X734750Y278760D01*
X734740Y278720D01*
X734735Y278675D01*
Y278635D01*
X734730Y278590D01*
X734735Y278545D01*
Y278505D01*
X734740Y278460D01*
X734750Y278420D01*
X734755Y278380D01*
X734770Y278335D01*
X734780Y278295D01*
X734795Y278255D01*
X734815Y278215D01*
X734830Y278180D01*
X734850Y278140D01*
X734950Y278000D01*
X734980Y277970D01*
Y275840D01*
X734990Y275715D01*
X735030Y275590D01*
X735090Y275480D01*
X735170Y275380D01*
X735270Y275300D01*
X735380Y275240D01*
X735505Y275200D01*
X735630Y275190D01*
X735755Y275200D01*
X735880Y275240D01*
X735990Y275300D01*
X736090Y275380D01*
X736170Y275480D01*
X736230Y275590D01*
X736270Y275715D01*
X736280Y275840D01*
Y277965D01*
X736310Y277995D01*
X736335Y278030D01*
X736365Y278065D01*
X736385Y278100D01*
X736410Y278135D01*
X736450Y278215D01*
X736495Y278335D01*
X736505Y278375D01*
X736515Y278420D01*
X736520Y278460D01*
X736530Y278505D01*
Y278675D01*
X736520Y278720D01*
X736515Y278760D01*
X736505Y278805D01*
X736495Y278845D01*
X736450Y278965D01*
X736410Y279045D01*
X736385Y279080D01*
X736365Y279115D01*
X736335Y279150D01*
X736310Y279185D01*
X736280Y279215D01*
Y281640D01*
X736270Y281765D01*
X736230Y281890D01*
X736170Y282000D01*
X736090Y282100D01*
X735990Y282180D01*
X735880Y282240D01*
X735755Y282280D01*
X735630Y282290D01*
G37*
G36*
G01X740355D02*
X740230Y282280D01*
X740105Y282240D01*
X739995Y282180D01*
X739895Y282100D01*
X739815Y282000D01*
X739755Y281890D01*
X739715Y281765D01*
X739705Y281640D01*
Y279210D01*
X739675Y279180D01*
X739575Y279040D01*
X739555Y279000D01*
X739540Y278965D01*
X739520Y278925D01*
X739505Y278885D01*
X739495Y278845D01*
X739480Y278800D01*
X739475Y278760D01*
X739465Y278720D01*
X739460Y278675D01*
Y278635D01*
X739455Y278590D01*
X739460Y278545D01*
Y278505D01*
X739465Y278460D01*
X739475Y278420D01*
X739480Y278380D01*
X739495Y278335D01*
X739505Y278295D01*
X739520Y278255D01*
X739540Y278215D01*
X739555Y278180D01*
X739575Y278140D01*
X739675Y278000D01*
X739705Y277970D01*
Y275840D01*
X739715Y275715D01*
X739755Y275590D01*
X739815Y275480D01*
X739895Y275380D01*
X739995Y275300D01*
X740105Y275240D01*
X740230Y275200D01*
X740355Y275190D01*
X740480Y275200D01*
X740605Y275240D01*
X740715Y275300D01*
X740815Y275380D01*
X740895Y275480D01*
X740955Y275590D01*
X740995Y275715D01*
X741005Y275840D01*
Y277965D01*
X741035Y277995D01*
X741060Y278030D01*
X741090Y278065D01*
X741110Y278100D01*
X741135Y278135D01*
X741175Y278215D01*
X741220Y278335D01*
X741230Y278375D01*
X741240Y278420D01*
X741245Y278460D01*
X741255Y278505D01*
Y278675D01*
X741245Y278720D01*
X741240Y278760D01*
X741230Y278805D01*
X741220Y278845D01*
X741175Y278965D01*
X741135Y279045D01*
X741110Y279080D01*
X741090Y279115D01*
X741060Y279150D01*
X741035Y279185D01*
X741005Y279215D01*
Y281640D01*
X740995Y281765D01*
X740955Y281890D01*
X740895Y282000D01*
X740815Y282100D01*
X740715Y282180D01*
X740605Y282240D01*
X740480Y282280D01*
X740355Y282290D01*
G37*
G36*
G01X745079D02*
X744954Y282280D01*
X744829Y282240D01*
X744719Y282180D01*
X744619Y282100D01*
X744539Y282000D01*
X744479Y281890D01*
X744439Y281765D01*
X744429Y281640D01*
Y279210D01*
X744399Y279180D01*
X744299Y279040D01*
X744279Y279000D01*
X744264Y278965D01*
X744244Y278925D01*
X744229Y278885D01*
X744219Y278845D01*
X744204Y278800D01*
X744199Y278760D01*
X744189Y278720D01*
X744184Y278675D01*
Y278635D01*
X744179Y278590D01*
X744184Y278545D01*
Y278505D01*
X744189Y278460D01*
X744199Y278420D01*
X744204Y278380D01*
X744219Y278335D01*
X744229Y278295D01*
X744244Y278255D01*
X744264Y278215D01*
X744279Y278180D01*
X744299Y278140D01*
X744399Y278000D01*
X744429Y277970D01*
Y275840D01*
X744439Y275715D01*
X744479Y275590D01*
X744539Y275480D01*
X744619Y275380D01*
X744719Y275300D01*
X744829Y275240D01*
X744954Y275200D01*
X745079Y275190D01*
X745204Y275200D01*
X745329Y275240D01*
X745439Y275300D01*
X745539Y275380D01*
X745619Y275480D01*
X745679Y275590D01*
X745719Y275715D01*
X745729Y275840D01*
Y277965D01*
X745759Y277995D01*
X745784Y278030D01*
X745814Y278065D01*
X745834Y278100D01*
X745859Y278135D01*
X745899Y278215D01*
X745944Y278335D01*
X745954Y278375D01*
X745964Y278420D01*
X745969Y278460D01*
X745979Y278505D01*
Y278675D01*
X745969Y278720D01*
X745964Y278760D01*
X745954Y278805D01*
X745944Y278845D01*
X745899Y278965D01*
X745859Y279045D01*
X745834Y279080D01*
X745814Y279115D01*
X745784Y279150D01*
X745759Y279185D01*
X745729Y279215D01*
Y281640D01*
X745719Y281765D01*
X745679Y281890D01*
X745619Y282000D01*
X745539Y282100D01*
X745439Y282180D01*
X745329Y282240D01*
X745204Y282280D01*
X745079Y282290D01*
G37*
G54D58*
X345500Y166500D03*
G54D86*
G01X-31497Y-1D02*
X26377D01*
G01X-35434Y3936D02*
G03X-31497Y-1I3937J0D01*
G01X-35434Y585039D02*
Y3936D01*
G01X-7874Y588976D02*
X-31497D01*
G01D02*
G03X-35434Y585039I0J-3937D01*
G01X-12698Y15747D02*
G03I-6988J0D01*
G01Y573227D02*
G03I-6988J0D01*
G01X826773Y286614D02*
G03X822836Y290551I-3937J0D01*
G01X3938D01*
G03X1Y286614I0J-3937D01*
G01Y61811D01*
G03X3938Y57874I3937J0D01*
G01X53938D01*
G02X57875Y53937I0J-3937D01*
G01Y12598D01*
X59844Y10629D01*
X336222D01*
X338190Y12598D01*
Y39960D01*
G02X345671I3740J0D01*
G01Y12598D01*
X347639Y10629D01*
X387797D01*
X389765Y12598D01*
Y42126D01*
G02X393702Y46063I3937J0D01*
G01X409450D01*
G02X413387Y42126I0J-3937D01*
G01Y3937D01*
G03X417324Y0I3937J0D01*
G01X822836D01*
G03X826773Y3937I0J3937D01*
G01Y286614D01*
G01X22440Y49999D02*
X-3937D01*
G01X-7874Y53936D02*
Y72440D01*
G01Y53936D02*
G03X-3937Y49999I3937J0D01*
G01X0Y72440D02*
G03X-7874I-3937J0D01*
G01Y103149D02*
G03X0I3937J0D01*
G01X-7874D02*
Y210235D01*
G01X0D02*
G03X-7874I-3937J0D01*
G01Y240944D02*
Y348031D01*
G01Y240944D02*
G03X0I3937J0D01*
G01X-3Y302361D02*
G03X3934Y298424I3937J0D01*
G01X822832D01*
G03X826769Y302361I0J3937D01*
G01Y527164D01*
G03X822832Y531101I-3937J0D01*
G01X772832D01*
G02X768895Y535038I0J3937D01*
G01Y576377D01*
X766926Y578346D01*
X490548D01*
X488580Y576377D01*
Y549015D01*
G02X481099I-3740J0D01*
G01Y576377D01*
X479131Y578346D01*
X438973D01*
X437005Y576377D01*
Y546849D01*
G02X433068Y542912I-3937J0D01*
G01X417320D01*
G02X413383Y546849I0J3937D01*
G01Y585038D01*
G03X409446Y588975I-3937J0D01*
G01X3934D01*
G03X-3Y585038I0J-3937D01*
G01Y302361D01*
G01X0Y348031D02*
G03X-7874I-3937J0D01*
G01Y378739D02*
Y485826D01*
G01Y378739D02*
G03X0I3937J0D01*
G01Y485826D02*
G03X-7874I-3937J0D01*
G01Y516535D02*
Y588976D01*
G01Y516535D02*
G03X0I3937J-1D01*
G01X26377Y-1D02*
Y46062D01*
G01D02*
G03X22440Y49999I-3937J0D01*
G01X70851Y-113865D02*
Y-96365D01*
G01X80021D02*
Y-113865D01*
G01Y-105115D02*
X70851D01*
G01X92936Y-113865D02*
X91626Y-113573D01*
X90316Y-112407D01*
X89442Y-110365D01*
X89006Y-108032D01*
X89442Y-105698D01*
X90316Y-103657D01*
X91626Y-102490D01*
X92936Y-102199D01*
X94246Y-102490D01*
X95556Y-103657D01*
X96429Y-105698D01*
X96648Y-108032D01*
X96429Y-110365D01*
X95556Y-112407D01*
X94246Y-113573D01*
X92936Y-113865D01*
G01X106724D02*
Y-102199D01*
G01Y-105115D02*
X107598Y-103657D01*
X108908Y-102490D01*
X110654Y-102199D01*
X112182Y-102490D01*
X113493Y-103657D01*
X114148Y-105698D01*
Y-113865D01*
G01X124661Y-105990D02*
X131648D01*
X130993Y-103948D01*
X129901Y-102782D01*
X128373Y-102199D01*
X126844Y-102490D01*
X125534Y-103365D01*
X124661Y-105407D01*
X124224Y-107157D01*
Y-108907D01*
X124661Y-110657D01*
X125753Y-112407D01*
X127063Y-113573D01*
X128591Y-113865D01*
X130119Y-113282D01*
X131648Y-111532D01*
G01X140851Y-119115D02*
X142161Y-119698D01*
X143908Y-119115D01*
X144999Y-117949D01*
X145873Y-116490D01*
X147182Y-111824D01*
X150021Y-102199D01*
G01X143034D02*
X147182Y-111824D01*
G01X182182Y-104532D02*
X183056Y-103657D01*
X183711Y-102199D01*
X184148Y-100156D01*
X183711Y-98407D01*
X182838Y-97240D01*
X181309Y-96365D01*
X175414D01*
Y-113865D01*
X182619D01*
X184148Y-112699D01*
X185021Y-110948D01*
X185458Y-108907D01*
X185021Y-106865D01*
X183711Y-105115D01*
X182182Y-104532D01*
X175414D01*
G01X201866Y-113865D02*
Y-102199D01*
G01Y-104240D02*
X200993Y-103074D01*
X199682Y-102490D01*
X198154Y-102199D01*
X196626Y-102782D01*
X195316Y-103948D01*
X194442Y-105698D01*
X194006Y-108032D01*
X194442Y-110365D01*
X195316Y-112115D01*
X196626Y-113282D01*
X198154Y-113865D01*
X199682Y-113573D01*
X200993Y-112699D01*
X201866Y-111532D01*
G01X219366Y-96365D02*
Y-113865D01*
G01Y-111241D02*
X218493Y-112699D01*
X217182Y-113573D01*
X215654Y-113865D01*
X213908Y-113282D01*
X212598Y-111824D01*
X211724Y-110074D01*
X211506Y-108032D01*
X211724Y-105990D01*
X212598Y-104240D01*
X213908Y-102782D01*
X215654Y-102199D01*
X217182Y-102490D01*
X218274Y-103074D01*
X219366Y-104240D01*
G01X229879Y-118240D02*
X231408Y-119407D01*
X233154Y-119698D01*
X234682Y-119407D01*
X235993Y-117949D01*
X236866Y-115907D01*
Y-102199D01*
G01Y-104532D02*
X235993Y-103365D01*
X234682Y-102490D01*
X233154Y-102199D01*
X231408Y-102782D01*
X230316Y-103948D01*
X229442Y-105990D01*
X229006Y-108032D01*
X229224Y-109782D01*
X230098Y-111824D01*
X231408Y-113282D01*
X233154Y-113865D01*
X234464Y-113573D01*
X235993Y-112407D01*
X236866Y-111241D01*
G01X247161Y-105990D02*
X254148D01*
X253493Y-103948D01*
X252401Y-102782D01*
X250873Y-102199D01*
X249344Y-102490D01*
X248034Y-103365D01*
X247161Y-105407D01*
X246724Y-107157D01*
Y-108907D01*
X247161Y-110657D01*
X248253Y-112407D01*
X249563Y-113573D01*
X251091Y-113865D01*
X252619Y-113282D01*
X254148Y-111532D01*
G01X264879Y-113865D02*
Y-102199D01*
G01Y-104532D02*
X265971Y-103365D01*
X267063Y-102490D01*
X268591Y-102199D01*
X269682Y-102490D01*
X270993Y-103365D01*
G01X298569Y-113865D02*
Y-96365D01*
X303809D01*
X305556Y-97240D01*
X306866Y-99282D01*
X307303Y-101615D01*
X306866Y-103948D01*
X305774Y-105698D01*
X303809Y-106574D01*
X298569D01*
G01X324366Y-113865D02*
Y-102199D01*
G01Y-104240D02*
X323493Y-103074D01*
X322182Y-102490D01*
X320654Y-102199D01*
X319126Y-102782D01*
X317816Y-103948D01*
X316942Y-105698D01*
X316506Y-108032D01*
X316942Y-110365D01*
X317816Y-112115D01*
X319126Y-113282D01*
X320654Y-113865D01*
X322182Y-113573D01*
X323493Y-112699D01*
X324366Y-111532D01*
G01X334224Y-113865D02*
Y-102199D01*
G01Y-105115D02*
X335098Y-103657D01*
X336408Y-102490D01*
X338154Y-102199D01*
X339682Y-102490D01*
X340993Y-103657D01*
X341648Y-105698D01*
Y-113865D01*
G01X355436Y-96365D02*
Y-113865D01*
G01X352379Y-102199D02*
X358493D01*
G01X369224Y-113865D02*
Y-96365D01*
G01Y-104823D02*
X370316Y-103365D01*
X371408Y-102490D01*
X373154Y-102199D01*
X374464Y-102490D01*
X375993Y-103657D01*
X376648Y-105407D01*
Y-113865D01*
G01X387161Y-105990D02*
X394148D01*
X393493Y-103948D01*
X392401Y-102782D01*
X390873Y-102199D01*
X389344Y-102490D01*
X388034Y-103365D01*
X387161Y-105407D01*
X386724Y-107157D01*
Y-108907D01*
X387161Y-110657D01*
X388253Y-112407D01*
X389563Y-113573D01*
X391091Y-113865D01*
X392619Y-113282D01*
X394148Y-111532D01*
G01X404879Y-113865D02*
Y-102199D01*
G01Y-104532D02*
X405971Y-103365D01*
X407063Y-102490D01*
X408591Y-102199D01*
X409682Y-102490D01*
X410993Y-103365D01*
G01X437259Y-113865D02*
Y-96365D01*
X442936Y-110948D01*
X448613Y-96365D01*
Y-113865D01*
G01X462182Y-104532D02*
X463056Y-103657D01*
X463711Y-102199D01*
X464148Y-100156D01*
X463711Y-98407D01*
X462838Y-97240D01*
X461309Y-96365D01*
X455414D01*
Y-113865D01*
X462619D01*
X464148Y-112699D01*
X465021Y-110948D01*
X465458Y-108907D01*
X465021Y-106865D01*
X463711Y-105115D01*
X462182Y-104532D01*
X455414D01*
G01X102756Y290550D02*
G03Y298424I0J3937D01*
G01X133465D02*
G03Y290550I0J-3937D01*
G01X227259Y-68865D02*
Y-51365D01*
X232936Y-65948D01*
X238613Y-51365D01*
Y-68865D01*
G01X250436D02*
X249126Y-68573D01*
X247816Y-67407D01*
X246942Y-65365D01*
X246506Y-63032D01*
X246942Y-60698D01*
X247816Y-58657D01*
X249126Y-57490D01*
X250436Y-57199D01*
X251746Y-57490D01*
X253056Y-58657D01*
X253929Y-60698D01*
X254148Y-63032D01*
X253929Y-65365D01*
X253056Y-67407D01*
X251746Y-68573D01*
X250436Y-68865D01*
G01X271866Y-51365D02*
Y-68865D01*
G01Y-66241D02*
X270993Y-67699D01*
X269682Y-68573D01*
X268154Y-68865D01*
X266408Y-68282D01*
X265098Y-66824D01*
X264224Y-65074D01*
X264006Y-63032D01*
X264224Y-60990D01*
X265098Y-59240D01*
X266408Y-57782D01*
X268154Y-57199D01*
X269682Y-57490D01*
X270774Y-58074D01*
X271866Y-59240D01*
G01X282161Y-60990D02*
X289148D01*
X288493Y-58948D01*
X287401Y-57782D01*
X285873Y-57199D01*
X284344Y-57490D01*
X283034Y-58365D01*
X282161Y-60407D01*
X281724Y-62157D01*
Y-63907D01*
X282161Y-65657D01*
X283253Y-67407D01*
X284563Y-68573D01*
X286091Y-68865D01*
X287619Y-68282D01*
X289148Y-66532D01*
G01X302936Y-68865D02*
Y-51365D01*
G01X299606Y290551D02*
G03Y298425I0J3937D01*
G01X330314D02*
G03Y290551I0J-3937D01*
G01X496457Y290550D02*
G03Y298424I0J3937D01*
G01X527166D02*
G03Y290550I0J-3937D01*
G01X542319Y-68865D02*
Y-51365D01*
X547559D01*
X549306Y-52240D01*
X550616Y-54282D01*
X551053Y-56615D01*
X550616Y-58948D01*
X549524Y-60698D01*
X547559Y-61574D01*
X542319D01*
G01X568989Y-52824D02*
X567679Y-51948D01*
X566151Y-51365D01*
X564404D01*
X562439Y-52240D01*
X560911Y-53698D01*
X559819Y-55449D01*
X558946Y-58365D01*
X558727Y-60990D01*
X559164Y-63615D01*
X559819Y-65365D01*
X561129Y-67115D01*
X562658Y-68282D01*
X564186Y-68865D01*
X565714D01*
X567243Y-68282D01*
X568553Y-67407D01*
X569645Y-66241D01*
G01X583432Y-59532D02*
X584306Y-58657D01*
X584961Y-57199D01*
X585398Y-55156D01*
X584961Y-53407D01*
X584088Y-52240D01*
X582559Y-51365D01*
X576664D01*
Y-68865D01*
X583869D01*
X585398Y-67699D01*
X586271Y-65948D01*
X586708Y-63907D01*
X586271Y-61865D01*
X584961Y-60115D01*
X583432Y-59532D01*
X576664D01*
G01X592636Y-74698D02*
X605736D01*
G01X611664Y-68865D02*
Y-51365D01*
X621708Y-68865D01*
Y-51365D01*
G01X634186Y-68865D02*
X632439Y-68573D01*
X630911Y-67407D01*
X629601Y-65657D01*
X628727Y-63615D01*
X628291Y-61282D01*
Y-58948D01*
X628727Y-56615D01*
X629601Y-54573D01*
X630911Y-52824D01*
X632439Y-51657D01*
X634186Y-51365D01*
X635932Y-51657D01*
X637461Y-52824D01*
X638771Y-54573D01*
X639645Y-56615D01*
X640081Y-58948D01*
Y-61282D01*
X639645Y-63615D01*
X638771Y-65657D01*
X637461Y-67407D01*
X635932Y-68573D01*
X634186Y-68865D01*
G01X555436Y-113865D02*
Y-96365D01*
X552816Y-99865D01*
G01Y-113865D02*
X558056D01*
G01X568133Y-110365D02*
X569442Y-112407D01*
X571189Y-113573D01*
X573154Y-113865D01*
X574901Y-113573D01*
X576648Y-112115D01*
X577739Y-110365D01*
X577958Y-108615D01*
X577521Y-106574D01*
X575993Y-105115D01*
X574464Y-104532D01*
X572499D01*
G01X574464D02*
X575774Y-103657D01*
X576866Y-102199D01*
X577303Y-100449D01*
X576866Y-98698D01*
X575774Y-97240D01*
X573809Y-96365D01*
X571844Y-96657D01*
X569879Y-97824D01*
G01X590436Y-113865D02*
Y-96365D01*
X587816Y-99865D01*
G01Y-113865D02*
X593056D01*
G01X603133Y-110365D02*
X604442Y-112407D01*
X606189Y-113573D01*
X608154Y-113865D01*
X609901Y-113573D01*
X611648Y-112115D01*
X612739Y-110365D01*
X612958Y-108615D01*
X612521Y-106574D01*
X610993Y-105115D01*
X609464Y-104532D01*
X607499D01*
G01X609464D02*
X610774Y-103657D01*
X611866Y-102199D01*
X612303Y-100449D01*
X611866Y-98698D01*
X610774Y-97240D01*
X608809Y-96365D01*
X606844Y-96657D01*
X604879Y-97824D01*
G01X625436Y-96365D02*
X623689Y-96948D01*
X622379Y-98407D01*
X621506Y-100156D01*
X620851Y-102490D01*
X620633Y-105115D01*
X620851Y-107740D01*
X621506Y-110074D01*
X622379Y-111824D01*
X623689Y-113282D01*
X625436Y-113865D01*
X627182Y-113282D01*
X628493Y-111824D01*
X629366Y-110074D01*
X630021Y-107740D01*
X630239Y-105115D01*
X630021Y-102490D01*
X629366Y-100156D01*
X628493Y-98407D01*
X627182Y-96948D01*
X625436Y-96365D01*
G01X685027Y-51365D02*
X690486Y-68865D01*
X695945Y-51365D01*
G01X712353Y-68865D02*
X703619D01*
Y-51365D01*
X712353D01*
G01X708859Y-59823D02*
X703619D01*
G01X721119Y-68865D02*
Y-51365D01*
X726578D01*
X728324Y-52240D01*
X729416Y-53407D01*
X729853Y-55740D01*
X729416Y-58074D01*
X728106Y-59532D01*
X726578Y-60407D01*
X721119D01*
G01X726578D02*
X729853Y-68865D01*
G01X742986Y-69448D02*
X742549Y-69157D01*
Y-68573D01*
X742986Y-68282D01*
X743423Y-68573D01*
Y-69157D01*
X742986Y-69448D01*
G01X693308Y290550D02*
G03Y298424I0J3937D01*
G01X707986Y-113865D02*
Y-96365D01*
X705366Y-99865D01*
G01Y-113865D02*
X710606D01*
G01X727232Y-104532D02*
X728106Y-103657D01*
X728761Y-102199D01*
X729198Y-100156D01*
X728761Y-98407D01*
X727888Y-97240D01*
X726359Y-96365D01*
X720464D01*
Y-113865D01*
X727669D01*
X729198Y-112699D01*
X730071Y-110948D01*
X730508Y-108907D01*
X730071Y-106865D01*
X728761Y-105115D01*
X727232Y-104532D01*
X720464D01*
G01X724016Y298424D02*
G03Y290550I0J-3937D01*
G01X800393Y588976D02*
Y542913D01*
G01D02*
G03X804330Y538976I3937J0D01*
G01X858267Y588976D02*
X800393D01*
G01X818569Y-51365D02*
Y-68865D01*
X827303D01*
G01X844366D02*
Y-57199D01*
G01Y-59240D02*
X843493Y-58074D01*
X842182Y-57490D01*
X840654Y-57199D01*
X839126Y-57782D01*
X837816Y-58948D01*
X836942Y-60698D01*
X836506Y-63032D01*
X836942Y-65365D01*
X837816Y-67115D01*
X839126Y-68282D01*
X840654Y-68865D01*
X842182Y-68573D01*
X843493Y-67699D01*
X844366Y-66532D01*
G01X853351Y-74115D02*
X854661Y-74698D01*
X856408Y-74115D01*
X857499Y-72949D01*
X858373Y-71490D01*
X859682Y-66824D01*
X862521Y-57199D01*
G01X855534D02*
X859682Y-66824D01*
G01X872161Y-60990D02*
X879148D01*
X878493Y-58948D01*
X877401Y-57782D01*
X875873Y-57199D01*
X874344Y-57490D01*
X873034Y-58365D01*
X872161Y-60407D01*
X871724Y-62157D01*
Y-63907D01*
X872161Y-65657D01*
X873253Y-67407D01*
X874563Y-68573D01*
X876091Y-68865D01*
X877619Y-68282D01*
X879148Y-66532D01*
G01X889879Y-68865D02*
Y-57199D01*
G01Y-59532D02*
X890971Y-58365D01*
X892063Y-57490D01*
X893591Y-57199D01*
X894682Y-57490D01*
X895993Y-58365D01*
G01X804330Y538976D02*
X830708D01*
G01X882440Y-104532D02*
X881566Y-103657D01*
X880911Y-102199D01*
X880474Y-100156D01*
X880911Y-98407D01*
X881784Y-97240D01*
X883313Y-96365D01*
X889208D01*
Y-113865D01*
X882003D01*
X880474Y-112699D01*
X879601Y-110948D01*
X879164Y-108907D01*
X879601Y-106865D01*
X880911Y-105115D01*
X882440Y-104532D01*
X889208D01*
G01X871271Y-111532D02*
X869524Y-112990D01*
X867559Y-113865D01*
X865813D01*
X864066Y-112990D01*
X862756Y-111532D01*
X862101Y-109490D01*
X862538Y-107449D01*
X863629Y-105698D01*
X865594Y-104532D01*
X868214Y-103948D01*
X869743Y-102782D01*
X870398Y-100740D01*
X869961Y-98698D01*
X868869Y-97240D01*
X867341Y-96365D01*
X865813D01*
X864284Y-96948D01*
X862974Y-98407D01*
G01X854863Y-113865D02*
Y-96365D01*
X849186Y-110948D01*
X843509Y-96365D01*
Y-113865D01*
G01X836489D02*
Y-96365D01*
X832123D01*
X830376Y-97240D01*
X829066Y-98407D01*
X827974Y-100156D01*
X827101Y-102199D01*
X826883Y-105115D01*
X827101Y-108032D01*
X827974Y-110074D01*
X829066Y-111824D01*
X830376Y-112990D01*
X832123Y-113865D01*
X836489D01*
G01X834645Y72440D02*
G03X826771I-3937J0D01*
G01Y103149D02*
G03X834645I3937J0D01*
G01Y210235D02*
G03X826771I-3937J0D01*
G01Y240944D02*
G03X834645I3937J0D01*
G01Y348031D02*
G03X826771I-3937J0D01*
G01Y378739D02*
G03X834645I3937J0D01*
G01Y485826D02*
G03X826771I-3937J0D01*
G01Y516535D02*
G03X834645I3937J-1D01*
G01Y535039D02*
G03X830708Y538976I-3937J0D01*
G01X834645Y72440D02*
Y-1D01*
G01D02*
X858267D01*
G01X853444Y15747D02*
G03I-6988J0D01*
G01X834645Y210235D02*
Y103149D01*
G01Y348031D02*
Y240944D01*
G01Y485826D02*
Y378739D01*
G01Y535039D02*
Y516535D01*
G01X853444Y573227D02*
G03I-6988J0D01*
G01X862204Y3936D02*
Y585039D01*
G01X858267Y-1D02*
G03X862204Y3936I0J3937D01*
G01Y585039D02*
G03X858267Y588976I-3937J0D01*
G01X943619Y-110365D02*
X944711Y-112115D01*
X946021Y-113282D01*
X947549Y-113865D01*
X949296Y-113282D01*
X950606Y-112115D01*
X951916Y-110365D01*
X952353Y-108032D01*
Y-96365D01*
G01X965486Y-113865D02*
X963739Y-113573D01*
X962211Y-112407D01*
X960901Y-110657D01*
X960027Y-108615D01*
X959591Y-106282D01*
Y-103948D01*
X960027Y-101615D01*
X960901Y-99573D01*
X962211Y-97824D01*
X963739Y-96657D01*
X965486Y-96365D01*
X967232Y-96657D01*
X968761Y-97824D01*
X970071Y-99573D01*
X970945Y-101615D01*
X971381Y-103948D01*
Y-106282D01*
X970945Y-108615D01*
X970071Y-110657D01*
X968761Y-112407D01*
X967232Y-113573D01*
X965486Y-113865D01*
G01X978401Y-111532D02*
X980148Y-112990D01*
X982113Y-113865D01*
X983859D01*
X985606Y-112990D01*
X986916Y-111532D01*
X987571Y-109490D01*
X987134Y-107449D01*
X986043Y-105698D01*
X984078Y-104532D01*
X981458Y-103948D01*
X979929Y-102782D01*
X979274Y-100740D01*
X979711Y-98698D01*
X980803Y-97240D01*
X982331Y-96365D01*
X983859D01*
X985388Y-96948D01*
X986698Y-98407D01*
G01X1004853Y-113865D02*
X996119D01*
Y-96365D01*
X1004853D01*
G01X1001359Y-104823D02*
X996119D01*
G01X1013619Y-113865D02*
Y-96365D01*
X1018859D01*
X1020606Y-97240D01*
X1021916Y-99282D01*
X1022353Y-101615D01*
X1021916Y-103948D01*
X1020824Y-105698D01*
X1018859Y-106574D01*
X1013619D01*
G01X1030901Y-113865D02*
Y-96365D01*
G01X1040071D02*
Y-113865D01*
G01Y-105115D02*
X1030901D01*
G01X1066119Y-96365D02*
Y-113865D01*
X1074853D01*
G01X1082527D02*
X1087986Y-96365D01*
X1093445Y-113865D01*
G01X1091479Y-107740D02*
X1084492D01*
G01X1100683Y-96365D02*
Y-108907D01*
X1101556Y-111532D01*
X1103303Y-113282D01*
X1105486Y-113865D01*
X1107669Y-113282D01*
X1109416Y-111532D01*
X1110289Y-108907D01*
Y-96365D01*
G01X960683Y-68865D02*
Y-51365D01*
X965049D01*
X966796Y-52240D01*
X968106Y-53407D01*
X969198Y-55156D01*
X970071Y-57199D01*
X970289Y-60115D01*
X970071Y-63032D01*
X969198Y-65074D01*
X968106Y-66824D01*
X966796Y-67990D01*
X965049Y-68865D01*
X960683D01*
G01X979711Y-60990D02*
X986698D01*
X986043Y-58948D01*
X984951Y-57782D01*
X983423Y-57199D01*
X981894Y-57490D01*
X980584Y-58365D01*
X979711Y-60407D01*
X979274Y-62157D01*
Y-63907D01*
X979711Y-65657D01*
X980803Y-67407D01*
X982113Y-68573D01*
X983641Y-68865D01*
X985169Y-68282D01*
X986698Y-66532D01*
G01X997211Y-66824D02*
X998303Y-67990D01*
X999831Y-68865D01*
X1001141D01*
X1002451Y-68282D01*
X1003324Y-67407D01*
X1003761Y-66241D01*
X1003543Y-64490D01*
X1002669Y-63615D01*
X998739Y-61865D01*
X997866Y-59823D01*
X998303Y-58365D01*
X999176Y-57490D01*
X1000486Y-57199D01*
X1001796Y-57490D01*
X1003106Y-58365D01*
G01X1017986Y-57199D02*
Y-68865D01*
G01Y-52532D02*
X1017549Y-52240D01*
Y-51657D01*
X1017986Y-51365D01*
X1018423Y-51657D01*
Y-52240D01*
X1017986Y-52532D01*
G01X1032429Y-73240D02*
X1033958Y-74407D01*
X1035704Y-74698D01*
X1037232Y-74407D01*
X1038543Y-72949D01*
X1039416Y-70907D01*
Y-57199D01*
G01Y-59532D02*
X1038543Y-58365D01*
X1037232Y-57490D01*
X1035704Y-57199D01*
X1033958Y-57782D01*
X1032866Y-58948D01*
X1031992Y-60990D01*
X1031556Y-63032D01*
X1031774Y-64782D01*
X1032648Y-66824D01*
X1033958Y-68282D01*
X1035704Y-68865D01*
X1037014Y-68573D01*
X1038543Y-67407D01*
X1039416Y-66241D01*
G01X1049274Y-68865D02*
Y-57199D01*
G01Y-60115D02*
X1050148Y-58657D01*
X1051458Y-57490D01*
X1053204Y-57199D01*
X1054732Y-57490D01*
X1056043Y-58657D01*
X1056698Y-60698D01*
Y-68865D01*
G01X1067211Y-60990D02*
X1074198D01*
X1073543Y-58948D01*
X1072451Y-57782D01*
X1070923Y-57199D01*
X1069394Y-57490D01*
X1068084Y-58365D01*
X1067211Y-60407D01*
X1066774Y-62157D01*
Y-63907D01*
X1067211Y-65657D01*
X1068303Y-67407D01*
X1069613Y-68573D01*
X1071141Y-68865D01*
X1072669Y-68282D01*
X1074198Y-66532D01*
G01X1084929Y-68865D02*
Y-57199D01*
G01Y-59532D02*
X1086021Y-58365D01*
X1087113Y-57490D01*
X1088641Y-57199D01*
X1089732Y-57490D01*
X1091043Y-58365D01*
G01X1131686Y-113865D02*
Y-96365D01*
X1129066Y-99865D01*
G01Y-113865D02*
X1134306D01*
G01X1149186D02*
Y-96365D01*
X1146566Y-99865D01*
G01Y-113865D02*
X1151806D01*
G01X1162756Y-114448D02*
X1170616Y-96365D01*
G01X1184186Y-113865D02*
Y-96365D01*
X1181566Y-99865D01*
G01Y-113865D02*
X1186806D01*
G01X1196883Y-110365D02*
X1198192Y-112407D01*
X1199939Y-113573D01*
X1201904Y-113865D01*
X1203651Y-113573D01*
X1205398Y-112115D01*
X1206489Y-110365D01*
X1206708Y-108615D01*
X1206271Y-106574D01*
X1204743Y-105115D01*
X1203214Y-104532D01*
X1201249D01*
G01X1203214D02*
X1204524Y-103657D01*
X1205616Y-102199D01*
X1206053Y-100449D01*
X1205616Y-98698D01*
X1204524Y-97240D01*
X1202559Y-96365D01*
X1200594Y-96657D01*
X1198629Y-97824D01*
G01X1215256Y-114448D02*
X1223116Y-96365D01*
G01X1232538Y-99282D02*
X1233848Y-97532D01*
X1235376Y-96657D01*
X1237123Y-96365D01*
X1239306Y-96948D01*
X1240834Y-98407D01*
X1241271Y-100156D01*
X1241053Y-101907D01*
X1240179Y-103365D01*
X1235813Y-106282D01*
X1233848Y-108323D01*
X1232538Y-111241D01*
X1232101Y-113865D01*
X1241271D01*
G01X1254186Y-96365D02*
X1252439Y-96948D01*
X1251129Y-98407D01*
X1250256Y-100156D01*
X1249601Y-102490D01*
X1249383Y-105115D01*
X1249601Y-107740D01*
X1250256Y-110074D01*
X1251129Y-111824D01*
X1252439Y-113282D01*
X1254186Y-113865D01*
X1255932Y-113282D01*
X1257243Y-111824D01*
X1258116Y-110074D01*
X1258771Y-107740D01*
X1258989Y-105115D01*
X1258771Y-102490D01*
X1258116Y-100156D01*
X1257243Y-98407D01*
X1255932Y-96948D01*
X1254186Y-96365D01*
G01X1271686Y-113865D02*
Y-96365D01*
X1269066Y-99865D01*
G01Y-113865D02*
X1274306D01*
G01X1291806D02*
Y-96365D01*
X1283727Y-108907D01*
X1294645D01*
G01X1179383Y-68865D02*
Y-51365D01*
X1183749D01*
X1185496Y-52240D01*
X1186806Y-53407D01*
X1187898Y-55156D01*
X1188771Y-57199D01*
X1188989Y-60115D01*
X1188771Y-63032D01*
X1187898Y-65074D01*
X1186806Y-66824D01*
X1185496Y-67990D01*
X1183749Y-68865D01*
X1179383D01*
G01X1205616D02*
Y-57199D01*
G01Y-59240D02*
X1204743Y-58074D01*
X1203432Y-57490D01*
X1201904Y-57199D01*
X1200376Y-57782D01*
X1199066Y-58948D01*
X1198192Y-60698D01*
X1197756Y-63032D01*
X1198192Y-65365D01*
X1199066Y-67115D01*
X1200376Y-68282D01*
X1201904Y-68865D01*
X1203432Y-68573D01*
X1204743Y-67699D01*
X1205616Y-66532D01*
G01X1219186Y-51365D02*
Y-68865D01*
G01X1216129Y-57199D02*
X1222243D01*
G01X1233411Y-60990D02*
X1240398D01*
X1239743Y-58948D01*
X1238651Y-57782D01*
X1237123Y-57199D01*
X1235594Y-57490D01*
X1234284Y-58365D01*
X1233411Y-60407D01*
X1232974Y-62157D01*
Y-63907D01*
X1233411Y-65657D01*
X1234503Y-67407D01*
X1235813Y-68573D01*
X1237341Y-68865D01*
X1238869Y-68282D01*
X1240398Y-66532D01*
G54D68*
X482480Y70042D03*
X476575Y215354D03*
X777362Y70042D03*
X771457Y215354D03*
G54D59*
X372376Y246689D03*
Y270311D03*
X387624Y246689D03*
Y270311D03*
G36*
G01X501772Y282290D02*
X501647Y282280D01*
X501522Y282240D01*
X501412Y282180D01*
X501312Y282100D01*
X501232Y282000D01*
X501172Y281890D01*
X501132Y281765D01*
X501122Y281640D01*
Y278210D01*
X501092Y278180D01*
X500992Y278040D01*
X500972Y278000D01*
X500957Y277965D01*
X500937Y277925D01*
X500922Y277885D01*
X500912Y277845D01*
X500897Y277800D01*
X500892Y277760D01*
X500882Y277720D01*
X500877Y277675D01*
Y277635D01*
X500872Y277590D01*
X500877Y277545D01*
Y277505D01*
X500882Y277460D01*
X500892Y277420D01*
X500897Y277380D01*
X500912Y277335D01*
X500922Y277295D01*
X500937Y277255D01*
X500957Y277215D01*
X500972Y277180D01*
X500992Y277140D01*
X501092Y277000D01*
X501122Y276970D01*
Y275840D01*
X501132Y275715D01*
X501172Y275590D01*
X501232Y275480D01*
X501312Y275380D01*
X501412Y275300D01*
X501522Y275240D01*
X501647Y275200D01*
X501772Y275190D01*
X501897Y275200D01*
X502022Y275240D01*
X502132Y275300D01*
X502232Y275380D01*
X502312Y275480D01*
X502372Y275590D01*
X502412Y275715D01*
X502422Y275840D01*
Y276970D01*
X502452Y277000D01*
X502552Y277140D01*
X502572Y277180D01*
X502587Y277215D01*
X502607Y277255D01*
X502622Y277295D01*
X502632Y277335D01*
X502647Y277380D01*
X502652Y277420D01*
X502662Y277460D01*
X502667Y277505D01*
Y277545D01*
X502672Y277590D01*
X502667Y277635D01*
Y277675D01*
X502662Y277720D01*
X502652Y277760D01*
X502647Y277800D01*
X502632Y277845D01*
X502622Y277885D01*
X502607Y277925D01*
X502587Y277965D01*
X502572Y278000D01*
X502552Y278040D01*
X502452Y278180D01*
X502422Y278210D01*
Y281640D01*
X502412Y281765D01*
X502372Y281890D01*
X502312Y282000D01*
X502232Y282100D01*
X502132Y282180D01*
X502022Y282240D01*
X501897Y282280D01*
X501772Y282290D01*
G37*
G36*
G01X506496D02*
X506371Y282280D01*
X506246Y282240D01*
X506136Y282180D01*
X506036Y282100D01*
X505956Y282000D01*
X505896Y281890D01*
X505856Y281765D01*
X505846Y281640D01*
Y278210D01*
X505816Y278180D01*
X505716Y278040D01*
X505696Y278000D01*
X505681Y277965D01*
X505661Y277925D01*
X505646Y277885D01*
X505636Y277845D01*
X505621Y277800D01*
X505616Y277760D01*
X505606Y277720D01*
X505601Y277675D01*
Y277635D01*
X505596Y277590D01*
X505601Y277545D01*
Y277505D01*
X505606Y277460D01*
X505616Y277420D01*
X505621Y277380D01*
X505636Y277335D01*
X505646Y277295D01*
X505661Y277255D01*
X505681Y277215D01*
X505696Y277180D01*
X505716Y277140D01*
X505816Y277000D01*
X505846Y276970D01*
Y275840D01*
X505856Y275715D01*
X505896Y275590D01*
X505956Y275480D01*
X506036Y275380D01*
X506136Y275300D01*
X506246Y275240D01*
X506371Y275200D01*
X506496Y275190D01*
X506621Y275200D01*
X506746Y275240D01*
X506856Y275300D01*
X506956Y275380D01*
X507036Y275480D01*
X507096Y275590D01*
X507136Y275715D01*
X507146Y275840D01*
Y276970D01*
X507176Y277000D01*
X507276Y277140D01*
X507296Y277180D01*
X507311Y277215D01*
X507331Y277255D01*
X507346Y277295D01*
X507356Y277335D01*
X507371Y277380D01*
X507376Y277420D01*
X507386Y277460D01*
X507391Y277505D01*
Y277545D01*
X507396Y277590D01*
X507391Y277635D01*
Y277675D01*
X507386Y277720D01*
X507376Y277760D01*
X507371Y277800D01*
X507356Y277845D01*
X507346Y277885D01*
X507331Y277925D01*
X507311Y277965D01*
X507296Y278000D01*
X507276Y278040D01*
X507176Y278180D01*
X507146Y278210D01*
Y281640D01*
X507136Y281765D01*
X507096Y281890D01*
X507036Y282000D01*
X506956Y282100D01*
X506856Y282180D01*
X506746Y282240D01*
X506621Y282280D01*
X506496Y282290D01*
G37*
G36*
G01X511221D02*
X511096Y282280D01*
X510971Y282240D01*
X510861Y282180D01*
X510761Y282100D01*
X510681Y282000D01*
X510621Y281890D01*
X510581Y281765D01*
X510571Y281640D01*
Y278210D01*
X510541Y278180D01*
X510441Y278040D01*
X510421Y278000D01*
X510406Y277965D01*
X510386Y277925D01*
X510371Y277885D01*
X510361Y277845D01*
X510346Y277800D01*
X510341Y277760D01*
X510331Y277720D01*
X510326Y277675D01*
Y277635D01*
X510321Y277590D01*
X510326Y277545D01*
Y277505D01*
X510331Y277460D01*
X510341Y277420D01*
X510346Y277380D01*
X510361Y277335D01*
X510371Y277295D01*
X510386Y277255D01*
X510406Y277215D01*
X510421Y277180D01*
X510441Y277140D01*
X510541Y277000D01*
X510571Y276970D01*
Y275840D01*
X510581Y275715D01*
X510621Y275590D01*
X510681Y275480D01*
X510761Y275380D01*
X510861Y275300D01*
X510971Y275240D01*
X511096Y275200D01*
X511221Y275190D01*
X511346Y275200D01*
X511471Y275240D01*
X511581Y275300D01*
X511681Y275380D01*
X511761Y275480D01*
X511821Y275590D01*
X511861Y275715D01*
X511871Y275840D01*
Y276970D01*
X511901Y277000D01*
X512001Y277140D01*
X512021Y277180D01*
X512036Y277215D01*
X512056Y277255D01*
X512071Y277295D01*
X512081Y277335D01*
X512096Y277380D01*
X512101Y277420D01*
X512111Y277460D01*
X512116Y277505D01*
Y277545D01*
X512121Y277590D01*
X512116Y277635D01*
Y277675D01*
X512111Y277720D01*
X512101Y277760D01*
X512096Y277800D01*
X512081Y277845D01*
X512071Y277885D01*
X512056Y277925D01*
X512036Y277965D01*
X512021Y278000D01*
X512001Y278040D01*
X511901Y278180D01*
X511871Y278210D01*
Y281640D01*
X511861Y281765D01*
X511821Y281890D01*
X511761Y282000D01*
X511681Y282100D01*
X511581Y282180D01*
X511471Y282240D01*
X511346Y282280D01*
X511221Y282290D01*
G37*
G36*
G01X515945D02*
X515820Y282280D01*
X515695Y282240D01*
X515585Y282180D01*
X515485Y282100D01*
X515405Y282000D01*
X515345Y281890D01*
X515305Y281765D01*
X515295Y281640D01*
Y278210D01*
X515265Y278180D01*
X515165Y278040D01*
X515145Y278000D01*
X515130Y277965D01*
X515110Y277925D01*
X515095Y277885D01*
X515085Y277845D01*
X515070Y277800D01*
X515065Y277760D01*
X515055Y277720D01*
X515050Y277675D01*
Y277635D01*
X515045Y277590D01*
X515050Y277545D01*
Y277505D01*
X515055Y277460D01*
X515065Y277420D01*
X515070Y277380D01*
X515085Y277335D01*
X515095Y277295D01*
X515110Y277255D01*
X515130Y277215D01*
X515145Y277180D01*
X515165Y277140D01*
X515265Y277000D01*
X515295Y276970D01*
Y275840D01*
X515305Y275715D01*
X515345Y275590D01*
X515405Y275480D01*
X515485Y275380D01*
X515585Y275300D01*
X515695Y275240D01*
X515820Y275200D01*
X515945Y275190D01*
X516070Y275200D01*
X516195Y275240D01*
X516305Y275300D01*
X516405Y275380D01*
X516485Y275480D01*
X516545Y275590D01*
X516585Y275715D01*
X516595Y275840D01*
Y276970D01*
X516625Y277000D01*
X516725Y277140D01*
X516745Y277180D01*
X516760Y277215D01*
X516780Y277255D01*
X516795Y277295D01*
X516805Y277335D01*
X516820Y277380D01*
X516825Y277420D01*
X516835Y277460D01*
X516840Y277505D01*
Y277545D01*
X516845Y277590D01*
X516840Y277635D01*
Y277675D01*
X516835Y277720D01*
X516825Y277760D01*
X516820Y277800D01*
X516805Y277845D01*
X516795Y277885D01*
X516780Y277925D01*
X516760Y277965D01*
X516745Y278000D01*
X516725Y278040D01*
X516625Y278180D01*
X516595Y278210D01*
Y281640D01*
X516585Y281765D01*
X516545Y281890D01*
X516485Y282000D01*
X516405Y282100D01*
X516305Y282180D01*
X516195Y282240D01*
X516070Y282280D01*
X515945Y282290D01*
G37*
G36*
G01X520670D02*
X520545Y282280D01*
X520420Y282240D01*
X520310Y282180D01*
X520210Y282100D01*
X520130Y282000D01*
X520070Y281890D01*
X520030Y281765D01*
X520020Y281640D01*
Y278210D01*
X519990Y278180D01*
X519890Y278040D01*
X519870Y278000D01*
X519855Y277965D01*
X519835Y277925D01*
X519820Y277885D01*
X519810Y277845D01*
X519795Y277800D01*
X519790Y277760D01*
X519780Y277720D01*
X519775Y277675D01*
Y277635D01*
X519770Y277590D01*
X519775Y277545D01*
Y277505D01*
X519780Y277460D01*
X519790Y277420D01*
X519795Y277380D01*
X519810Y277335D01*
X519820Y277295D01*
X519835Y277255D01*
X519855Y277215D01*
X519870Y277180D01*
X519890Y277140D01*
X519990Y277000D01*
X520020Y276970D01*
Y275840D01*
X520030Y275715D01*
X520070Y275590D01*
X520130Y275480D01*
X520210Y275380D01*
X520310Y275300D01*
X520420Y275240D01*
X520545Y275200D01*
X520670Y275190D01*
X520795Y275200D01*
X520920Y275240D01*
X521030Y275300D01*
X521130Y275380D01*
X521210Y275480D01*
X521270Y275590D01*
X521310Y275715D01*
X521320Y275840D01*
Y276970D01*
X521350Y277000D01*
X521450Y277140D01*
X521470Y277180D01*
X521485Y277215D01*
X521505Y277255D01*
X521520Y277295D01*
X521530Y277335D01*
X521545Y277380D01*
X521550Y277420D01*
X521560Y277460D01*
X521565Y277505D01*
Y277545D01*
X521570Y277590D01*
X521565Y277635D01*
Y277675D01*
X521560Y277720D01*
X521550Y277760D01*
X521545Y277800D01*
X521530Y277845D01*
X521520Y277885D01*
X521505Y277925D01*
X521485Y277965D01*
X521470Y278000D01*
X521450Y278040D01*
X521350Y278180D01*
X521320Y278210D01*
Y281640D01*
X521310Y281765D01*
X521270Y281890D01*
X521210Y282000D01*
X521130Y282100D01*
X521030Y282180D01*
X520920Y282240D01*
X520795Y282280D01*
X520670Y282290D01*
G37*
G36*
G01X525394D02*
X525269Y282280D01*
X525144Y282240D01*
X525034Y282180D01*
X524934Y282100D01*
X524854Y282000D01*
X524794Y281890D01*
X524754Y281765D01*
X524744Y281640D01*
Y278210D01*
X524714Y278180D01*
X524614Y278040D01*
X524594Y278000D01*
X524579Y277965D01*
X524559Y277925D01*
X524544Y277885D01*
X524534Y277845D01*
X524519Y277800D01*
X524514Y277760D01*
X524504Y277720D01*
X524499Y277675D01*
Y277635D01*
X524494Y277590D01*
X524499Y277545D01*
Y277505D01*
X524504Y277460D01*
X524514Y277420D01*
X524519Y277380D01*
X524534Y277335D01*
X524544Y277295D01*
X524559Y277255D01*
X524579Y277215D01*
X524594Y277180D01*
X524614Y277140D01*
X524714Y277000D01*
X524744Y276970D01*
Y275840D01*
X524754Y275715D01*
X524794Y275590D01*
X524854Y275480D01*
X524934Y275380D01*
X525034Y275300D01*
X525144Y275240D01*
X525269Y275200D01*
X525394Y275190D01*
X525519Y275200D01*
X525644Y275240D01*
X525754Y275300D01*
X525854Y275380D01*
X525934Y275480D01*
X525994Y275590D01*
X526034Y275715D01*
X526044Y275840D01*
Y276970D01*
X526074Y277000D01*
X526174Y277140D01*
X526194Y277180D01*
X526209Y277215D01*
X526229Y277255D01*
X526244Y277295D01*
X526254Y277335D01*
X526269Y277380D01*
X526274Y277420D01*
X526284Y277460D01*
X526289Y277505D01*
Y277545D01*
X526294Y277590D01*
X526289Y277635D01*
Y277675D01*
X526284Y277720D01*
X526274Y277760D01*
X526269Y277800D01*
X526254Y277845D01*
X526244Y277885D01*
X526229Y277925D01*
X526209Y277965D01*
X526194Y278000D01*
X526174Y278040D01*
X526074Y278180D01*
X526044Y278210D01*
Y281640D01*
X526034Y281765D01*
X525994Y281890D01*
X525934Y282000D01*
X525854Y282100D01*
X525754Y282180D01*
X525644Y282240D01*
X525519Y282280D01*
X525394Y282290D01*
G37*
G36*
G01X530118D02*
X529993Y282280D01*
X529868Y282240D01*
X529758Y282180D01*
X529658Y282100D01*
X529578Y282000D01*
X529518Y281890D01*
X529478Y281765D01*
X529468Y281640D01*
Y278210D01*
X529438Y278180D01*
X529338Y278040D01*
X529318Y278000D01*
X529303Y277965D01*
X529283Y277925D01*
X529268Y277885D01*
X529258Y277845D01*
X529243Y277800D01*
X529238Y277760D01*
X529228Y277720D01*
X529223Y277675D01*
Y277635D01*
X529218Y277590D01*
X529223Y277545D01*
Y277505D01*
X529228Y277460D01*
X529238Y277420D01*
X529243Y277380D01*
X529258Y277335D01*
X529268Y277295D01*
X529283Y277255D01*
X529303Y277215D01*
X529318Y277180D01*
X529338Y277140D01*
X529438Y277000D01*
X529468Y276970D01*
Y275840D01*
X529478Y275715D01*
X529518Y275590D01*
X529578Y275480D01*
X529658Y275380D01*
X529758Y275300D01*
X529868Y275240D01*
X529993Y275200D01*
X530118Y275190D01*
X530243Y275200D01*
X530368Y275240D01*
X530478Y275300D01*
X530578Y275380D01*
X530658Y275480D01*
X530718Y275590D01*
X530758Y275715D01*
X530768Y275840D01*
Y276970D01*
X530798Y277000D01*
X530898Y277140D01*
X530918Y277180D01*
X530933Y277215D01*
X530953Y277255D01*
X530968Y277295D01*
X530978Y277335D01*
X530993Y277380D01*
X530998Y277420D01*
X531008Y277460D01*
X531013Y277505D01*
Y277545D01*
X531018Y277590D01*
X531013Y277635D01*
Y277675D01*
X531008Y277720D01*
X530998Y277760D01*
X530993Y277800D01*
X530978Y277845D01*
X530968Y277885D01*
X530953Y277925D01*
X530933Y277965D01*
X530918Y278000D01*
X530898Y278040D01*
X530798Y278180D01*
X530768Y278210D01*
Y281640D01*
X530758Y281765D01*
X530718Y281890D01*
X530658Y282000D01*
X530578Y282100D01*
X530478Y282180D01*
X530368Y282240D01*
X530243Y282280D01*
X530118Y282290D01*
G37*
G36*
G01X534843D02*
X534718Y282280D01*
X534593Y282240D01*
X534483Y282180D01*
X534383Y282100D01*
X534303Y282000D01*
X534243Y281890D01*
X534203Y281765D01*
X534193Y281640D01*
Y278210D01*
X534163Y278180D01*
X534063Y278040D01*
X534043Y278000D01*
X534028Y277965D01*
X534008Y277925D01*
X533993Y277885D01*
X533983Y277845D01*
X533968Y277800D01*
X533963Y277760D01*
X533953Y277720D01*
X533948Y277675D01*
Y277635D01*
X533943Y277590D01*
X533948Y277545D01*
Y277505D01*
X533953Y277460D01*
X533963Y277420D01*
X533968Y277380D01*
X533983Y277335D01*
X533993Y277295D01*
X534008Y277255D01*
X534028Y277215D01*
X534043Y277180D01*
X534063Y277140D01*
X534163Y277000D01*
X534193Y276970D01*
Y275840D01*
X534203Y275715D01*
X534243Y275590D01*
X534303Y275480D01*
X534383Y275380D01*
X534483Y275300D01*
X534593Y275240D01*
X534718Y275200D01*
X534843Y275190D01*
X534968Y275200D01*
X535093Y275240D01*
X535203Y275300D01*
X535303Y275380D01*
X535383Y275480D01*
X535443Y275590D01*
X535483Y275715D01*
X535493Y275840D01*
Y276970D01*
X535523Y277000D01*
X535623Y277140D01*
X535643Y277180D01*
X535658Y277215D01*
X535678Y277255D01*
X535693Y277295D01*
X535703Y277335D01*
X535718Y277380D01*
X535723Y277420D01*
X535733Y277460D01*
X535738Y277505D01*
Y277545D01*
X535743Y277590D01*
X535738Y277635D01*
Y277675D01*
X535733Y277720D01*
X535723Y277760D01*
X535718Y277800D01*
X535703Y277845D01*
X535693Y277885D01*
X535678Y277925D01*
X535658Y277965D01*
X535643Y278000D01*
X535623Y278040D01*
X535523Y278180D01*
X535493Y278210D01*
Y281640D01*
X535483Y281765D01*
X535443Y281890D01*
X535383Y282000D01*
X535303Y282100D01*
X535203Y282180D01*
X535093Y282240D01*
X534968Y282280D01*
X534843Y282290D01*
G37*
G36*
G01X539567D02*
X539442Y282280D01*
X539317Y282240D01*
X539207Y282180D01*
X539107Y282100D01*
X539027Y282000D01*
X538967Y281890D01*
X538927Y281765D01*
X538917Y281640D01*
Y278210D01*
X538887Y278180D01*
X538787Y278040D01*
X538767Y278000D01*
X538752Y277965D01*
X538732Y277925D01*
X538717Y277885D01*
X538707Y277845D01*
X538692Y277800D01*
X538687Y277760D01*
X538677Y277720D01*
X538672Y277675D01*
Y277635D01*
X538667Y277590D01*
X538672Y277545D01*
Y277505D01*
X538677Y277460D01*
X538687Y277420D01*
X538692Y277380D01*
X538707Y277335D01*
X538717Y277295D01*
X538732Y277255D01*
X538752Y277215D01*
X538767Y277180D01*
X538787Y277140D01*
X538887Y277000D01*
X538917Y276970D01*
Y275840D01*
X538927Y275715D01*
X538967Y275590D01*
X539027Y275480D01*
X539107Y275380D01*
X539207Y275300D01*
X539317Y275240D01*
X539442Y275200D01*
X539567Y275190D01*
X539692Y275200D01*
X539817Y275240D01*
X539927Y275300D01*
X540027Y275380D01*
X540107Y275480D01*
X540167Y275590D01*
X540207Y275715D01*
X540217Y275840D01*
Y276970D01*
X540247Y277000D01*
X540347Y277140D01*
X540367Y277180D01*
X540382Y277215D01*
X540402Y277255D01*
X540417Y277295D01*
X540427Y277335D01*
X540442Y277380D01*
X540447Y277420D01*
X540457Y277460D01*
X540462Y277505D01*
Y277545D01*
X540467Y277590D01*
X540462Y277635D01*
Y277675D01*
X540457Y277720D01*
X540447Y277760D01*
X540442Y277800D01*
X540427Y277845D01*
X540417Y277885D01*
X540402Y277925D01*
X540382Y277965D01*
X540367Y278000D01*
X540347Y278040D01*
X540247Y278180D01*
X540217Y278210D01*
Y281640D01*
X540207Y281765D01*
X540167Y281890D01*
X540107Y282000D01*
X540027Y282100D01*
X539927Y282180D01*
X539817Y282240D01*
X539692Y282280D01*
X539567Y282290D01*
G37*
G36*
G01X544292D02*
X544167Y282280D01*
X544042Y282240D01*
X543932Y282180D01*
X543832Y282100D01*
X543752Y282000D01*
X543692Y281890D01*
X543652Y281765D01*
X543642Y281640D01*
Y278210D01*
X543612Y278180D01*
X543512Y278040D01*
X543492Y278000D01*
X543477Y277965D01*
X543457Y277925D01*
X543442Y277885D01*
X543432Y277845D01*
X543417Y277800D01*
X543412Y277760D01*
X543402Y277720D01*
X543397Y277675D01*
Y277635D01*
X543392Y277590D01*
X543397Y277545D01*
Y277505D01*
X543402Y277460D01*
X543412Y277420D01*
X543417Y277380D01*
X543432Y277335D01*
X543442Y277295D01*
X543457Y277255D01*
X543477Y277215D01*
X543492Y277180D01*
X543512Y277140D01*
X543612Y277000D01*
X543642Y276970D01*
Y275840D01*
X543652Y275715D01*
X543692Y275590D01*
X543752Y275480D01*
X543832Y275380D01*
X543932Y275300D01*
X544042Y275240D01*
X544167Y275200D01*
X544292Y275190D01*
X544417Y275200D01*
X544542Y275240D01*
X544652Y275300D01*
X544752Y275380D01*
X544832Y275480D01*
X544892Y275590D01*
X544932Y275715D01*
X544942Y275840D01*
Y276970D01*
X544972Y277000D01*
X545072Y277140D01*
X545092Y277180D01*
X545107Y277215D01*
X545127Y277255D01*
X545142Y277295D01*
X545152Y277335D01*
X545167Y277380D01*
X545172Y277420D01*
X545182Y277460D01*
X545187Y277505D01*
Y277545D01*
X545192Y277590D01*
X545187Y277635D01*
Y277675D01*
X545182Y277720D01*
X545172Y277760D01*
X545167Y277800D01*
X545152Y277845D01*
X545142Y277885D01*
X545127Y277925D01*
X545107Y277965D01*
X545092Y278000D01*
X545072Y278040D01*
X544972Y278180D01*
X544942Y278210D01*
Y281640D01*
X544932Y281765D01*
X544892Y281890D01*
X544832Y282000D01*
X544752Y282100D01*
X544652Y282180D01*
X544542Y282240D01*
X544417Y282280D01*
X544292Y282290D01*
G37*
G36*
G01X549016D02*
X548891Y282280D01*
X548766Y282240D01*
X548656Y282180D01*
X548556Y282100D01*
X548476Y282000D01*
X548416Y281890D01*
X548376Y281765D01*
X548366Y281640D01*
Y278210D01*
X548336Y278180D01*
X548236Y278040D01*
X548216Y278000D01*
X548201Y277965D01*
X548181Y277925D01*
X548166Y277885D01*
X548156Y277845D01*
X548141Y277800D01*
X548136Y277760D01*
X548126Y277720D01*
X548121Y277675D01*
Y277635D01*
X548116Y277590D01*
X548121Y277545D01*
Y277505D01*
X548126Y277460D01*
X548136Y277420D01*
X548141Y277380D01*
X548156Y277335D01*
X548166Y277295D01*
X548181Y277255D01*
X548201Y277215D01*
X548216Y277180D01*
X548236Y277140D01*
X548336Y277000D01*
X548366Y276970D01*
Y275840D01*
X548376Y275715D01*
X548416Y275590D01*
X548476Y275480D01*
X548556Y275380D01*
X548656Y275300D01*
X548766Y275240D01*
X548891Y275200D01*
X549016Y275190D01*
X549141Y275200D01*
X549266Y275240D01*
X549376Y275300D01*
X549476Y275380D01*
X549556Y275480D01*
X549616Y275590D01*
X549656Y275715D01*
X549666Y275840D01*
Y276970D01*
X549696Y277000D01*
X549796Y277140D01*
X549816Y277180D01*
X549831Y277215D01*
X549851Y277255D01*
X549866Y277295D01*
X549876Y277335D01*
X549891Y277380D01*
X549896Y277420D01*
X549906Y277460D01*
X549911Y277505D01*
Y277545D01*
X549916Y277590D01*
X549911Y277635D01*
Y277675D01*
X549906Y277720D01*
X549896Y277760D01*
X549891Y277800D01*
X549876Y277845D01*
X549866Y277885D01*
X549851Y277925D01*
X549831Y277965D01*
X549816Y278000D01*
X549796Y278040D01*
X549696Y278180D01*
X549666Y278210D01*
Y281640D01*
X549656Y281765D01*
X549616Y281890D01*
X549556Y282000D01*
X549476Y282100D01*
X549376Y282180D01*
X549266Y282240D01*
X549141Y282280D01*
X549016Y282290D01*
G37*
G36*
G01X553740D02*
X553615Y282280D01*
X553490Y282240D01*
X553380Y282180D01*
X553280Y282100D01*
X553200Y282000D01*
X553140Y281890D01*
X553100Y281765D01*
X553090Y281640D01*
Y278210D01*
X553060Y278180D01*
X552960Y278040D01*
X552940Y278000D01*
X552925Y277965D01*
X552905Y277925D01*
X552890Y277885D01*
X552880Y277845D01*
X552865Y277800D01*
X552860Y277760D01*
X552850Y277720D01*
X552845Y277675D01*
Y277635D01*
X552840Y277590D01*
X552845Y277545D01*
Y277505D01*
X552850Y277460D01*
X552860Y277420D01*
X552865Y277380D01*
X552880Y277335D01*
X552890Y277295D01*
X552905Y277255D01*
X552925Y277215D01*
X552940Y277180D01*
X552960Y277140D01*
X553060Y277000D01*
X553090Y276970D01*
Y275840D01*
X553100Y275715D01*
X553140Y275590D01*
X553200Y275480D01*
X553280Y275380D01*
X553380Y275300D01*
X553490Y275240D01*
X553615Y275200D01*
X553740Y275190D01*
X553865Y275200D01*
X553990Y275240D01*
X554100Y275300D01*
X554200Y275380D01*
X554280Y275480D01*
X554340Y275590D01*
X554380Y275715D01*
X554390Y275840D01*
Y276970D01*
X554420Y277000D01*
X554520Y277140D01*
X554540Y277180D01*
X554555Y277215D01*
X554575Y277255D01*
X554590Y277295D01*
X554600Y277335D01*
X554615Y277380D01*
X554620Y277420D01*
X554630Y277460D01*
X554635Y277505D01*
Y277545D01*
X554640Y277590D01*
X554635Y277635D01*
Y277675D01*
X554630Y277720D01*
X554620Y277760D01*
X554615Y277800D01*
X554600Y277845D01*
X554590Y277885D01*
X554575Y277925D01*
X554555Y277965D01*
X554540Y278000D01*
X554520Y278040D01*
X554420Y278180D01*
X554390Y278210D01*
Y281640D01*
X554380Y281765D01*
X554340Y281890D01*
X554280Y282000D01*
X554200Y282100D01*
X554100Y282180D01*
X553990Y282240D01*
X553865Y282280D01*
X553740Y282290D01*
G37*
G36*
G01X558465D02*
X558340Y282280D01*
X558215Y282240D01*
X558105Y282180D01*
X558005Y282100D01*
X557925Y282000D01*
X557865Y281890D01*
X557825Y281765D01*
X557815Y281640D01*
Y278210D01*
X557785Y278180D01*
X557685Y278040D01*
X557665Y278000D01*
X557650Y277965D01*
X557630Y277925D01*
X557615Y277885D01*
X557605Y277845D01*
X557590Y277800D01*
X557585Y277760D01*
X557575Y277720D01*
X557570Y277675D01*
Y277635D01*
X557565Y277590D01*
X557570Y277545D01*
Y277505D01*
X557575Y277460D01*
X557585Y277420D01*
X557590Y277380D01*
X557605Y277335D01*
X557615Y277295D01*
X557630Y277255D01*
X557650Y277215D01*
X557665Y277180D01*
X557685Y277140D01*
X557785Y277000D01*
X557815Y276970D01*
Y275840D01*
X557825Y275715D01*
X557865Y275590D01*
X557925Y275480D01*
X558005Y275380D01*
X558105Y275300D01*
X558215Y275240D01*
X558340Y275200D01*
X558465Y275190D01*
X558590Y275200D01*
X558715Y275240D01*
X558825Y275300D01*
X558925Y275380D01*
X559005Y275480D01*
X559065Y275590D01*
X559105Y275715D01*
X559115Y275840D01*
Y276970D01*
X559145Y277000D01*
X559245Y277140D01*
X559265Y277180D01*
X559280Y277215D01*
X559300Y277255D01*
X559315Y277295D01*
X559325Y277335D01*
X559340Y277380D01*
X559345Y277420D01*
X559355Y277460D01*
X559360Y277505D01*
Y277545D01*
X559365Y277590D01*
X559360Y277635D01*
Y277675D01*
X559355Y277720D01*
X559345Y277760D01*
X559340Y277800D01*
X559325Y277845D01*
X559315Y277885D01*
X559300Y277925D01*
X559280Y277965D01*
X559265Y278000D01*
X559245Y278040D01*
X559145Y278180D01*
X559115Y278210D01*
Y281640D01*
X559105Y281765D01*
X559065Y281890D01*
X559005Y282000D01*
X558925Y282100D01*
X558825Y282180D01*
X558715Y282240D01*
X558590Y282280D01*
X558465Y282290D01*
G37*
G36*
G01X563189D02*
X563064Y282280D01*
X562939Y282240D01*
X562829Y282180D01*
X562729Y282100D01*
X562649Y282000D01*
X562589Y281890D01*
X562549Y281765D01*
X562539Y281640D01*
Y278210D01*
X562509Y278180D01*
X562409Y278040D01*
X562389Y278000D01*
X562374Y277965D01*
X562354Y277925D01*
X562339Y277885D01*
X562329Y277845D01*
X562314Y277800D01*
X562309Y277760D01*
X562299Y277720D01*
X562294Y277675D01*
Y277635D01*
X562289Y277590D01*
X562294Y277545D01*
Y277505D01*
X562299Y277460D01*
X562309Y277420D01*
X562314Y277380D01*
X562329Y277335D01*
X562339Y277295D01*
X562354Y277255D01*
X562374Y277215D01*
X562389Y277180D01*
X562409Y277140D01*
X562509Y277000D01*
X562539Y276970D01*
Y275840D01*
X562549Y275715D01*
X562589Y275590D01*
X562649Y275480D01*
X562729Y275380D01*
X562829Y275300D01*
X562939Y275240D01*
X563064Y275200D01*
X563189Y275190D01*
X563314Y275200D01*
X563439Y275240D01*
X563549Y275300D01*
X563649Y275380D01*
X563729Y275480D01*
X563789Y275590D01*
X563829Y275715D01*
X563839Y275840D01*
Y276970D01*
X563869Y277000D01*
X563969Y277140D01*
X563989Y277180D01*
X564004Y277215D01*
X564024Y277255D01*
X564039Y277295D01*
X564049Y277335D01*
X564064Y277380D01*
X564069Y277420D01*
X564079Y277460D01*
X564084Y277505D01*
Y277545D01*
X564089Y277590D01*
X564084Y277635D01*
Y277675D01*
X564079Y277720D01*
X564069Y277760D01*
X564064Y277800D01*
X564049Y277845D01*
X564039Y277885D01*
X564024Y277925D01*
X564004Y277965D01*
X563989Y278000D01*
X563969Y278040D01*
X563869Y278180D01*
X563839Y278210D01*
Y281640D01*
X563829Y281765D01*
X563789Y281890D01*
X563729Y282000D01*
X563649Y282100D01*
X563549Y282180D01*
X563439Y282240D01*
X563314Y282280D01*
X563189Y282290D01*
G37*
G36*
G01X567914D02*
X567789Y282280D01*
X567664Y282240D01*
X567554Y282180D01*
X567454Y282100D01*
X567374Y282000D01*
X567314Y281890D01*
X567274Y281765D01*
X567264Y281640D01*
Y278210D01*
X567234Y278180D01*
X567134Y278040D01*
X567114Y278000D01*
X567099Y277965D01*
X567079Y277925D01*
X567064Y277885D01*
X567054Y277845D01*
X567039Y277800D01*
X567034Y277760D01*
X567024Y277720D01*
X567019Y277675D01*
Y277635D01*
X567014Y277590D01*
X567019Y277545D01*
Y277505D01*
X567024Y277460D01*
X567034Y277420D01*
X567039Y277380D01*
X567054Y277335D01*
X567064Y277295D01*
X567079Y277255D01*
X567099Y277215D01*
X567114Y277180D01*
X567134Y277140D01*
X567234Y277000D01*
X567264Y276970D01*
Y275840D01*
X567274Y275715D01*
X567314Y275590D01*
X567374Y275480D01*
X567454Y275380D01*
X567554Y275300D01*
X567664Y275240D01*
X567789Y275200D01*
X567914Y275190D01*
X568039Y275200D01*
X568164Y275240D01*
X568274Y275300D01*
X568374Y275380D01*
X568454Y275480D01*
X568514Y275590D01*
X568554Y275715D01*
X568564Y275840D01*
Y276970D01*
X568594Y277000D01*
X568694Y277140D01*
X568714Y277180D01*
X568729Y277215D01*
X568749Y277255D01*
X568764Y277295D01*
X568774Y277335D01*
X568789Y277380D01*
X568794Y277420D01*
X568804Y277460D01*
X568809Y277505D01*
Y277545D01*
X568814Y277590D01*
X568809Y277635D01*
Y277675D01*
X568804Y277720D01*
X568794Y277760D01*
X568789Y277800D01*
X568774Y277845D01*
X568764Y277885D01*
X568749Y277925D01*
X568729Y277965D01*
X568714Y278000D01*
X568694Y278040D01*
X568594Y278180D01*
X568564Y278210D01*
Y281640D01*
X568554Y281765D01*
X568514Y281890D01*
X568454Y282000D01*
X568374Y282100D01*
X568274Y282180D01*
X568164Y282240D01*
X568039Y282280D01*
X567914Y282290D01*
G37*
G36*
G01X572638D02*
X572513Y282280D01*
X572388Y282240D01*
X572278Y282180D01*
X572178Y282100D01*
X572098Y282000D01*
X572038Y281890D01*
X571998Y281765D01*
X571988Y281640D01*
Y278210D01*
X571958Y278180D01*
X571858Y278040D01*
X571838Y278000D01*
X571823Y277965D01*
X571803Y277925D01*
X571788Y277885D01*
X571778Y277845D01*
X571763Y277800D01*
X571758Y277760D01*
X571748Y277720D01*
X571743Y277675D01*
Y277635D01*
X571738Y277590D01*
X571743Y277545D01*
Y277505D01*
X571748Y277460D01*
X571758Y277420D01*
X571763Y277380D01*
X571778Y277335D01*
X571788Y277295D01*
X571803Y277255D01*
X571823Y277215D01*
X571838Y277180D01*
X571858Y277140D01*
X571958Y277000D01*
X571988Y276970D01*
Y275840D01*
X571998Y275715D01*
X572038Y275590D01*
X572098Y275480D01*
X572178Y275380D01*
X572278Y275300D01*
X572388Y275240D01*
X572513Y275200D01*
X572638Y275190D01*
X572763Y275200D01*
X572888Y275240D01*
X572998Y275300D01*
X573098Y275380D01*
X573178Y275480D01*
X573238Y275590D01*
X573278Y275715D01*
X573288Y275840D01*
Y276970D01*
X573318Y277000D01*
X573418Y277140D01*
X573438Y277180D01*
X573453Y277215D01*
X573473Y277255D01*
X573488Y277295D01*
X573498Y277335D01*
X573513Y277380D01*
X573518Y277420D01*
X573528Y277460D01*
X573533Y277505D01*
Y277545D01*
X573538Y277590D01*
X573533Y277635D01*
Y277675D01*
X573528Y277720D01*
X573518Y277760D01*
X573513Y277800D01*
X573498Y277845D01*
X573488Y277885D01*
X573473Y277925D01*
X573453Y277965D01*
X573438Y278000D01*
X573418Y278040D01*
X573318Y278180D01*
X573288Y278210D01*
Y281640D01*
X573278Y281765D01*
X573238Y281890D01*
X573178Y282000D01*
X573098Y282100D01*
X572998Y282180D01*
X572888Y282240D01*
X572763Y282280D01*
X572638Y282290D01*
G37*
G36*
G01X577362D02*
X577237Y282280D01*
X577112Y282240D01*
X577002Y282180D01*
X576902Y282100D01*
X576822Y282000D01*
X576762Y281890D01*
X576722Y281765D01*
X576712Y281640D01*
Y278210D01*
X576682Y278180D01*
X576582Y278040D01*
X576562Y278000D01*
X576547Y277965D01*
X576527Y277925D01*
X576512Y277885D01*
X576502Y277845D01*
X576487Y277800D01*
X576482Y277760D01*
X576472Y277720D01*
X576467Y277675D01*
Y277635D01*
X576462Y277590D01*
X576467Y277545D01*
Y277505D01*
X576472Y277460D01*
X576482Y277420D01*
X576487Y277380D01*
X576502Y277335D01*
X576512Y277295D01*
X576527Y277255D01*
X576547Y277215D01*
X576562Y277180D01*
X576582Y277140D01*
X576682Y277000D01*
X576712Y276970D01*
Y275840D01*
X576722Y275715D01*
X576762Y275590D01*
X576822Y275480D01*
X576902Y275380D01*
X577002Y275300D01*
X577112Y275240D01*
X577237Y275200D01*
X577362Y275190D01*
X577487Y275200D01*
X577612Y275240D01*
X577722Y275300D01*
X577822Y275380D01*
X577902Y275480D01*
X577962Y275590D01*
X578002Y275715D01*
X578012Y275840D01*
Y276970D01*
X578042Y277000D01*
X578142Y277140D01*
X578162Y277180D01*
X578177Y277215D01*
X578197Y277255D01*
X578212Y277295D01*
X578222Y277335D01*
X578237Y277380D01*
X578242Y277420D01*
X578252Y277460D01*
X578257Y277505D01*
Y277545D01*
X578262Y277590D01*
X578257Y277635D01*
Y277675D01*
X578252Y277720D01*
X578242Y277760D01*
X578237Y277800D01*
X578222Y277845D01*
X578212Y277885D01*
X578197Y277925D01*
X578177Y277965D01*
X578162Y278000D01*
X578142Y278040D01*
X578042Y278180D01*
X578012Y278210D01*
Y281640D01*
X578002Y281765D01*
X577962Y281890D01*
X577902Y282000D01*
X577822Y282100D01*
X577722Y282180D01*
X577612Y282240D01*
X577487Y282280D01*
X577362Y282290D01*
G37*
G36*
G01X582087D02*
X581962Y282280D01*
X581837Y282240D01*
X581727Y282180D01*
X581627Y282100D01*
X581547Y282000D01*
X581487Y281890D01*
X581447Y281765D01*
X581437Y281640D01*
Y278210D01*
X581407Y278180D01*
X581307Y278040D01*
X581287Y278000D01*
X581272Y277965D01*
X581252Y277925D01*
X581237Y277885D01*
X581227Y277845D01*
X581212Y277800D01*
X581207Y277760D01*
X581197Y277720D01*
X581192Y277675D01*
Y277635D01*
X581187Y277590D01*
X581192Y277545D01*
Y277505D01*
X581197Y277460D01*
X581207Y277420D01*
X581212Y277380D01*
X581227Y277335D01*
X581237Y277295D01*
X581252Y277255D01*
X581272Y277215D01*
X581287Y277180D01*
X581307Y277140D01*
X581407Y277000D01*
X581437Y276970D01*
Y275840D01*
X581447Y275715D01*
X581487Y275590D01*
X581547Y275480D01*
X581627Y275380D01*
X581727Y275300D01*
X581837Y275240D01*
X581962Y275200D01*
X582087Y275190D01*
X582212Y275200D01*
X582337Y275240D01*
X582447Y275300D01*
X582547Y275380D01*
X582627Y275480D01*
X582687Y275590D01*
X582727Y275715D01*
X582737Y275840D01*
Y276970D01*
X582767Y277000D01*
X582867Y277140D01*
X582887Y277180D01*
X582902Y277215D01*
X582922Y277255D01*
X582937Y277295D01*
X582947Y277335D01*
X582962Y277380D01*
X582967Y277420D01*
X582977Y277460D01*
X582982Y277505D01*
Y277545D01*
X582987Y277590D01*
X582982Y277635D01*
Y277675D01*
X582977Y277720D01*
X582967Y277760D01*
X582962Y277800D01*
X582947Y277845D01*
X582937Y277885D01*
X582922Y277925D01*
X582902Y277965D01*
X582887Y278000D01*
X582867Y278040D01*
X582767Y278180D01*
X582737Y278210D01*
Y281640D01*
X582727Y281765D01*
X582687Y281890D01*
X582627Y282000D01*
X582547Y282100D01*
X582447Y282180D01*
X582337Y282240D01*
X582212Y282280D01*
X582087Y282290D01*
G37*
G36*
G01X586811D02*
X586686Y282280D01*
X586561Y282240D01*
X586451Y282180D01*
X586351Y282100D01*
X586271Y282000D01*
X586211Y281890D01*
X586171Y281765D01*
X586161Y281640D01*
Y278210D01*
X586131Y278180D01*
X586031Y278040D01*
X586011Y278000D01*
X585996Y277965D01*
X585976Y277925D01*
X585961Y277885D01*
X585951Y277845D01*
X585936Y277800D01*
X585931Y277760D01*
X585921Y277720D01*
X585916Y277675D01*
Y277635D01*
X585911Y277590D01*
X585916Y277545D01*
Y277505D01*
X585921Y277460D01*
X585931Y277420D01*
X585936Y277380D01*
X585951Y277335D01*
X585961Y277295D01*
X585976Y277255D01*
X585996Y277215D01*
X586011Y277180D01*
X586031Y277140D01*
X586131Y277000D01*
X586161Y276970D01*
Y275840D01*
X586171Y275715D01*
X586211Y275590D01*
X586271Y275480D01*
X586351Y275380D01*
X586451Y275300D01*
X586561Y275240D01*
X586686Y275200D01*
X586811Y275190D01*
X586936Y275200D01*
X587061Y275240D01*
X587171Y275300D01*
X587271Y275380D01*
X587351Y275480D01*
X587411Y275590D01*
X587451Y275715D01*
X587461Y275840D01*
Y276970D01*
X587491Y277000D01*
X587591Y277140D01*
X587611Y277180D01*
X587626Y277215D01*
X587646Y277255D01*
X587661Y277295D01*
X587671Y277335D01*
X587686Y277380D01*
X587691Y277420D01*
X587701Y277460D01*
X587706Y277505D01*
Y277545D01*
X587711Y277590D01*
X587706Y277635D01*
Y277675D01*
X587701Y277720D01*
X587691Y277760D01*
X587686Y277800D01*
X587671Y277845D01*
X587661Y277885D01*
X587646Y277925D01*
X587626Y277965D01*
X587611Y278000D01*
X587591Y278040D01*
X587491Y278180D01*
X587461Y278210D01*
Y281640D01*
X587451Y281765D01*
X587411Y281890D01*
X587351Y282000D01*
X587271Y282100D01*
X587171Y282180D01*
X587061Y282240D01*
X586936Y282280D01*
X586811Y282290D01*
G37*
G36*
G01X591536D02*
X591411Y282280D01*
X591286Y282240D01*
X591176Y282180D01*
X591076Y282100D01*
X590996Y282000D01*
X590936Y281890D01*
X590896Y281765D01*
X590886Y281640D01*
Y278210D01*
X590856Y278180D01*
X590756Y278040D01*
X590736Y278000D01*
X590721Y277965D01*
X590701Y277925D01*
X590686Y277885D01*
X590676Y277845D01*
X590661Y277800D01*
X590656Y277760D01*
X590646Y277720D01*
X590641Y277675D01*
Y277635D01*
X590636Y277590D01*
X590641Y277545D01*
Y277505D01*
X590646Y277460D01*
X590656Y277420D01*
X590661Y277380D01*
X590676Y277335D01*
X590686Y277295D01*
X590701Y277255D01*
X590721Y277215D01*
X590736Y277180D01*
X590756Y277140D01*
X590856Y277000D01*
X590886Y276970D01*
Y275840D01*
X590896Y275715D01*
X590936Y275590D01*
X590996Y275480D01*
X591076Y275380D01*
X591176Y275300D01*
X591286Y275240D01*
X591411Y275200D01*
X591536Y275190D01*
X591661Y275200D01*
X591786Y275240D01*
X591896Y275300D01*
X591996Y275380D01*
X592076Y275480D01*
X592136Y275590D01*
X592176Y275715D01*
X592186Y275840D01*
Y276970D01*
X592216Y277000D01*
X592316Y277140D01*
X592336Y277180D01*
X592351Y277215D01*
X592371Y277255D01*
X592386Y277295D01*
X592396Y277335D01*
X592411Y277380D01*
X592416Y277420D01*
X592426Y277460D01*
X592431Y277505D01*
Y277545D01*
X592436Y277590D01*
X592431Y277635D01*
Y277675D01*
X592426Y277720D01*
X592416Y277760D01*
X592411Y277800D01*
X592396Y277845D01*
X592386Y277885D01*
X592371Y277925D01*
X592351Y277965D01*
X592336Y278000D01*
X592316Y278040D01*
X592216Y278180D01*
X592186Y278210D01*
Y281640D01*
X592176Y281765D01*
X592136Y281890D01*
X592076Y282000D01*
X591996Y282100D01*
X591896Y282180D01*
X591786Y282240D01*
X591661Y282280D01*
X591536Y282290D01*
G37*
G36*
G01X596260D02*
X596135Y282280D01*
X596010Y282240D01*
X595900Y282180D01*
X595800Y282100D01*
X595720Y282000D01*
X595660Y281890D01*
X595620Y281765D01*
X595610Y281640D01*
Y278210D01*
X595580Y278180D01*
X595480Y278040D01*
X595460Y278000D01*
X595445Y277965D01*
X595425Y277925D01*
X595410Y277885D01*
X595400Y277845D01*
X595385Y277800D01*
X595380Y277760D01*
X595370Y277720D01*
X595365Y277675D01*
Y277635D01*
X595360Y277590D01*
X595365Y277545D01*
Y277505D01*
X595370Y277460D01*
X595380Y277420D01*
X595385Y277380D01*
X595400Y277335D01*
X595410Y277295D01*
X595425Y277255D01*
X595445Y277215D01*
X595460Y277180D01*
X595480Y277140D01*
X595580Y277000D01*
X595610Y276970D01*
Y275840D01*
X595620Y275715D01*
X595660Y275590D01*
X595720Y275480D01*
X595800Y275380D01*
X595900Y275300D01*
X596010Y275240D01*
X596135Y275200D01*
X596260Y275190D01*
X596385Y275200D01*
X596510Y275240D01*
X596620Y275300D01*
X596720Y275380D01*
X596800Y275480D01*
X596860Y275590D01*
X596900Y275715D01*
X596910Y275840D01*
Y276970D01*
X596940Y277000D01*
X597040Y277140D01*
X597060Y277180D01*
X597075Y277215D01*
X597095Y277255D01*
X597110Y277295D01*
X597120Y277335D01*
X597135Y277380D01*
X597140Y277420D01*
X597150Y277460D01*
X597155Y277505D01*
Y277545D01*
X597160Y277590D01*
X597155Y277635D01*
Y277675D01*
X597150Y277720D01*
X597140Y277760D01*
X597135Y277800D01*
X597120Y277845D01*
X597110Y277885D01*
X597095Y277925D01*
X597075Y277965D01*
X597060Y278000D01*
X597040Y278040D01*
X596940Y278180D01*
X596910Y278210D01*
Y281640D01*
X596900Y281765D01*
X596860Y281890D01*
X596800Y282000D01*
X596720Y282100D01*
X596620Y282180D01*
X596510Y282240D01*
X596385Y282280D01*
X596260Y282290D01*
G37*
G36*
G01X600985D02*
X600860Y282280D01*
X600735Y282240D01*
X600625Y282180D01*
X600525Y282100D01*
X600445Y282000D01*
X600385Y281890D01*
X600345Y281765D01*
X600335Y281640D01*
Y278210D01*
X600305Y278180D01*
X600205Y278040D01*
X600185Y278000D01*
X600170Y277965D01*
X600150Y277925D01*
X600135Y277885D01*
X600125Y277845D01*
X600110Y277800D01*
X600105Y277760D01*
X600095Y277720D01*
X600090Y277675D01*
Y277635D01*
X600085Y277590D01*
X600090Y277545D01*
Y277505D01*
X600095Y277460D01*
X600105Y277420D01*
X600110Y277380D01*
X600125Y277335D01*
X600135Y277295D01*
X600150Y277255D01*
X600170Y277215D01*
X600185Y277180D01*
X600205Y277140D01*
X600305Y277000D01*
X600335Y276970D01*
Y275840D01*
X600345Y275715D01*
X600385Y275590D01*
X600445Y275480D01*
X600525Y275380D01*
X600625Y275300D01*
X600735Y275240D01*
X600860Y275200D01*
X600985Y275190D01*
X601110Y275200D01*
X601235Y275240D01*
X601345Y275300D01*
X601445Y275380D01*
X601525Y275480D01*
X601585Y275590D01*
X601625Y275715D01*
X601635Y275840D01*
Y276970D01*
X601665Y277000D01*
X601765Y277140D01*
X601785Y277180D01*
X601800Y277215D01*
X601820Y277255D01*
X601835Y277295D01*
X601845Y277335D01*
X601860Y277380D01*
X601865Y277420D01*
X601875Y277460D01*
X601880Y277505D01*
Y277545D01*
X601885Y277590D01*
X601880Y277635D01*
Y277675D01*
X601875Y277720D01*
X601865Y277760D01*
X601860Y277800D01*
X601845Y277845D01*
X601835Y277885D01*
X601820Y277925D01*
X601800Y277965D01*
X601785Y278000D01*
X601765Y278040D01*
X601665Y278180D01*
X601635Y278210D01*
Y281640D01*
X601625Y281765D01*
X601585Y281890D01*
X601525Y282000D01*
X601445Y282100D01*
X601345Y282180D01*
X601235Y282240D01*
X601110Y282280D01*
X600985Y282290D01*
G37*
G36*
G01X605709D02*
X605584Y282280D01*
X605459Y282240D01*
X605349Y282180D01*
X605249Y282100D01*
X605169Y282000D01*
X605109Y281890D01*
X605069Y281765D01*
X605059Y281640D01*
Y278210D01*
X605029Y278180D01*
X604929Y278040D01*
X604909Y278000D01*
X604894Y277965D01*
X604874Y277925D01*
X604859Y277885D01*
X604849Y277845D01*
X604834Y277800D01*
X604829Y277760D01*
X604819Y277720D01*
X604814Y277675D01*
Y277635D01*
X604809Y277590D01*
X604814Y277545D01*
Y277505D01*
X604819Y277460D01*
X604829Y277420D01*
X604834Y277380D01*
X604849Y277335D01*
X604859Y277295D01*
X604874Y277255D01*
X604894Y277215D01*
X604909Y277180D01*
X604929Y277140D01*
X605029Y277000D01*
X605059Y276970D01*
Y275840D01*
X605069Y275715D01*
X605109Y275590D01*
X605169Y275480D01*
X605249Y275380D01*
X605349Y275300D01*
X605459Y275240D01*
X605584Y275200D01*
X605709Y275190D01*
X605834Y275200D01*
X605959Y275240D01*
X606069Y275300D01*
X606169Y275380D01*
X606249Y275480D01*
X606309Y275590D01*
X606349Y275715D01*
X606359Y275840D01*
Y276970D01*
X606389Y277000D01*
X606489Y277140D01*
X606509Y277180D01*
X606524Y277215D01*
X606544Y277255D01*
X606559Y277295D01*
X606569Y277335D01*
X606584Y277380D01*
X606589Y277420D01*
X606599Y277460D01*
X606604Y277505D01*
Y277545D01*
X606609Y277590D01*
X606604Y277635D01*
Y277675D01*
X606599Y277720D01*
X606589Y277760D01*
X606584Y277800D01*
X606569Y277845D01*
X606559Y277885D01*
X606544Y277925D01*
X606524Y277965D01*
X606509Y278000D01*
X606489Y278040D01*
X606389Y278180D01*
X606359Y278210D01*
Y281640D01*
X606349Y281765D01*
X606309Y281890D01*
X606249Y282000D01*
X606169Y282100D01*
X606069Y282180D01*
X605959Y282240D01*
X605834Y282280D01*
X605709Y282290D01*
G37*
G36*
G01X610433D02*
X610308Y282280D01*
X610183Y282240D01*
X610073Y282180D01*
X609973Y282100D01*
X609893Y282000D01*
X609833Y281890D01*
X609793Y281765D01*
X609783Y281640D01*
Y278210D01*
X609753Y278180D01*
X609653Y278040D01*
X609633Y278000D01*
X609618Y277965D01*
X609598Y277925D01*
X609583Y277885D01*
X609573Y277845D01*
X609558Y277800D01*
X609553Y277760D01*
X609543Y277720D01*
X609538Y277675D01*
Y277635D01*
X609533Y277590D01*
X609538Y277545D01*
Y277505D01*
X609543Y277460D01*
X609553Y277420D01*
X609558Y277380D01*
X609573Y277335D01*
X609583Y277295D01*
X609598Y277255D01*
X609618Y277215D01*
X609633Y277180D01*
X609653Y277140D01*
X609753Y277000D01*
X609783Y276970D01*
Y275840D01*
X609793Y275715D01*
X609833Y275590D01*
X609893Y275480D01*
X609973Y275380D01*
X610073Y275300D01*
X610183Y275240D01*
X610308Y275200D01*
X610433Y275190D01*
X610558Y275200D01*
X610683Y275240D01*
X610793Y275300D01*
X610893Y275380D01*
X610973Y275480D01*
X611033Y275590D01*
X611073Y275715D01*
X611083Y275840D01*
Y276970D01*
X611113Y277000D01*
X611213Y277140D01*
X611233Y277180D01*
X611248Y277215D01*
X611268Y277255D01*
X611283Y277295D01*
X611293Y277335D01*
X611308Y277380D01*
X611313Y277420D01*
X611323Y277460D01*
X611328Y277505D01*
Y277545D01*
X611333Y277590D01*
X611328Y277635D01*
Y277675D01*
X611323Y277720D01*
X611313Y277760D01*
X611308Y277800D01*
X611293Y277845D01*
X611283Y277885D01*
X611268Y277925D01*
X611248Y277965D01*
X611233Y278000D01*
X611213Y278040D01*
X611113Y278180D01*
X611083Y278210D01*
Y281640D01*
X611073Y281765D01*
X611033Y281890D01*
X610973Y282000D01*
X610893Y282100D01*
X610793Y282180D01*
X610683Y282240D01*
X610558Y282280D01*
X610433Y282290D01*
G37*
G36*
G01X615158D02*
X615033Y282280D01*
X614908Y282240D01*
X614798Y282180D01*
X614698Y282100D01*
X614618Y282000D01*
X614558Y281890D01*
X614518Y281765D01*
X614508Y281640D01*
Y278210D01*
X614478Y278180D01*
X614378Y278040D01*
X614358Y278000D01*
X614343Y277965D01*
X614323Y277925D01*
X614308Y277885D01*
X614298Y277845D01*
X614283Y277800D01*
X614278Y277760D01*
X614268Y277720D01*
X614263Y277675D01*
Y277635D01*
X614258Y277590D01*
X614263Y277545D01*
Y277505D01*
X614268Y277460D01*
X614278Y277420D01*
X614283Y277380D01*
X614298Y277335D01*
X614308Y277295D01*
X614323Y277255D01*
X614343Y277215D01*
X614358Y277180D01*
X614378Y277140D01*
X614478Y277000D01*
X614508Y276970D01*
Y275840D01*
X614518Y275715D01*
X614558Y275590D01*
X614618Y275480D01*
X614698Y275380D01*
X614798Y275300D01*
X614908Y275240D01*
X615033Y275200D01*
X615158Y275190D01*
X615283Y275200D01*
X615408Y275240D01*
X615518Y275300D01*
X615618Y275380D01*
X615698Y275480D01*
X615758Y275590D01*
X615798Y275715D01*
X615808Y275840D01*
Y276970D01*
X615838Y277000D01*
X615938Y277140D01*
X615958Y277180D01*
X615973Y277215D01*
X615993Y277255D01*
X616008Y277295D01*
X616018Y277335D01*
X616033Y277380D01*
X616038Y277420D01*
X616048Y277460D01*
X616053Y277505D01*
Y277545D01*
X616058Y277590D01*
X616053Y277635D01*
Y277675D01*
X616048Y277720D01*
X616038Y277760D01*
X616033Y277800D01*
X616018Y277845D01*
X616008Y277885D01*
X615993Y277925D01*
X615973Y277965D01*
X615958Y278000D01*
X615938Y278040D01*
X615838Y278180D01*
X615808Y278210D01*
Y281640D01*
X615798Y281765D01*
X615758Y281890D01*
X615698Y282000D01*
X615618Y282100D01*
X615518Y282180D01*
X615408Y282240D01*
X615283Y282280D01*
X615158Y282290D01*
G37*
G36*
G01X619882D02*
X619757Y282280D01*
X619632Y282240D01*
X619522Y282180D01*
X619422Y282100D01*
X619342Y282000D01*
X619282Y281890D01*
X619242Y281765D01*
X619232Y281640D01*
Y278210D01*
X619202Y278180D01*
X619102Y278040D01*
X619082Y278000D01*
X619067Y277965D01*
X619047Y277925D01*
X619032Y277885D01*
X619022Y277845D01*
X619007Y277800D01*
X619002Y277760D01*
X618992Y277720D01*
X618987Y277675D01*
Y277635D01*
X618982Y277590D01*
X618987Y277545D01*
Y277505D01*
X618992Y277460D01*
X619002Y277420D01*
X619007Y277380D01*
X619022Y277335D01*
X619032Y277295D01*
X619047Y277255D01*
X619067Y277215D01*
X619082Y277180D01*
X619102Y277140D01*
X619202Y277000D01*
X619232Y276970D01*
Y275840D01*
X619242Y275715D01*
X619282Y275590D01*
X619342Y275480D01*
X619422Y275380D01*
X619522Y275300D01*
X619632Y275240D01*
X619757Y275200D01*
X619882Y275190D01*
X620007Y275200D01*
X620132Y275240D01*
X620242Y275300D01*
X620342Y275380D01*
X620422Y275480D01*
X620482Y275590D01*
X620522Y275715D01*
X620532Y275840D01*
Y276970D01*
X620562Y277000D01*
X620662Y277140D01*
X620682Y277180D01*
X620697Y277215D01*
X620717Y277255D01*
X620732Y277295D01*
X620742Y277335D01*
X620757Y277380D01*
X620762Y277420D01*
X620772Y277460D01*
X620777Y277505D01*
Y277545D01*
X620782Y277590D01*
X620777Y277635D01*
Y277675D01*
X620772Y277720D01*
X620762Y277760D01*
X620757Y277800D01*
X620742Y277845D01*
X620732Y277885D01*
X620717Y277925D01*
X620697Y277965D01*
X620682Y278000D01*
X620662Y278040D01*
X620562Y278180D01*
X620532Y278210D01*
Y281640D01*
X620522Y281765D01*
X620482Y281890D01*
X620422Y282000D01*
X620342Y282100D01*
X620242Y282180D01*
X620132Y282240D01*
X620007Y282280D01*
X619882Y282290D01*
G37*
G36*
G01X624607D02*
X624482Y282280D01*
X624357Y282240D01*
X624247Y282180D01*
X624147Y282100D01*
X624067Y282000D01*
X624007Y281890D01*
X623967Y281765D01*
X623957Y281640D01*
Y278210D01*
X623927Y278180D01*
X623827Y278040D01*
X623807Y278000D01*
X623792Y277965D01*
X623772Y277925D01*
X623757Y277885D01*
X623747Y277845D01*
X623732Y277800D01*
X623727Y277760D01*
X623717Y277720D01*
X623712Y277675D01*
Y277635D01*
X623707Y277590D01*
X623712Y277545D01*
Y277505D01*
X623717Y277460D01*
X623727Y277420D01*
X623732Y277380D01*
X623747Y277335D01*
X623757Y277295D01*
X623772Y277255D01*
X623792Y277215D01*
X623807Y277180D01*
X623827Y277140D01*
X623927Y277000D01*
X623957Y276970D01*
Y275840D01*
X623967Y275715D01*
X624007Y275590D01*
X624067Y275480D01*
X624147Y275380D01*
X624247Y275300D01*
X624357Y275240D01*
X624482Y275200D01*
X624607Y275190D01*
X624732Y275200D01*
X624857Y275240D01*
X624967Y275300D01*
X625067Y275380D01*
X625147Y275480D01*
X625207Y275590D01*
X625247Y275715D01*
X625257Y275840D01*
Y276970D01*
X625287Y277000D01*
X625387Y277140D01*
X625407Y277180D01*
X625422Y277215D01*
X625442Y277255D01*
X625457Y277295D01*
X625467Y277335D01*
X625482Y277380D01*
X625487Y277420D01*
X625497Y277460D01*
X625502Y277505D01*
Y277545D01*
X625507Y277590D01*
X625502Y277635D01*
Y277675D01*
X625497Y277720D01*
X625487Y277760D01*
X625482Y277800D01*
X625467Y277845D01*
X625457Y277885D01*
X625442Y277925D01*
X625422Y277965D01*
X625407Y278000D01*
X625387Y278040D01*
X625287Y278180D01*
X625257Y278210D01*
Y281640D01*
X625247Y281765D01*
X625207Y281890D01*
X625147Y282000D01*
X625067Y282100D01*
X624967Y282180D01*
X624857Y282240D01*
X624732Y282280D01*
X624607Y282290D01*
G37*
G36*
G01X629331D02*
X629206Y282280D01*
X629081Y282240D01*
X628971Y282180D01*
X628871Y282100D01*
X628791Y282000D01*
X628731Y281890D01*
X628691Y281765D01*
X628681Y281640D01*
Y278210D01*
X628651Y278180D01*
X628551Y278040D01*
X628531Y278000D01*
X628516Y277965D01*
X628496Y277925D01*
X628481Y277885D01*
X628471Y277845D01*
X628456Y277800D01*
X628451Y277760D01*
X628441Y277720D01*
X628436Y277675D01*
Y277635D01*
X628431Y277590D01*
X628436Y277545D01*
Y277505D01*
X628441Y277460D01*
X628451Y277420D01*
X628456Y277380D01*
X628471Y277335D01*
X628481Y277295D01*
X628496Y277255D01*
X628516Y277215D01*
X628531Y277180D01*
X628551Y277140D01*
X628651Y277000D01*
X628681Y276970D01*
Y275840D01*
X628691Y275715D01*
X628731Y275590D01*
X628791Y275480D01*
X628871Y275380D01*
X628971Y275300D01*
X629081Y275240D01*
X629206Y275200D01*
X629331Y275190D01*
X629456Y275200D01*
X629581Y275240D01*
X629691Y275300D01*
X629791Y275380D01*
X629871Y275480D01*
X629931Y275590D01*
X629971Y275715D01*
X629981Y275840D01*
Y276970D01*
X630011Y277000D01*
X630111Y277140D01*
X630131Y277180D01*
X630146Y277215D01*
X630166Y277255D01*
X630181Y277295D01*
X630191Y277335D01*
X630206Y277380D01*
X630211Y277420D01*
X630221Y277460D01*
X630226Y277505D01*
Y277545D01*
X630231Y277590D01*
X630226Y277635D01*
Y277675D01*
X630221Y277720D01*
X630211Y277760D01*
X630206Y277800D01*
X630191Y277845D01*
X630181Y277885D01*
X630166Y277925D01*
X630146Y277965D01*
X630131Y278000D01*
X630111Y278040D01*
X630011Y278180D01*
X629981Y278210D01*
Y281640D01*
X629971Y281765D01*
X629931Y281890D01*
X629871Y282000D01*
X629791Y282100D01*
X629691Y282180D01*
X629581Y282240D01*
X629456Y282280D01*
X629331Y282290D01*
G37*
G36*
G01X634055D02*
X633930Y282280D01*
X633805Y282240D01*
X633695Y282180D01*
X633595Y282100D01*
X633515Y282000D01*
X633455Y281890D01*
X633415Y281765D01*
X633405Y281640D01*
Y278210D01*
X633375Y278180D01*
X633275Y278040D01*
X633255Y278000D01*
X633240Y277965D01*
X633220Y277925D01*
X633205Y277885D01*
X633195Y277845D01*
X633180Y277800D01*
X633175Y277760D01*
X633165Y277720D01*
X633160Y277675D01*
Y277635D01*
X633155Y277590D01*
X633160Y277545D01*
Y277505D01*
X633165Y277460D01*
X633175Y277420D01*
X633180Y277380D01*
X633195Y277335D01*
X633205Y277295D01*
X633220Y277255D01*
X633240Y277215D01*
X633255Y277180D01*
X633275Y277140D01*
X633375Y277000D01*
X633405Y276970D01*
Y275840D01*
X633415Y275715D01*
X633455Y275590D01*
X633515Y275480D01*
X633595Y275380D01*
X633695Y275300D01*
X633805Y275240D01*
X633930Y275200D01*
X634055Y275190D01*
X634180Y275200D01*
X634305Y275240D01*
X634415Y275300D01*
X634515Y275380D01*
X634595Y275480D01*
X634655Y275590D01*
X634695Y275715D01*
X634705Y275840D01*
Y276970D01*
X634735Y277000D01*
X634835Y277140D01*
X634855Y277180D01*
X634870Y277215D01*
X634890Y277255D01*
X634905Y277295D01*
X634915Y277335D01*
X634930Y277380D01*
X634935Y277420D01*
X634945Y277460D01*
X634950Y277505D01*
Y277545D01*
X634955Y277590D01*
X634950Y277635D01*
Y277675D01*
X634945Y277720D01*
X634935Y277760D01*
X634930Y277800D01*
X634915Y277845D01*
X634905Y277885D01*
X634890Y277925D01*
X634870Y277965D01*
X634855Y278000D01*
X634835Y278040D01*
X634735Y278180D01*
X634705Y278210D01*
Y281640D01*
X634695Y281765D01*
X634655Y281890D01*
X634595Y282000D01*
X634515Y282100D01*
X634415Y282180D01*
X634305Y282240D01*
X634180Y282280D01*
X634055Y282290D01*
G37*
G36*
G01X638780D02*
X638655Y282280D01*
X638530Y282240D01*
X638420Y282180D01*
X638320Y282100D01*
X638240Y282000D01*
X638180Y281890D01*
X638140Y281765D01*
X638130Y281640D01*
Y278210D01*
X638100Y278180D01*
X638000Y278040D01*
X637980Y278000D01*
X637965Y277965D01*
X637945Y277925D01*
X637930Y277885D01*
X637920Y277845D01*
X637905Y277800D01*
X637900Y277760D01*
X637890Y277720D01*
X637885Y277675D01*
Y277635D01*
X637880Y277590D01*
X637885Y277545D01*
Y277505D01*
X637890Y277460D01*
X637900Y277420D01*
X637905Y277380D01*
X637920Y277335D01*
X637930Y277295D01*
X637945Y277255D01*
X637965Y277215D01*
X637980Y277180D01*
X638000Y277140D01*
X638100Y277000D01*
X638130Y276970D01*
Y275840D01*
X638140Y275715D01*
X638180Y275590D01*
X638240Y275480D01*
X638320Y275380D01*
X638420Y275300D01*
X638530Y275240D01*
X638655Y275200D01*
X638780Y275190D01*
X638905Y275200D01*
X639030Y275240D01*
X639140Y275300D01*
X639240Y275380D01*
X639320Y275480D01*
X639380Y275590D01*
X639420Y275715D01*
X639430Y275840D01*
Y276970D01*
X639460Y277000D01*
X639560Y277140D01*
X639580Y277180D01*
X639595Y277215D01*
X639615Y277255D01*
X639630Y277295D01*
X639640Y277335D01*
X639655Y277380D01*
X639660Y277420D01*
X639670Y277460D01*
X639675Y277505D01*
Y277545D01*
X639680Y277590D01*
X639675Y277635D01*
Y277675D01*
X639670Y277720D01*
X639660Y277760D01*
X639655Y277800D01*
X639640Y277845D01*
X639630Y277885D01*
X639615Y277925D01*
X639595Y277965D01*
X639580Y278000D01*
X639560Y278040D01*
X639460Y278180D01*
X639430Y278210D01*
Y281640D01*
X639420Y281765D01*
X639380Y281890D01*
X639320Y282000D01*
X639240Y282100D01*
X639140Y282180D01*
X639030Y282240D01*
X638905Y282280D01*
X638780Y282290D01*
G37*
G36*
G01X643504D02*
X643379Y282280D01*
X643254Y282240D01*
X643144Y282180D01*
X643044Y282100D01*
X642964Y282000D01*
X642904Y281890D01*
X642864Y281765D01*
X642854Y281640D01*
Y278210D01*
X642824Y278180D01*
X642724Y278040D01*
X642704Y278000D01*
X642689Y277965D01*
X642669Y277925D01*
X642654Y277885D01*
X642644Y277845D01*
X642629Y277800D01*
X642624Y277760D01*
X642614Y277720D01*
X642609Y277675D01*
Y277635D01*
X642604Y277590D01*
X642609Y277545D01*
Y277505D01*
X642614Y277460D01*
X642624Y277420D01*
X642629Y277380D01*
X642644Y277335D01*
X642654Y277295D01*
X642669Y277255D01*
X642689Y277215D01*
X642704Y277180D01*
X642724Y277140D01*
X642824Y277000D01*
X642854Y276970D01*
Y275840D01*
X642864Y275715D01*
X642904Y275590D01*
X642964Y275480D01*
X643044Y275380D01*
X643144Y275300D01*
X643254Y275240D01*
X643379Y275200D01*
X643504Y275190D01*
X643629Y275200D01*
X643754Y275240D01*
X643864Y275300D01*
X643964Y275380D01*
X644044Y275480D01*
X644104Y275590D01*
X644144Y275715D01*
X644154Y275840D01*
Y276970D01*
X644184Y277000D01*
X644284Y277140D01*
X644304Y277180D01*
X644319Y277215D01*
X644339Y277255D01*
X644354Y277295D01*
X644364Y277335D01*
X644379Y277380D01*
X644384Y277420D01*
X644394Y277460D01*
X644399Y277505D01*
Y277545D01*
X644404Y277590D01*
X644399Y277635D01*
Y277675D01*
X644394Y277720D01*
X644384Y277760D01*
X644379Y277800D01*
X644364Y277845D01*
X644354Y277885D01*
X644339Y277925D01*
X644319Y277965D01*
X644304Y278000D01*
X644284Y278040D01*
X644184Y278180D01*
X644154Y278210D01*
Y281640D01*
X644144Y281765D01*
X644104Y281890D01*
X644044Y282000D01*
X643964Y282100D01*
X643864Y282180D01*
X643754Y282240D01*
X643629Y282280D01*
X643504Y282290D01*
G37*
G36*
G01X648229D02*
X648104Y282280D01*
X647979Y282240D01*
X647869Y282180D01*
X647769Y282100D01*
X647689Y282000D01*
X647629Y281890D01*
X647589Y281765D01*
X647579Y281640D01*
Y278210D01*
X647549Y278180D01*
X647449Y278040D01*
X647429Y278000D01*
X647414Y277965D01*
X647394Y277925D01*
X647379Y277885D01*
X647369Y277845D01*
X647354Y277800D01*
X647349Y277760D01*
X647339Y277720D01*
X647334Y277675D01*
Y277635D01*
X647329Y277590D01*
X647334Y277545D01*
Y277505D01*
X647339Y277460D01*
X647349Y277420D01*
X647354Y277380D01*
X647369Y277335D01*
X647379Y277295D01*
X647394Y277255D01*
X647414Y277215D01*
X647429Y277180D01*
X647449Y277140D01*
X647549Y277000D01*
X647579Y276970D01*
Y275840D01*
X647589Y275715D01*
X647629Y275590D01*
X647689Y275480D01*
X647769Y275380D01*
X647869Y275300D01*
X647979Y275240D01*
X648104Y275200D01*
X648229Y275190D01*
X648354Y275200D01*
X648479Y275240D01*
X648589Y275300D01*
X648689Y275380D01*
X648769Y275480D01*
X648829Y275590D01*
X648869Y275715D01*
X648879Y275840D01*
Y276970D01*
X648909Y277000D01*
X649009Y277140D01*
X649029Y277180D01*
X649044Y277215D01*
X649064Y277255D01*
X649079Y277295D01*
X649089Y277335D01*
X649104Y277380D01*
X649109Y277420D01*
X649119Y277460D01*
X649124Y277505D01*
Y277545D01*
X649129Y277590D01*
X649124Y277635D01*
Y277675D01*
X649119Y277720D01*
X649109Y277760D01*
X649104Y277800D01*
X649089Y277845D01*
X649079Y277885D01*
X649064Y277925D01*
X649044Y277965D01*
X649029Y278000D01*
X649009Y278040D01*
X648909Y278180D01*
X648879Y278210D01*
Y281640D01*
X648869Y281765D01*
X648829Y281890D01*
X648769Y282000D01*
X648689Y282100D01*
X648589Y282180D01*
X648479Y282240D01*
X648354Y282280D01*
X648229Y282290D01*
G37*
G36*
G01X652953D02*
X652828Y282280D01*
X652703Y282240D01*
X652593Y282180D01*
X652493Y282100D01*
X652413Y282000D01*
X652353Y281890D01*
X652313Y281765D01*
X652303Y281640D01*
Y278210D01*
X652273Y278180D01*
X652173Y278040D01*
X652153Y278000D01*
X652138Y277965D01*
X652118Y277925D01*
X652103Y277885D01*
X652093Y277845D01*
X652078Y277800D01*
X652073Y277760D01*
X652063Y277720D01*
X652058Y277675D01*
Y277635D01*
X652053Y277590D01*
X652058Y277545D01*
Y277505D01*
X652063Y277460D01*
X652073Y277420D01*
X652078Y277380D01*
X652093Y277335D01*
X652103Y277295D01*
X652118Y277255D01*
X652138Y277215D01*
X652153Y277180D01*
X652173Y277140D01*
X652273Y277000D01*
X652303Y276970D01*
Y275840D01*
X652313Y275715D01*
X652353Y275590D01*
X652413Y275480D01*
X652493Y275380D01*
X652593Y275300D01*
X652703Y275240D01*
X652828Y275200D01*
X652953Y275190D01*
X653078Y275200D01*
X653203Y275240D01*
X653313Y275300D01*
X653413Y275380D01*
X653493Y275480D01*
X653553Y275590D01*
X653593Y275715D01*
X653603Y275840D01*
Y276970D01*
X653633Y277000D01*
X653733Y277140D01*
X653753Y277180D01*
X653768Y277215D01*
X653788Y277255D01*
X653803Y277295D01*
X653813Y277335D01*
X653828Y277380D01*
X653833Y277420D01*
X653843Y277460D01*
X653848Y277505D01*
Y277545D01*
X653853Y277590D01*
X653848Y277635D01*
Y277675D01*
X653843Y277720D01*
X653833Y277760D01*
X653828Y277800D01*
X653813Y277845D01*
X653803Y277885D01*
X653788Y277925D01*
X653768Y277965D01*
X653753Y278000D01*
X653733Y278040D01*
X653633Y278180D01*
X653603Y278210D01*
Y281640D01*
X653593Y281765D01*
X653553Y281890D01*
X653493Y282000D01*
X653413Y282100D01*
X653313Y282180D01*
X653203Y282240D01*
X653078Y282280D01*
X652953Y282290D01*
G37*
G36*
G01X667126D02*
X667001Y282280D01*
X666876Y282240D01*
X666766Y282180D01*
X666666Y282100D01*
X666586Y282000D01*
X666526Y281890D01*
X666486Y281765D01*
X666476Y281640D01*
Y278210D01*
X666446Y278180D01*
X666346Y278040D01*
X666326Y278000D01*
X666311Y277965D01*
X666291Y277925D01*
X666276Y277885D01*
X666266Y277845D01*
X666251Y277800D01*
X666246Y277760D01*
X666236Y277720D01*
X666231Y277675D01*
Y277635D01*
X666226Y277590D01*
X666231Y277545D01*
Y277505D01*
X666236Y277460D01*
X666246Y277420D01*
X666251Y277380D01*
X666266Y277335D01*
X666276Y277295D01*
X666291Y277255D01*
X666311Y277215D01*
X666326Y277180D01*
X666346Y277140D01*
X666446Y277000D01*
X666476Y276970D01*
Y275840D01*
X666486Y275715D01*
X666526Y275590D01*
X666586Y275480D01*
X666666Y275380D01*
X666766Y275300D01*
X666876Y275240D01*
X667001Y275200D01*
X667126Y275190D01*
X667251Y275200D01*
X667376Y275240D01*
X667486Y275300D01*
X667586Y275380D01*
X667666Y275480D01*
X667726Y275590D01*
X667766Y275715D01*
X667776Y275840D01*
Y276970D01*
X667806Y277000D01*
X667906Y277140D01*
X667926Y277180D01*
X667941Y277215D01*
X667961Y277255D01*
X667976Y277295D01*
X667986Y277335D01*
X668001Y277380D01*
X668006Y277420D01*
X668016Y277460D01*
X668021Y277505D01*
Y277545D01*
X668026Y277590D01*
X668021Y277635D01*
Y277675D01*
X668016Y277720D01*
X668006Y277760D01*
X668001Y277800D01*
X667986Y277845D01*
X667976Y277885D01*
X667961Y277925D01*
X667941Y277965D01*
X667926Y278000D01*
X667906Y278040D01*
X667806Y278180D01*
X667776Y278210D01*
Y281640D01*
X667766Y281765D01*
X667726Y281890D01*
X667666Y282000D01*
X667586Y282100D01*
X667486Y282180D01*
X667376Y282240D01*
X667251Y282280D01*
X667126Y282290D01*
G37*
G36*
G01X671851D02*
X671726Y282280D01*
X671601Y282240D01*
X671491Y282180D01*
X671391Y282100D01*
X671311Y282000D01*
X671251Y281890D01*
X671211Y281765D01*
X671201Y281640D01*
Y278210D01*
X671171Y278180D01*
X671071Y278040D01*
X671051Y278000D01*
X671036Y277965D01*
X671016Y277925D01*
X671001Y277885D01*
X670991Y277845D01*
X670976Y277800D01*
X670971Y277760D01*
X670961Y277720D01*
X670956Y277675D01*
Y277635D01*
X670951Y277590D01*
X670956Y277545D01*
Y277505D01*
X670961Y277460D01*
X670971Y277420D01*
X670976Y277380D01*
X670991Y277335D01*
X671001Y277295D01*
X671016Y277255D01*
X671036Y277215D01*
X671051Y277180D01*
X671071Y277140D01*
X671171Y277000D01*
X671201Y276970D01*
Y275840D01*
X671211Y275715D01*
X671251Y275590D01*
X671311Y275480D01*
X671391Y275380D01*
X671491Y275300D01*
X671601Y275240D01*
X671726Y275200D01*
X671851Y275190D01*
X671976Y275200D01*
X672101Y275240D01*
X672211Y275300D01*
X672311Y275380D01*
X672391Y275480D01*
X672451Y275590D01*
X672491Y275715D01*
X672501Y275840D01*
Y276970D01*
X672531Y277000D01*
X672631Y277140D01*
X672651Y277180D01*
X672666Y277215D01*
X672686Y277255D01*
X672701Y277295D01*
X672711Y277335D01*
X672726Y277380D01*
X672731Y277420D01*
X672741Y277460D01*
X672746Y277505D01*
Y277545D01*
X672751Y277590D01*
X672746Y277635D01*
Y277675D01*
X672741Y277720D01*
X672731Y277760D01*
X672726Y277800D01*
X672711Y277845D01*
X672701Y277885D01*
X672686Y277925D01*
X672666Y277965D01*
X672651Y278000D01*
X672631Y278040D01*
X672531Y278180D01*
X672501Y278210D01*
Y281640D01*
X672491Y281765D01*
X672451Y281890D01*
X672391Y282000D01*
X672311Y282100D01*
X672211Y282180D01*
X672101Y282240D01*
X671976Y282280D01*
X671851Y282290D01*
G37*
G36*
G01X676575D02*
X676450Y282280D01*
X676325Y282240D01*
X676215Y282180D01*
X676115Y282100D01*
X676035Y282000D01*
X675975Y281890D01*
X675935Y281765D01*
X675925Y281640D01*
Y278210D01*
X675895Y278180D01*
X675795Y278040D01*
X675775Y278000D01*
X675760Y277965D01*
X675740Y277925D01*
X675725Y277885D01*
X675715Y277845D01*
X675700Y277800D01*
X675695Y277760D01*
X675685Y277720D01*
X675680Y277675D01*
Y277635D01*
X675675Y277590D01*
X675680Y277545D01*
Y277505D01*
X675685Y277460D01*
X675695Y277420D01*
X675700Y277380D01*
X675715Y277335D01*
X675725Y277295D01*
X675740Y277255D01*
X675760Y277215D01*
X675775Y277180D01*
X675795Y277140D01*
X675895Y277000D01*
X675925Y276970D01*
Y275840D01*
X675935Y275715D01*
X675975Y275590D01*
X676035Y275480D01*
X676115Y275380D01*
X676215Y275300D01*
X676325Y275240D01*
X676450Y275200D01*
X676575Y275190D01*
X676700Y275200D01*
X676825Y275240D01*
X676935Y275300D01*
X677035Y275380D01*
X677115Y275480D01*
X677175Y275590D01*
X677215Y275715D01*
X677225Y275840D01*
Y276970D01*
X677255Y277000D01*
X677355Y277140D01*
X677375Y277180D01*
X677390Y277215D01*
X677410Y277255D01*
X677425Y277295D01*
X677435Y277335D01*
X677450Y277380D01*
X677455Y277420D01*
X677465Y277460D01*
X677470Y277505D01*
Y277545D01*
X677475Y277590D01*
X677470Y277635D01*
Y277675D01*
X677465Y277720D01*
X677455Y277760D01*
X677450Y277800D01*
X677435Y277845D01*
X677425Y277885D01*
X677410Y277925D01*
X677390Y277965D01*
X677375Y278000D01*
X677355Y278040D01*
X677255Y278180D01*
X677225Y278210D01*
Y281640D01*
X677215Y281765D01*
X677175Y281890D01*
X677115Y282000D01*
X677035Y282100D01*
X676935Y282180D01*
X676825Y282240D01*
X676700Y282280D01*
X676575Y282290D01*
G37*
G36*
G01X681299D02*
X681174Y282280D01*
X681049Y282240D01*
X680939Y282180D01*
X680839Y282100D01*
X680759Y282000D01*
X680699Y281890D01*
X680659Y281765D01*
X680649Y281640D01*
Y278210D01*
X680619Y278180D01*
X680519Y278040D01*
X680499Y278000D01*
X680484Y277965D01*
X680464Y277925D01*
X680449Y277885D01*
X680439Y277845D01*
X680424Y277800D01*
X680419Y277760D01*
X680409Y277720D01*
X680404Y277675D01*
Y277635D01*
X680399Y277590D01*
X680404Y277545D01*
Y277505D01*
X680409Y277460D01*
X680419Y277420D01*
X680424Y277380D01*
X680439Y277335D01*
X680449Y277295D01*
X680464Y277255D01*
X680484Y277215D01*
X680499Y277180D01*
X680519Y277140D01*
X680619Y277000D01*
X680649Y276970D01*
Y275840D01*
X680659Y275715D01*
X680699Y275590D01*
X680759Y275480D01*
X680839Y275380D01*
X680939Y275300D01*
X681049Y275240D01*
X681174Y275200D01*
X681299Y275190D01*
X681424Y275200D01*
X681549Y275240D01*
X681659Y275300D01*
X681759Y275380D01*
X681839Y275480D01*
X681899Y275590D01*
X681939Y275715D01*
X681949Y275840D01*
Y276970D01*
X681979Y277000D01*
X682079Y277140D01*
X682099Y277180D01*
X682114Y277215D01*
X682134Y277255D01*
X682149Y277295D01*
X682159Y277335D01*
X682174Y277380D01*
X682179Y277420D01*
X682189Y277460D01*
X682194Y277505D01*
Y277545D01*
X682199Y277590D01*
X682194Y277635D01*
Y277675D01*
X682189Y277720D01*
X682179Y277760D01*
X682174Y277800D01*
X682159Y277845D01*
X682149Y277885D01*
X682134Y277925D01*
X682114Y277965D01*
X682099Y278000D01*
X682079Y278040D01*
X681979Y278180D01*
X681949Y278210D01*
Y281640D01*
X681939Y281765D01*
X681899Y281890D01*
X681839Y282000D01*
X681759Y282100D01*
X681659Y282180D01*
X681549Y282240D01*
X681424Y282280D01*
X681299Y282290D01*
G37*
G36*
G01X686024D02*
X685899Y282280D01*
X685774Y282240D01*
X685664Y282180D01*
X685564Y282100D01*
X685484Y282000D01*
X685424Y281890D01*
X685384Y281765D01*
X685374Y281640D01*
Y278210D01*
X685344Y278180D01*
X685244Y278040D01*
X685224Y278000D01*
X685209Y277965D01*
X685189Y277925D01*
X685174Y277885D01*
X685164Y277845D01*
X685149Y277800D01*
X685144Y277760D01*
X685134Y277720D01*
X685129Y277675D01*
Y277635D01*
X685124Y277590D01*
X685129Y277545D01*
Y277505D01*
X685134Y277460D01*
X685144Y277420D01*
X685149Y277380D01*
X685164Y277335D01*
X685174Y277295D01*
X685189Y277255D01*
X685209Y277215D01*
X685224Y277180D01*
X685244Y277140D01*
X685344Y277000D01*
X685374Y276970D01*
Y275840D01*
X685384Y275715D01*
X685424Y275590D01*
X685484Y275480D01*
X685564Y275380D01*
X685664Y275300D01*
X685774Y275240D01*
X685899Y275200D01*
X686024Y275190D01*
X686149Y275200D01*
X686274Y275240D01*
X686384Y275300D01*
X686484Y275380D01*
X686564Y275480D01*
X686624Y275590D01*
X686664Y275715D01*
X686674Y275840D01*
Y276970D01*
X686704Y277000D01*
X686804Y277140D01*
X686824Y277180D01*
X686839Y277215D01*
X686859Y277255D01*
X686874Y277295D01*
X686884Y277335D01*
X686899Y277380D01*
X686904Y277420D01*
X686914Y277460D01*
X686919Y277505D01*
Y277545D01*
X686924Y277590D01*
X686919Y277635D01*
Y277675D01*
X686914Y277720D01*
X686904Y277760D01*
X686899Y277800D01*
X686884Y277845D01*
X686874Y277885D01*
X686859Y277925D01*
X686839Y277965D01*
X686824Y278000D01*
X686804Y278040D01*
X686704Y278180D01*
X686674Y278210D01*
Y281640D01*
X686664Y281765D01*
X686624Y281890D01*
X686564Y282000D01*
X686484Y282100D01*
X686384Y282180D01*
X686274Y282240D01*
X686149Y282280D01*
X686024Y282290D01*
G37*
G36*
G01X690748D02*
X690623Y282280D01*
X690498Y282240D01*
X690388Y282180D01*
X690288Y282100D01*
X690208Y282000D01*
X690148Y281890D01*
X690108Y281765D01*
X690098Y281640D01*
Y278210D01*
X690068Y278180D01*
X689968Y278040D01*
X689948Y278000D01*
X689933Y277965D01*
X689913Y277925D01*
X689898Y277885D01*
X689888Y277845D01*
X689873Y277800D01*
X689868Y277760D01*
X689858Y277720D01*
X689853Y277675D01*
Y277635D01*
X689848Y277590D01*
X689853Y277545D01*
Y277505D01*
X689858Y277460D01*
X689868Y277420D01*
X689873Y277380D01*
X689888Y277335D01*
X689898Y277295D01*
X689913Y277255D01*
X689933Y277215D01*
X689948Y277180D01*
X689968Y277140D01*
X690068Y277000D01*
X690098Y276970D01*
Y275840D01*
X690108Y275715D01*
X690148Y275590D01*
X690208Y275480D01*
X690288Y275380D01*
X690388Y275300D01*
X690498Y275240D01*
X690623Y275200D01*
X690748Y275190D01*
X690873Y275200D01*
X690998Y275240D01*
X691108Y275300D01*
X691208Y275380D01*
X691288Y275480D01*
X691348Y275590D01*
X691388Y275715D01*
X691398Y275840D01*
Y276970D01*
X691428Y277000D01*
X691528Y277140D01*
X691548Y277180D01*
X691563Y277215D01*
X691583Y277255D01*
X691598Y277295D01*
X691608Y277335D01*
X691623Y277380D01*
X691628Y277420D01*
X691638Y277460D01*
X691643Y277505D01*
Y277545D01*
X691648Y277590D01*
X691643Y277635D01*
Y277675D01*
X691638Y277720D01*
X691628Y277760D01*
X691623Y277800D01*
X691608Y277845D01*
X691598Y277885D01*
X691583Y277925D01*
X691563Y277965D01*
X691548Y278000D01*
X691528Y278040D01*
X691428Y278180D01*
X691398Y278210D01*
Y281640D01*
X691388Y281765D01*
X691348Y281890D01*
X691288Y282000D01*
X691208Y282100D01*
X691108Y282180D01*
X690998Y282240D01*
X690873Y282280D01*
X690748Y282290D01*
G37*
G36*
G01X695473D02*
X695348Y282280D01*
X695223Y282240D01*
X695113Y282180D01*
X695013Y282100D01*
X694933Y282000D01*
X694873Y281890D01*
X694833Y281765D01*
X694823Y281640D01*
Y278210D01*
X694793Y278180D01*
X694693Y278040D01*
X694673Y278000D01*
X694658Y277965D01*
X694638Y277925D01*
X694623Y277885D01*
X694613Y277845D01*
X694598Y277800D01*
X694593Y277760D01*
X694583Y277720D01*
X694578Y277675D01*
Y277635D01*
X694573Y277590D01*
X694578Y277545D01*
Y277505D01*
X694583Y277460D01*
X694593Y277420D01*
X694598Y277380D01*
X694613Y277335D01*
X694623Y277295D01*
X694638Y277255D01*
X694658Y277215D01*
X694673Y277180D01*
X694693Y277140D01*
X694793Y277000D01*
X694823Y276970D01*
Y275840D01*
X694833Y275715D01*
X694873Y275590D01*
X694933Y275480D01*
X695013Y275380D01*
X695113Y275300D01*
X695223Y275240D01*
X695348Y275200D01*
X695473Y275190D01*
X695598Y275200D01*
X695723Y275240D01*
X695833Y275300D01*
X695933Y275380D01*
X696013Y275480D01*
X696073Y275590D01*
X696113Y275715D01*
X696123Y275840D01*
Y276970D01*
X696153Y277000D01*
X696253Y277140D01*
X696273Y277180D01*
X696288Y277215D01*
X696308Y277255D01*
X696323Y277295D01*
X696333Y277335D01*
X696348Y277380D01*
X696353Y277420D01*
X696363Y277460D01*
X696368Y277505D01*
Y277545D01*
X696373Y277590D01*
X696368Y277635D01*
Y277675D01*
X696363Y277720D01*
X696353Y277760D01*
X696348Y277800D01*
X696333Y277845D01*
X696323Y277885D01*
X696308Y277925D01*
X696288Y277965D01*
X696273Y278000D01*
X696253Y278040D01*
X696153Y278180D01*
X696123Y278210D01*
Y281640D01*
X696113Y281765D01*
X696073Y281890D01*
X696013Y282000D01*
X695933Y282100D01*
X695833Y282180D01*
X695723Y282240D01*
X695598Y282280D01*
X695473Y282290D01*
G37*
G36*
G01X700197D02*
X700072Y282280D01*
X699947Y282240D01*
X699837Y282180D01*
X699737Y282100D01*
X699657Y282000D01*
X699597Y281890D01*
X699557Y281765D01*
X699547Y281640D01*
Y278210D01*
X699517Y278180D01*
X699417Y278040D01*
X699397Y278000D01*
X699382Y277965D01*
X699362Y277925D01*
X699347Y277885D01*
X699337Y277845D01*
X699322Y277800D01*
X699317Y277760D01*
X699307Y277720D01*
X699302Y277675D01*
Y277635D01*
X699297Y277590D01*
X699302Y277545D01*
Y277505D01*
X699307Y277460D01*
X699317Y277420D01*
X699322Y277380D01*
X699337Y277335D01*
X699347Y277295D01*
X699362Y277255D01*
X699382Y277215D01*
X699397Y277180D01*
X699417Y277140D01*
X699517Y277000D01*
X699547Y276970D01*
Y275840D01*
X699557Y275715D01*
X699597Y275590D01*
X699657Y275480D01*
X699737Y275380D01*
X699837Y275300D01*
X699947Y275240D01*
X700072Y275200D01*
X700197Y275190D01*
X700322Y275200D01*
X700447Y275240D01*
X700557Y275300D01*
X700657Y275380D01*
X700737Y275480D01*
X700797Y275590D01*
X700837Y275715D01*
X700847Y275840D01*
Y276970D01*
X700877Y277000D01*
X700977Y277140D01*
X700997Y277180D01*
X701012Y277215D01*
X701032Y277255D01*
X701047Y277295D01*
X701057Y277335D01*
X701072Y277380D01*
X701077Y277420D01*
X701087Y277460D01*
X701092Y277505D01*
Y277545D01*
X701097Y277590D01*
X701092Y277635D01*
Y277675D01*
X701087Y277720D01*
X701077Y277760D01*
X701072Y277800D01*
X701057Y277845D01*
X701047Y277885D01*
X701032Y277925D01*
X701012Y277965D01*
X700997Y278000D01*
X700977Y278040D01*
X700877Y278180D01*
X700847Y278210D01*
Y281640D01*
X700837Y281765D01*
X700797Y281890D01*
X700737Y282000D01*
X700657Y282100D01*
X700557Y282180D01*
X700447Y282240D01*
X700322Y282280D01*
X700197Y282290D01*
G37*
G36*
G01X704922D02*
X704797Y282280D01*
X704672Y282240D01*
X704562Y282180D01*
X704462Y282100D01*
X704382Y282000D01*
X704322Y281890D01*
X704282Y281765D01*
X704272Y281640D01*
Y278210D01*
X704242Y278180D01*
X704142Y278040D01*
X704122Y278000D01*
X704107Y277965D01*
X704087Y277925D01*
X704072Y277885D01*
X704062Y277845D01*
X704047Y277800D01*
X704042Y277760D01*
X704032Y277720D01*
X704027Y277675D01*
Y277635D01*
X704022Y277590D01*
X704027Y277545D01*
Y277505D01*
X704032Y277460D01*
X704042Y277420D01*
X704047Y277380D01*
X704062Y277335D01*
X704072Y277295D01*
X704087Y277255D01*
X704107Y277215D01*
X704122Y277180D01*
X704142Y277140D01*
X704242Y277000D01*
X704272Y276970D01*
Y275840D01*
X704282Y275715D01*
X704322Y275590D01*
X704382Y275480D01*
X704462Y275380D01*
X704562Y275300D01*
X704672Y275240D01*
X704797Y275200D01*
X704922Y275190D01*
X705047Y275200D01*
X705172Y275240D01*
X705282Y275300D01*
X705382Y275380D01*
X705462Y275480D01*
X705522Y275590D01*
X705562Y275715D01*
X705572Y275840D01*
Y276970D01*
X705602Y277000D01*
X705702Y277140D01*
X705722Y277180D01*
X705737Y277215D01*
X705757Y277255D01*
X705772Y277295D01*
X705782Y277335D01*
X705797Y277380D01*
X705802Y277420D01*
X705812Y277460D01*
X705817Y277505D01*
Y277545D01*
X705822Y277590D01*
X705817Y277635D01*
Y277675D01*
X705812Y277720D01*
X705802Y277760D01*
X705797Y277800D01*
X705782Y277845D01*
X705772Y277885D01*
X705757Y277925D01*
X705737Y277965D01*
X705722Y278000D01*
X705702Y278040D01*
X705602Y278180D01*
X705572Y278210D01*
Y281640D01*
X705562Y281765D01*
X705522Y281890D01*
X705462Y282000D01*
X705382Y282100D01*
X705282Y282180D01*
X705172Y282240D01*
X705047Y282280D01*
X704922Y282290D01*
G37*
G36*
G01X709646D02*
X709521Y282280D01*
X709396Y282240D01*
X709286Y282180D01*
X709186Y282100D01*
X709106Y282000D01*
X709046Y281890D01*
X709006Y281765D01*
X708996Y281640D01*
Y278210D01*
X708966Y278180D01*
X708866Y278040D01*
X708846Y278000D01*
X708831Y277965D01*
X708811Y277925D01*
X708796Y277885D01*
X708786Y277845D01*
X708771Y277800D01*
X708766Y277760D01*
X708756Y277720D01*
X708751Y277675D01*
Y277635D01*
X708746Y277590D01*
X708751Y277545D01*
Y277505D01*
X708756Y277460D01*
X708766Y277420D01*
X708771Y277380D01*
X708786Y277335D01*
X708796Y277295D01*
X708811Y277255D01*
X708831Y277215D01*
X708846Y277180D01*
X708866Y277140D01*
X708966Y277000D01*
X708996Y276970D01*
Y275840D01*
X709006Y275715D01*
X709046Y275590D01*
X709106Y275480D01*
X709186Y275380D01*
X709286Y275300D01*
X709396Y275240D01*
X709521Y275200D01*
X709646Y275190D01*
X709771Y275200D01*
X709896Y275240D01*
X710006Y275300D01*
X710106Y275380D01*
X710186Y275480D01*
X710246Y275590D01*
X710286Y275715D01*
X710296Y275840D01*
Y276970D01*
X710326Y277000D01*
X710426Y277140D01*
X710446Y277180D01*
X710461Y277215D01*
X710481Y277255D01*
X710496Y277295D01*
X710506Y277335D01*
X710521Y277380D01*
X710526Y277420D01*
X710536Y277460D01*
X710541Y277505D01*
Y277545D01*
X710546Y277590D01*
X710541Y277635D01*
Y277675D01*
X710536Y277720D01*
X710526Y277760D01*
X710521Y277800D01*
X710506Y277845D01*
X710496Y277885D01*
X710481Y277925D01*
X710461Y277965D01*
X710446Y278000D01*
X710426Y278040D01*
X710326Y278180D01*
X710296Y278210D01*
Y281640D01*
X710286Y281765D01*
X710246Y281890D01*
X710186Y282000D01*
X710106Y282100D01*
X710006Y282180D01*
X709896Y282240D01*
X709771Y282280D01*
X709646Y282290D01*
G37*
G36*
G01X714370D02*
X714245Y282280D01*
X714120Y282240D01*
X714010Y282180D01*
X713910Y282100D01*
X713830Y282000D01*
X713770Y281890D01*
X713730Y281765D01*
X713720Y281640D01*
Y278210D01*
X713690Y278180D01*
X713590Y278040D01*
X713570Y278000D01*
X713555Y277965D01*
X713535Y277925D01*
X713520Y277885D01*
X713510Y277845D01*
X713495Y277800D01*
X713490Y277760D01*
X713480Y277720D01*
X713475Y277675D01*
Y277635D01*
X713470Y277590D01*
X713475Y277545D01*
Y277505D01*
X713480Y277460D01*
X713490Y277420D01*
X713495Y277380D01*
X713510Y277335D01*
X713520Y277295D01*
X713535Y277255D01*
X713555Y277215D01*
X713570Y277180D01*
X713590Y277140D01*
X713690Y277000D01*
X713720Y276970D01*
Y275840D01*
X713730Y275715D01*
X713770Y275590D01*
X713830Y275480D01*
X713910Y275380D01*
X714010Y275300D01*
X714120Y275240D01*
X714245Y275200D01*
X714370Y275190D01*
X714495Y275200D01*
X714620Y275240D01*
X714730Y275300D01*
X714830Y275380D01*
X714910Y275480D01*
X714970Y275590D01*
X715010Y275715D01*
X715020Y275840D01*
Y276970D01*
X715050Y277000D01*
X715150Y277140D01*
X715170Y277180D01*
X715185Y277215D01*
X715205Y277255D01*
X715220Y277295D01*
X715230Y277335D01*
X715245Y277380D01*
X715250Y277420D01*
X715260Y277460D01*
X715265Y277505D01*
Y277545D01*
X715270Y277590D01*
X715265Y277635D01*
Y277675D01*
X715260Y277720D01*
X715250Y277760D01*
X715245Y277800D01*
X715230Y277845D01*
X715220Y277885D01*
X715205Y277925D01*
X715185Y277965D01*
X715170Y278000D01*
X715150Y278040D01*
X715050Y278180D01*
X715020Y278210D01*
Y281640D01*
X715010Y281765D01*
X714970Y281890D01*
X714910Y282000D01*
X714830Y282100D01*
X714730Y282180D01*
X714620Y282240D01*
X714495Y282280D01*
X714370Y282290D01*
G37*
G36*
G01X719095D02*
X718970Y282280D01*
X718845Y282240D01*
X718735Y282180D01*
X718635Y282100D01*
X718555Y282000D01*
X718495Y281890D01*
X718455Y281765D01*
X718445Y281640D01*
Y278210D01*
X718415Y278180D01*
X718315Y278040D01*
X718295Y278000D01*
X718280Y277965D01*
X718260Y277925D01*
X718245Y277885D01*
X718235Y277845D01*
X718220Y277800D01*
X718215Y277760D01*
X718205Y277720D01*
X718200Y277675D01*
Y277635D01*
X718195Y277590D01*
X718200Y277545D01*
Y277505D01*
X718205Y277460D01*
X718215Y277420D01*
X718220Y277380D01*
X718235Y277335D01*
X718245Y277295D01*
X718260Y277255D01*
X718280Y277215D01*
X718295Y277180D01*
X718315Y277140D01*
X718415Y277000D01*
X718445Y276970D01*
Y275840D01*
X718455Y275715D01*
X718495Y275590D01*
X718555Y275480D01*
X718635Y275380D01*
X718735Y275300D01*
X718845Y275240D01*
X718970Y275200D01*
X719095Y275190D01*
X719220Y275200D01*
X719345Y275240D01*
X719455Y275300D01*
X719555Y275380D01*
X719635Y275480D01*
X719695Y275590D01*
X719735Y275715D01*
X719745Y275840D01*
Y276970D01*
X719775Y277000D01*
X719875Y277140D01*
X719895Y277180D01*
X719910Y277215D01*
X719930Y277255D01*
X719945Y277295D01*
X719955Y277335D01*
X719970Y277380D01*
X719975Y277420D01*
X719985Y277460D01*
X719990Y277505D01*
Y277545D01*
X719995Y277590D01*
X719990Y277635D01*
Y277675D01*
X719985Y277720D01*
X719975Y277760D01*
X719970Y277800D01*
X719955Y277845D01*
X719945Y277885D01*
X719930Y277925D01*
X719910Y277965D01*
X719895Y278000D01*
X719875Y278040D01*
X719775Y278180D01*
X719745Y278210D01*
Y281640D01*
X719735Y281765D01*
X719695Y281890D01*
X719635Y282000D01*
X719555Y282100D01*
X719455Y282180D01*
X719345Y282240D01*
X719220Y282280D01*
X719095Y282290D01*
G37*
G36*
G01X723819D02*
X723694Y282280D01*
X723569Y282240D01*
X723459Y282180D01*
X723359Y282100D01*
X723279Y282000D01*
X723219Y281890D01*
X723179Y281765D01*
X723169Y281640D01*
Y278210D01*
X723139Y278180D01*
X723039Y278040D01*
X723019Y278000D01*
X723004Y277965D01*
X722984Y277925D01*
X722969Y277885D01*
X722959Y277845D01*
X722944Y277800D01*
X722939Y277760D01*
X722929Y277720D01*
X722924Y277675D01*
Y277635D01*
X722919Y277590D01*
X722924Y277545D01*
Y277505D01*
X722929Y277460D01*
X722939Y277420D01*
X722944Y277380D01*
X722959Y277335D01*
X722969Y277295D01*
X722984Y277255D01*
X723004Y277215D01*
X723019Y277180D01*
X723039Y277140D01*
X723139Y277000D01*
X723169Y276970D01*
Y275840D01*
X723179Y275715D01*
X723219Y275590D01*
X723279Y275480D01*
X723359Y275380D01*
X723459Y275300D01*
X723569Y275240D01*
X723694Y275200D01*
X723819Y275190D01*
X723944Y275200D01*
X724069Y275240D01*
X724179Y275300D01*
X724279Y275380D01*
X724359Y275480D01*
X724419Y275590D01*
X724459Y275715D01*
X724469Y275840D01*
Y276970D01*
X724499Y277000D01*
X724599Y277140D01*
X724619Y277180D01*
X724634Y277215D01*
X724654Y277255D01*
X724669Y277295D01*
X724679Y277335D01*
X724694Y277380D01*
X724699Y277420D01*
X724709Y277460D01*
X724714Y277505D01*
Y277545D01*
X724719Y277590D01*
X724714Y277635D01*
Y277675D01*
X724709Y277720D01*
X724699Y277760D01*
X724694Y277800D01*
X724679Y277845D01*
X724669Y277885D01*
X724654Y277925D01*
X724634Y277965D01*
X724619Y278000D01*
X724599Y278040D01*
X724499Y278180D01*
X724469Y278210D01*
Y281640D01*
X724459Y281765D01*
X724419Y281890D01*
X724359Y282000D01*
X724279Y282100D01*
X724179Y282180D01*
X724069Y282240D01*
X723944Y282280D01*
X723819Y282290D01*
G37*
G36*
G01X728544D02*
X728419Y282280D01*
X728294Y282240D01*
X728184Y282180D01*
X728084Y282100D01*
X728004Y282000D01*
X727944Y281890D01*
X727904Y281765D01*
X727894Y281640D01*
Y278210D01*
X727864Y278180D01*
X727764Y278040D01*
X727744Y278000D01*
X727729Y277965D01*
X727709Y277925D01*
X727694Y277885D01*
X727684Y277845D01*
X727669Y277800D01*
X727664Y277760D01*
X727654Y277720D01*
X727649Y277675D01*
Y277635D01*
X727644Y277590D01*
X727649Y277545D01*
Y277505D01*
X727654Y277460D01*
X727664Y277420D01*
X727669Y277380D01*
X727684Y277335D01*
X727694Y277295D01*
X727709Y277255D01*
X727729Y277215D01*
X727744Y277180D01*
X727764Y277140D01*
X727864Y277000D01*
X727894Y276970D01*
Y275840D01*
X727904Y275715D01*
X727944Y275590D01*
X728004Y275480D01*
X728084Y275380D01*
X728184Y275300D01*
X728294Y275240D01*
X728419Y275200D01*
X728544Y275190D01*
X728669Y275200D01*
X728794Y275240D01*
X728904Y275300D01*
X729004Y275380D01*
X729084Y275480D01*
X729144Y275590D01*
X729184Y275715D01*
X729194Y275840D01*
Y276970D01*
X729224Y277000D01*
X729324Y277140D01*
X729344Y277180D01*
X729359Y277215D01*
X729379Y277255D01*
X729394Y277295D01*
X729404Y277335D01*
X729419Y277380D01*
X729424Y277420D01*
X729434Y277460D01*
X729439Y277505D01*
Y277545D01*
X729444Y277590D01*
X729439Y277635D01*
Y277675D01*
X729434Y277720D01*
X729424Y277760D01*
X729419Y277800D01*
X729404Y277845D01*
X729394Y277885D01*
X729379Y277925D01*
X729359Y277965D01*
X729344Y278000D01*
X729324Y278040D01*
X729224Y278180D01*
X729194Y278210D01*
Y281640D01*
X729184Y281765D01*
X729144Y281890D01*
X729084Y282000D01*
X729004Y282100D01*
X728904Y282180D01*
X728794Y282240D01*
X728669Y282280D01*
X728544Y282290D01*
G37*
G36*
G01X733268D02*
X733143Y282280D01*
X733018Y282240D01*
X732908Y282180D01*
X732808Y282100D01*
X732728Y282000D01*
X732668Y281890D01*
X732628Y281765D01*
X732618Y281640D01*
Y278210D01*
X732588Y278180D01*
X732488Y278040D01*
X732468Y278000D01*
X732453Y277965D01*
X732433Y277925D01*
X732418Y277885D01*
X732408Y277845D01*
X732393Y277800D01*
X732388Y277760D01*
X732378Y277720D01*
X732373Y277675D01*
Y277635D01*
X732368Y277590D01*
X732373Y277545D01*
Y277505D01*
X732378Y277460D01*
X732388Y277420D01*
X732393Y277380D01*
X732408Y277335D01*
X732418Y277295D01*
X732433Y277255D01*
X732453Y277215D01*
X732468Y277180D01*
X732488Y277140D01*
X732588Y277000D01*
X732618Y276970D01*
Y275840D01*
X732628Y275715D01*
X732668Y275590D01*
X732728Y275480D01*
X732808Y275380D01*
X732908Y275300D01*
X733018Y275240D01*
X733143Y275200D01*
X733268Y275190D01*
X733393Y275200D01*
X733518Y275240D01*
X733628Y275300D01*
X733728Y275380D01*
X733808Y275480D01*
X733868Y275590D01*
X733908Y275715D01*
X733918Y275840D01*
Y276970D01*
X733948Y277000D01*
X734048Y277140D01*
X734068Y277180D01*
X734083Y277215D01*
X734103Y277255D01*
X734118Y277295D01*
X734128Y277335D01*
X734143Y277380D01*
X734148Y277420D01*
X734158Y277460D01*
X734163Y277505D01*
Y277545D01*
X734168Y277590D01*
X734163Y277635D01*
Y277675D01*
X734158Y277720D01*
X734148Y277760D01*
X734143Y277800D01*
X734128Y277845D01*
X734118Y277885D01*
X734103Y277925D01*
X734083Y277965D01*
X734068Y278000D01*
X734048Y278040D01*
X733948Y278180D01*
X733918Y278210D01*
Y281640D01*
X733908Y281765D01*
X733868Y281890D01*
X733808Y282000D01*
X733728Y282100D01*
X733628Y282180D01*
X733518Y282240D01*
X733393Y282280D01*
X733268Y282290D01*
G37*
G36*
G01X737992D02*
X737867Y282280D01*
X737742Y282240D01*
X737632Y282180D01*
X737532Y282100D01*
X737452Y282000D01*
X737392Y281890D01*
X737352Y281765D01*
X737342Y281640D01*
Y278210D01*
X737312Y278180D01*
X737212Y278040D01*
X737192Y278000D01*
X737177Y277965D01*
X737157Y277925D01*
X737142Y277885D01*
X737132Y277845D01*
X737117Y277800D01*
X737112Y277760D01*
X737102Y277720D01*
X737097Y277675D01*
Y277635D01*
X737092Y277590D01*
X737097Y277545D01*
Y277505D01*
X737102Y277460D01*
X737112Y277420D01*
X737117Y277380D01*
X737132Y277335D01*
X737142Y277295D01*
X737157Y277255D01*
X737177Y277215D01*
X737192Y277180D01*
X737212Y277140D01*
X737312Y277000D01*
X737342Y276970D01*
Y275840D01*
X737352Y275715D01*
X737392Y275590D01*
X737452Y275480D01*
X737532Y275380D01*
X737632Y275300D01*
X737742Y275240D01*
X737867Y275200D01*
X737992Y275190D01*
X738117Y275200D01*
X738242Y275240D01*
X738352Y275300D01*
X738452Y275380D01*
X738532Y275480D01*
X738592Y275590D01*
X738632Y275715D01*
X738642Y275840D01*
Y276970D01*
X738672Y277000D01*
X738772Y277140D01*
X738792Y277180D01*
X738807Y277215D01*
X738827Y277255D01*
X738842Y277295D01*
X738852Y277335D01*
X738867Y277380D01*
X738872Y277420D01*
X738882Y277460D01*
X738887Y277505D01*
Y277545D01*
X738892Y277590D01*
X738887Y277635D01*
Y277675D01*
X738882Y277720D01*
X738872Y277760D01*
X738867Y277800D01*
X738852Y277845D01*
X738842Y277885D01*
X738827Y277925D01*
X738807Y277965D01*
X738792Y278000D01*
X738772Y278040D01*
X738672Y278180D01*
X738642Y278210D01*
Y281640D01*
X738632Y281765D01*
X738592Y281890D01*
X738532Y282000D01*
X738452Y282100D01*
X738352Y282180D01*
X738242Y282240D01*
X738117Y282280D01*
X737992Y282290D01*
G37*
G36*
G01X742717D02*
X742592Y282280D01*
X742467Y282240D01*
X742357Y282180D01*
X742257Y282100D01*
X742177Y282000D01*
X742117Y281890D01*
X742077Y281765D01*
X742067Y281640D01*
Y278210D01*
X742037Y278180D01*
X741937Y278040D01*
X741917Y278000D01*
X741902Y277965D01*
X741882Y277925D01*
X741867Y277885D01*
X741857Y277845D01*
X741842Y277800D01*
X741837Y277760D01*
X741827Y277720D01*
X741822Y277675D01*
Y277635D01*
X741817Y277590D01*
X741822Y277545D01*
Y277505D01*
X741827Y277460D01*
X741837Y277420D01*
X741842Y277380D01*
X741857Y277335D01*
X741867Y277295D01*
X741882Y277255D01*
X741902Y277215D01*
X741917Y277180D01*
X741937Y277140D01*
X742037Y277000D01*
X742067Y276970D01*
Y275840D01*
X742077Y275715D01*
X742117Y275590D01*
X742177Y275480D01*
X742257Y275380D01*
X742357Y275300D01*
X742467Y275240D01*
X742592Y275200D01*
X742717Y275190D01*
X742842Y275200D01*
X742967Y275240D01*
X743077Y275300D01*
X743177Y275380D01*
X743257Y275480D01*
X743317Y275590D01*
X743357Y275715D01*
X743367Y275840D01*
Y276970D01*
X743397Y277000D01*
X743497Y277140D01*
X743517Y277180D01*
X743532Y277215D01*
X743552Y277255D01*
X743567Y277295D01*
X743577Y277335D01*
X743592Y277380D01*
X743597Y277420D01*
X743607Y277460D01*
X743612Y277505D01*
Y277545D01*
X743617Y277590D01*
X743612Y277635D01*
Y277675D01*
X743607Y277720D01*
X743597Y277760D01*
X743592Y277800D01*
X743577Y277845D01*
X743567Y277885D01*
X743552Y277925D01*
X743532Y277965D01*
X743517Y278000D01*
X743497Y278040D01*
X743397Y278180D01*
X743367Y278210D01*
Y281640D01*
X743357Y281765D01*
X743317Y281890D01*
X743257Y282000D01*
X743177Y282100D01*
X743077Y282180D01*
X742967Y282240D01*
X742842Y282280D01*
X742717Y282290D01*
G37*
G36*
G01X747441D02*
X747316Y282280D01*
X747191Y282240D01*
X747081Y282180D01*
X746981Y282100D01*
X746901Y282000D01*
X746841Y281890D01*
X746801Y281765D01*
X746791Y281640D01*
Y278210D01*
X746761Y278180D01*
X746661Y278040D01*
X746641Y278000D01*
X746626Y277965D01*
X746606Y277925D01*
X746591Y277885D01*
X746581Y277845D01*
X746566Y277800D01*
X746561Y277760D01*
X746551Y277720D01*
X746546Y277675D01*
Y277635D01*
X746541Y277590D01*
X746546Y277545D01*
Y277505D01*
X746551Y277460D01*
X746561Y277420D01*
X746566Y277380D01*
X746581Y277335D01*
X746591Y277295D01*
X746606Y277255D01*
X746626Y277215D01*
X746641Y277180D01*
X746661Y277140D01*
X746761Y277000D01*
X746791Y276970D01*
Y275840D01*
X746801Y275715D01*
X746841Y275590D01*
X746901Y275480D01*
X746981Y275380D01*
X747081Y275300D01*
X747191Y275240D01*
X747316Y275200D01*
X747441Y275190D01*
X747566Y275200D01*
X747691Y275240D01*
X747801Y275300D01*
X747901Y275380D01*
X747981Y275480D01*
X748041Y275590D01*
X748081Y275715D01*
X748091Y275840D01*
Y276970D01*
X748121Y277000D01*
X748221Y277140D01*
X748241Y277180D01*
X748256Y277215D01*
X748276Y277255D01*
X748291Y277295D01*
X748301Y277335D01*
X748316Y277380D01*
X748321Y277420D01*
X748331Y277460D01*
X748336Y277505D01*
Y277545D01*
X748341Y277590D01*
X748336Y277635D01*
Y277675D01*
X748331Y277720D01*
X748321Y277760D01*
X748316Y277800D01*
X748301Y277845D01*
X748291Y277885D01*
X748276Y277925D01*
X748256Y277965D01*
X748241Y278000D01*
X748221Y278040D01*
X748121Y278180D01*
X748091Y278210D01*
Y281640D01*
X748081Y281765D01*
X748041Y281890D01*
X747981Y282000D01*
X747901Y282100D01*
X747801Y282180D01*
X747691Y282240D01*
X747566Y282280D01*
X747441Y282290D01*
G37*
G54D78*
X517000Y102100D03*
X513000D03*
X515000Y96900D03*
X770700Y149600D03*
X766700D03*
X768700Y144400D03*
G54D69*
X500787Y70042D03*
X494882Y215354D03*
X759055Y70042D03*
X753150Y215354D03*
G54D79*
X762000Y163331D03*
Y154669D03*
M02*
